(lib_symbols
	(symbol "XC7K410T-2FFG900I_1"
			(exclude_from_sim no)
			(in_bom yes)
			(on_board yes)
			(property "Reference" "U"
				(at 82.55 -2.54 0)
				(effects
					(font
						(size 1.27 1.27)
						(thickness 0.15)
					)
					(justify left bottom)
				)
			)
			(property "Value" "XC7K410T-2FFG900I"
				(at 82.55 -7.62 0)
				(effects
					(font
						(size 1.27 1.27)
						(thickness 0.15)
					)
					(justify left bottom)
					(hide yes)
				)
			)
			(property "Footprint" "antmicro-footprints:BGA-900_31x31mm_Layout30x30_P1x1mm_FFG900"
				(at 82.55 -10.16 0)
				(effects
					(font
						(size 1.27 1.27)
						(thickness 0.15)
					)
					(justify left bottom)
					(hide yes)
				)
			)
			(property "Datasheet" "https://eu.mouser.com/datasheet/2/903/ds180_7Series_Overview-1591537.pdf"
				(at 82.55 -12.7 0)
				(effects
					(font
						(size 1.27 1.27)
						(thickness 0.15)
					)
					(justify left bottom)
					(hide yes)
				)
			)
			(property "Description" "FPGA, Kintex-7, MMCM, PLL, 350 I/O's, 710 MHz, 406720 Cells, 970 mV to 1.03 V, FCBGA-900"
				(at 0 0 0)
				(effects
					(font
						(size 1.27 1.27)
					)
					(hide yes)
				)
			)
			(property "MPN" "XC7K410T-2FFG900I"
				(at 82.55 -5.08 0)
				(effects
					(font
						(size 1.27 1.27)
						(thickness 0.15)
					)
					(justify left bottom)
				)
			)
			(property "Manufacturer" "AMD-Xilinx"
				(at 82.55 -15.24 0)
				(effects
					(font
						(size 1.27 1.27)
						(thickness 0.15)
					)
					(justify left bottom)
					(hide yes)
				)
			)
			(property "Author" "Antmicro"
				(at 82.55 -17.78 0)
				(effects
					(font
						(size 1.27 1.27)
						(thickness 0.15)
					)
					(justify left bottom)
					(hide yes)
				)
			)
			(property "License" "Apache-2.0"
				(at 82.55 -20.32 0)
				(effects
					(font
						(size 1.27 1.27)
						(thickness 0.15)
					)
					(justify left bottom)
					(hide yes)
				)
			)
			(property "ki_locked" ""
				(at 0 0 0)
				(effects
					(font
						(size 1.27 1.27)
					)
				)
			)
			(property "ki_keywords" "SMT, MICROCONTROLLER, IC, FPGA"
				(at 0 0 0)
				(effects
					(font
						(size 1.27 1.27)
					)
					(hide yes)
				)
			)
			(symbol "XC7K410T-2FFG900I_1_1_1"
				(rectangle
					(start 5.08 5.08)
					(end 50.8 -130.81)
					(stroke
						(width 0.254)
						(type default)
					)
					(fill
						(type background)
					)
				)
				(text "BANK 12"
					(at 15.24 2.54 0)
					(effects
						(font
							(size 1.27 1.27)
							(thickness 0.15)
						)
						(justify left bottom)
					)
				)
				(text "BANK 13"
					(at 31.75 2.54 0)
					(effects
						(font
							(size 1.27 1.27)
							(thickness 0.15)
						)
						(justify left bottom)
					)
				)
				(pin bidirectional line
					(at 0 0 0)
					(length 5.08)
					(name "VCCO_12"
						(effects
							(font
								(size 1.27 1.27)
							)
						)
					)
					(number "AC23"
						(effects
							(font
								(size 1.27 1.27)
							)
						)
					)
				)
				(pin passive line
					(at 0 0 0)
					(length 5.08)
					(hide yes)
					(name "VCCO_12"
						(effects
							(font
								(size 1.27 1.27)
							)
						)
					)
					(number "AD20"
						(effects
							(font
								(size 1.27 1.27)
							)
						)
					)
				)
				(pin passive line
					(at 0 0 0)
					(length 5.08)
					(hide yes)
					(name "VCCO_12"
						(effects
							(font
								(size 1.27 1.27)
							)
						)
					)
					(number "AF24"
						(effects
							(font
								(size 1.27 1.27)
							)
						)
					)
				)
				(pin passive line
					(at 0 0 0)
					(length 5.08)
					(hide yes)
					(name "VCCO_12"
						(effects
							(font
								(size 1.27 1.27)
							)
						)
					)
					(number "AG21"
						(effects
							(font
								(size 1.27 1.27)
							)
						)
					)
				)
				(pin passive line
					(at 0 0 0)
					(length 5.08)
					(hide yes)
					(name "VCCO_12"
						(effects
							(font
								(size 1.27 1.27)
							)
						)
					)
					(number "AK22"
						(effects
							(font
								(size 1.27 1.27)
							)
						)
					)
				)
				(pin passive line
					(at 0 0 0)
					(length 5.08)
					(hide yes)
					(name "VCCO_12"
						(effects
							(font
								(size 1.27 1.27)
							)
						)
					)
					(number "Y22"
						(effects
							(font
								(size 1.27 1.27)
							)
						)
					)
				)
				(pin bidirectional line
					(at 0 -3.81 0)
					(length 5.08)
					(name "IO_0_12"
						(effects
							(font
								(size 1.27 1.27)
							)
						)
					)
					(number "Y20"
						(effects
							(font
								(size 1.27 1.27)
							)
						)
					)
				)
				(pin bidirectional line
					(at 0 -6.35 0)
					(length 5.08)
					(name "IO_L1P_T0_12"
						(effects
							(font
								(size 1.27 1.27)
							)
						)
					)
					(number "Y23"
						(effects
							(font
								(size 1.27 1.27)
							)
						)
					)
				)
				(pin bidirectional line
					(at 0 -8.89 0)
					(length 5.08)
					(name "IO_L1N_T0_12"
						(effects
							(font
								(size 1.27 1.27)
							)
						)
					)
					(number "Y24"
						(effects
							(font
								(size 1.27 1.27)
							)
						)
					)
				)
				(pin bidirectional line
					(at 0 -11.43 0)
					(length 5.08)
					(name "IO_L2P_T0_12"
						(effects
							(font
								(size 1.27 1.27)
							)
						)
					)
					(number "Y21"
						(effects
							(font
								(size 1.27 1.27)
							)
						)
					)
				)
				(pin bidirectional line
					(at 0 -13.97 0)
					(length 5.08)
					(name "IO_L2N_T0_12"
						(effects
							(font
								(size 1.27 1.27)
							)
						)
					)
					(number "AA21"
						(effects
							(font
								(size 1.27 1.27)
							)
						)
					)
				)
				(pin bidirectional line
					(at 0 -16.51 0)
					(length 5.08)
					(name "IO_L3P_T0_DQS_12"
						(effects
							(font
								(size 1.27 1.27)
							)
						)
					)
					(number "AB22"
						(effects
							(font
								(size 1.27 1.27)
							)
						)
					)
				)
				(pin bidirectional line
					(at 0 -19.05 0)
					(length 5.08)
					(name "IO_L3N_T0_DQS_12"
						(effects
							(font
								(size 1.27 1.27)
							)
						)
					)
					(number "AB23"
						(effects
							(font
								(size 1.27 1.27)
							)
						)
					)
				)
				(pin bidirectional line
					(at 0 -21.59 0)
					(length 5.08)
					(name "IO_L4P_T0_12"
						(effects
							(font
								(size 1.27 1.27)
							)
						)
					)
					(number "AA22"
						(effects
							(font
								(size 1.27 1.27)
							)
						)
					)
				)
				(pin bidirectional line
					(at 0 -24.13 0)
					(length 5.08)
					(name "IO_L4N_T0_12"
						(effects
							(font
								(size 1.27 1.27)
							)
						)
					)
					(number "AA23"
						(effects
							(font
								(size 1.27 1.27)
							)
						)
					)
				)
				(pin bidirectional line
					(at 0 -26.67 0)
					(length 5.08)
					(name "IO_L5P_T0_12"
						(effects
							(font
								(size 1.27 1.27)
							)
						)
					)
					(number "AC20"
						(effects
							(font
								(size 1.27 1.27)
							)
						)
					)
				)
				(pin bidirectional line
					(at 0 -29.21 0)
					(length 5.08)
					(name "IO_L5N_T0_12"
						(effects
							(font
								(size 1.27 1.27)
							)
						)
					)
					(number "AC21"
						(effects
							(font
								(size 1.27 1.27)
							)
						)
					)
				)
				(pin bidirectional line
					(at 0 -31.75 0)
					(length 5.08)
					(name "IO_L6P_T0_12"
						(effects
							(font
								(size 1.27 1.27)
							)
						)
					)
					(number "AA20"
						(effects
							(font
								(size 1.27 1.27)
							)
						)
					)
				)
				(pin bidirectional line
					(at 0 -34.29 0)
					(length 5.08)
					(name "IO_L6N_T0_VREF_12"
						(effects
							(font
								(size 1.27 1.27)
							)
						)
					)
					(number "AB20"
						(effects
							(font
								(size 1.27 1.27)
							)
						)
					)
				)
				(pin bidirectional line
					(at 0 -36.83 0)
					(length 5.08)
					(name "IO_L7P_T1_12"
						(effects
							(font
								(size 1.27 1.27)
							)
						)
					)
					(number "AB24"
						(effects
							(font
								(size 1.27 1.27)
							)
						)
					)
				)
				(pin bidirectional line
					(at 0 -39.37 0)
					(length 5.08)
					(name "IO_L7N_T1_12"
						(effects
							(font
								(size 1.27 1.27)
							)
						)
					)
					(number "AC25"
						(effects
							(font
								(size 1.27 1.27)
							)
						)
					)
				)
				(pin bidirectional line
					(at 0 -41.91 0)
					(length 5.08)
					(name "IO_L8P_T1_12"
						(effects
							(font
								(size 1.27 1.27)
							)
						)
					)
					(number "AC22"
						(effects
							(font
								(size 1.27 1.27)
							)
						)
					)
				)
				(pin bidirectional line
					(at 0 -44.45 0)
					(length 5.08)
					(name "IO_L8N_T1_12"
						(effects
							(font
								(size 1.27 1.27)
							)
						)
					)
					(number "AD22"
						(effects
							(font
								(size 1.27 1.27)
							)
						)
					)
				)
				(pin bidirectional line
					(at 0 -46.99 0)
					(length 5.08)
					(name "IO_L9P_T1_DQS_12"
						(effects
							(font
								(size 1.27 1.27)
							)
						)
					)
					(number "AC24"
						(effects
							(font
								(size 1.27 1.27)
							)
						)
					)
				)
				(pin bidirectional line
					(at 0 -49.53 0)
					(length 5.08)
					(name "IO_L9N_T1_DQS_12"
						(effects
							(font
								(size 1.27 1.27)
							)
						)
					)
					(number "AD24"
						(effects
							(font
								(size 1.27 1.27)
							)
						)
					)
				)
				(pin bidirectional line
					(at 0 -52.07 0)
					(length 5.08)
					(name "IO_L10P_T1_12"
						(effects
							(font
								(size 1.27 1.27)
							)
						)
					)
					(number "AD21"
						(effects
							(font
								(size 1.27 1.27)
							)
						)
					)
				)
				(pin bidirectional line
					(at 0 -54.61 0)
					(length 5.08)
					(name "IO_L10N_T1_12"
						(effects
							(font
								(size 1.27 1.27)
							)
						)
					)
					(number "AE21"
						(effects
							(font
								(size 1.27 1.27)
							)
						)
					)
				)
				(pin bidirectional line
					(at 0 -57.15 0)
					(length 5.08)
					(name "IO_L11P_T1_SRCC_12"
						(effects
							(font
								(size 1.27 1.27)
							)
						)
					)
					(number "AE23"
						(effects
							(font
								(size 1.27 1.27)
							)
						)
					)
				)
				(pin bidirectional line
					(at 0 -59.69 0)
					(length 5.08)
					(name "IO_L11N_T1_SRCC_12"
						(effects
							(font
								(size 1.27 1.27)
							)
						)
					)
					(number "AF23"
						(effects
							(font
								(size 1.27 1.27)
							)
						)
					)
				)
				(pin bidirectional line
					(at 0 -62.23 0)
					(length 5.08)
					(name "IO_L12P_T1_MRCC_12"
						(effects
							(font
								(size 1.27 1.27)
							)
						)
					)
					(number "AD23"
						(effects
							(font
								(size 1.27 1.27)
							)
						)
					)
				)
				(pin bidirectional line
					(at 0 -64.77 0)
					(length 5.08)
					(name "IO_L12N_T1_MRCC_12"
						(effects
							(font
								(size 1.27 1.27)
							)
						)
					)
					(number "AE24"
						(effects
							(font
								(size 1.27 1.27)
							)
						)
					)
				)
				(pin bidirectional line
					(at 0 -67.31 0)
					(length 5.08)
					(name "IO_L13P_T2_MRCC_12"
						(effects
							(font
								(size 1.27 1.27)
							)
						)
					)
					(number "AF22"
						(effects
							(font
								(size 1.27 1.27)
							)
						)
					)
				)
				(pin bidirectional line
					(at 0 -69.85 0)
					(length 5.08)
					(name "IO_L13N_T2_MRCC_12"
						(effects
							(font
								(size 1.27 1.27)
							)
						)
					)
					(number "AG23"
						(effects
							(font
								(size 1.27 1.27)
							)
						)
					)
				)
				(pin bidirectional line
					(at 0 -72.39 0)
					(length 5.08)
					(name "IO_L14P_T2_SRCC_12"
						(effects
							(font
								(size 1.27 1.27)
							)
						)
					)
					(number "AG24"
						(effects
							(font
								(size 1.27 1.27)
							)
						)
					)
				)
				(pin bidirectional line
					(at 0 -74.93 0)
					(length 5.08)
					(name "IO_L14N_T2_SRCC_12"
						(effects
							(font
								(size 1.27 1.27)
							)
						)
					)
					(number "AH24"
						(effects
							(font
								(size 1.27 1.27)
							)
						)
					)
				)
				(pin bidirectional line
					(at 0 -77.47 0)
					(length 5.08)
					(name "IO_L15P_T2_DQS_12"
						(effects
							(font
								(size 1.27 1.27)
							)
						)
					)
					(number "AJ24"
						(effects
							(font
								(size 1.27 1.27)
							)
						)
					)
				)
				(pin bidirectional line
					(at 0 -80.01 0)
					(length 5.08)
					(name "IO_L15N_T2_DQS_12"
						(effects
							(font
								(size 1.27 1.27)
							)
						)
					)
					(number "AK25"
						(effects
							(font
								(size 1.27 1.27)
							)
						)
					)
				)
				(pin bidirectional line
					(at 0 -82.55 0)
					(length 5.08)
					(name "IO_L16P_T2_12"
						(effects
							(font
								(size 1.27 1.27)
							)
						)
					)
					(number "AE25"
						(effects
							(font
								(size 1.27 1.27)
							)
						)
					)
				)
				(pin bidirectional line
					(at 0 -85.09 0)
					(length 5.08)
					(name "IO_L16N_T2_12"
						(effects
							(font
								(size 1.27 1.27)
							)
						)
					)
					(number "AF25"
						(effects
							(font
								(size 1.27 1.27)
							)
						)
					)
				)
				(pin bidirectional line
					(at 0 -87.63 0)
					(length 5.08)
					(name "IO_L17P_T2_12"
						(effects
							(font
								(size 1.27 1.27)
							)
						)
					)
					(number "AK23"
						(effects
							(font
								(size 1.27 1.27)
							)
						)
					)
				)
				(pin bidirectional line
					(at 0 -90.17 0)
					(length 5.08)
					(name "IO_L17N_T2_12"
						(effects
							(font
								(size 1.27 1.27)
							)
						)
					)
					(number "AK24"
						(effects
							(font
								(size 1.27 1.27)
							)
						)
					)
				)
				(pin bidirectional line
					(at 0 -92.71 0)
					(length 5.08)
					(name "IO_L18P_T2_12"
						(effects
							(font
								(size 1.27 1.27)
							)
						)
					)
					(number "AG25"
						(effects
							(font
								(size 1.27 1.27)
							)
						)
					)
				)
				(pin bidirectional line
					(at 0 -95.25 0)
					(length 5.08)
					(name "IO_L18N_T2_12"
						(effects
							(font
								(size 1.27 1.27)
							)
						)
					)
					(number "AH25"
						(effects
							(font
								(size 1.27 1.27)
							)
						)
					)
				)
				(pin bidirectional line
					(at 0 -97.79 0)
					(length 5.08)
					(name "IO_L19P_T3_12"
						(effects
							(font
								(size 1.27 1.27)
							)
						)
					)
					(number "AF20"
						(effects
							(font
								(size 1.27 1.27)
							)
						)
					)
				)
				(pin bidirectional line
					(at 0 -100.33 0)
					(length 5.08)
					(name "IO_L19N_T3_VREF_12"
						(effects
							(font
								(size 1.27 1.27)
							)
						)
					)
					(number "AF21"
						(effects
							(font
								(size 1.27 1.27)
							)
						)
					)
				)
				(pin bidirectional line
					(at 0 -102.87 0)
					(length 5.08)
					(name "IO_L20P_T3_12"
						(effects
							(font
								(size 1.27 1.27)
							)
						)
					)
					(number "AG22"
						(effects
							(font
								(size 1.27 1.27)
							)
						)
					)
				)
				(pin bidirectional line
					(at 0 -105.41 0)
					(length 5.08)
					(name "IO_L20N_T3_12"
						(effects
							(font
								(size 1.27 1.27)
							)
						)
					)
					(number "AH22"
						(effects
							(font
								(size 1.27 1.27)
							)
						)
					)
				)
				(pin bidirectional line
					(at 0 -107.95 0)
					(length 5.08)
					(name "IO_L21P_T3_DQS_12"
						(effects
							(font
								(size 1.27 1.27)
							)
						)
					)
					(number "AJ22"
						(effects
							(font
								(size 1.27 1.27)
							)
						)
					)
				)
				(pin bidirectional line
					(at 0 -110.49 0)
					(length 5.08)
					(name "IO_L21N_T3_DQS_12"
						(effects
							(font
								(size 1.27 1.27)
							)
						)
					)
					(number "AJ23"
						(effects
							(font
								(size 1.27 1.27)
							)
						)
					)
				)
				(pin bidirectional line
					(at 0 -113.03 0)
					(length 5.08)
					(name "IO_L22P_T3_12"
						(effects
							(font
								(size 1.27 1.27)
							)
						)
					)
					(number "AG20"
						(effects
							(font
								(size 1.27 1.27)
							)
						)
					)
				)
				(pin bidirectional line
					(at 0 -115.57 0)
					(length 5.08)
					(name "IO_L22N_T3_12"
						(effects
							(font
								(size 1.27 1.27)
							)
						)
					)
					(number "AH20"
						(effects
							(font
								(size 1.27 1.27)
							)
						)
					)
				)
				(pin bidirectional line
					(at 0 -118.11 0)
					(length 5.08)
					(name "IO_L23P_T3_12"
						(effects
							(font
								(size 1.27 1.27)
							)
						)
					)
					(number "AH21"
						(effects
							(font
								(size 1.27 1.27)
							)
						)
					)
				)
				(pin bidirectional line
					(at 0 -120.65 0)
					(length 5.08)
					(name "IO_L23N_T3_12"
						(effects
							(font
								(size 1.27 1.27)
							)
						)
					)
					(number "AJ21"
						(effects
							(font
								(size 1.27 1.27)
							)
						)
					)
				)
				(pin bidirectional line
					(at 0 -123.19 0)
					(length 5.08)
					(name "IO_L24P_T3_12"
						(effects
							(font
								(size 1.27 1.27)
							)
						)
					)
					(number "AK20"
						(effects
							(font
								(size 1.27 1.27)
							)
						)
					)
				)
				(pin bidirectional line
					(at 0 -125.73 0)
					(length 5.08)
					(name "IO_L24N_T3_12"
						(effects
							(font
								(size 1.27 1.27)
							)
						)
					)
					(number "AK21"
						(effects
							(font
								(size 1.27 1.27)
							)
						)
					)
				)
				(pin bidirectional line
					(at 0 -128.27 0)
					(length 5.08)
					(name "IO_25_12"
						(effects
							(font
								(size 1.27 1.27)
							)
						)
					)
					(number "AE20"
						(effects
							(font
								(size 1.27 1.27)
							)
						)
					)
				)
				(pin bidirectional line
					(at 55.88 0 180)
					(length 5.08)
					(name "VCCO_13"
						(effects
							(font
								(size 1.27 1.27)
							)
						)
					)
					(number "AA29"
						(effects
							(font
								(size 1.27 1.27)
							)
						)
					)
				)
				(pin passive line
					(at 55.88 0 180)
					(length 5.08)
					(hide yes)
					(name "VCCO_13"
						(effects
							(font
								(size 1.27 1.27)
							)
						)
					)
					(number "AB26"
						(effects
							(font
								(size 1.27 1.27)
							)
						)
					)
				)
				(pin passive line
					(at 55.88 0 180)
					(length 5.08)
					(hide yes)
					(name "VCCO_13"
						(effects
							(font
								(size 1.27 1.27)
							)
						)
					)
					(number "AD30"
						(effects
							(font
								(size 1.27 1.27)
							)
						)
					)
				)
				(pin passive line
					(at 55.88 0 180)
					(length 5.08)
					(hide yes)
					(name "VCCO_13"
						(effects
							(font
								(size 1.27 1.27)
							)
						)
					)
					(number "AE27"
						(effects
							(font
								(size 1.27 1.27)
							)
						)
					)
				)
				(pin passive line
					(at 55.88 0 180)
					(length 5.08)
					(hide yes)
					(name "VCCO_13"
						(effects
							(font
								(size 1.27 1.27)
							)
						)
					)
					(number "AH28"
						(effects
							(font
								(size 1.27 1.27)
							)
						)
					)
				)
				(pin passive line
					(at 55.88 0 180)
					(length 5.08)
					(hide yes)
					(name "VCCO_13"
						(effects
							(font
								(size 1.27 1.27)
							)
						)
					)
					(number "AJ25"
						(effects
							(font
								(size 1.27 1.27)
							)
						)
					)
				)
				(pin bidirectional line
					(at 55.88 -3.81 180)
					(length 5.08)
					(name "IO_0_13"
						(effects
							(font
								(size 1.27 1.27)
							)
						)
					)
					(number "Y25"
						(effects
							(font
								(size 1.27 1.27)
							)
						)
					)
				)
				(pin bidirectional line
					(at 55.88 -6.35 180)
					(length 5.08)
					(name "IO_L1P_T0_13"
						(effects
							(font
								(size 1.27 1.27)
							)
						)
					)
					(number "Y26"
						(effects
							(font
								(size 1.27 1.27)
							)
						)
					)
				)
				(pin bidirectional line
					(at 55.88 -8.89 180)
					(length 5.08)
					(name "IO_L1N_T0_13"
						(effects
							(font
								(size 1.27 1.27)
							)
						)
					)
					(number "AA26"
						(effects
							(font
								(size 1.27 1.27)
							)
						)
					)
				)
				(pin bidirectional line
					(at 55.88 -11.43 180)
					(length 5.08)
					(name "IO_L2P_T0_13"
						(effects
							(font
								(size 1.27 1.27)
							)
						)
					)
					(number "W27"
						(effects
							(font
								(size 1.27 1.27)
							)
						)
					)
				)
				(pin bidirectional line
					(at 55.88 -13.97 180)
					(length 5.08)
					(name "IO_L2N_T0_13"
						(effects
							(font
								(size 1.27 1.27)
							)
						)
					)
					(number "W28"
						(effects
							(font
								(size 1.27 1.27)
							)
						)
					)
				)
				(pin bidirectional line
					(at 55.88 -16.51 180)
					(length 5.08)
					(name "IO_L3P_T0_DQS_13"
						(effects
							(font
								(size 1.27 1.27)
							)
						)
					)
					(number "Y28"
						(effects
							(font
								(size 1.27 1.27)
							)
						)
					)
				)
				(pin bidirectional line
					(at 55.88 -19.05 180)
					(length 5.08)
					(name "IO_L3N_T0_DQS_13"
						(effects
							(font
								(size 1.27 1.27)
							)
						)
					)
					(number "AA28"
						(effects
							(font
								(size 1.27 1.27)
							)
						)
					)
				)
				(pin bidirectional line
					(at 55.88 -21.59 180)
					(length 5.08)
					(name "IO_L4P_T0_13"
						(effects
							(font
								(size 1.27 1.27)
							)
						)
					)
					(number "W29"
						(effects
							(font
								(size 1.27 1.27)
							)
						)
					)
				)
				(pin bidirectional line
					(at 55.88 -24.13 180)
					(length 5.08)
					(name "IO_L4N_T0_13"
						(effects
							(font
								(size 1.27 1.27)
							)
						)
					)
					(number "Y29"
						(effects
							(font
								(size 1.27 1.27)
							)
						)
					)
				)
				(pin bidirectional line
					(at 55.88 -26.67 180)
					(length 5.08)
					(name "IO_L5P_T0_13"
						(effects
							(font
								(size 1.27 1.27)
							)
						)
					)
					(number "AA27"
						(effects
							(font
								(size 1.27 1.27)
							)
						)
					)
				)
				(pin bidirectional line
					(at 55.88 -29.21 180)
					(length 5.08)
					(name "IO_L5N_T0_13"
						(effects
							(font
								(size 1.27 1.27)
							)
						)
					)
					(number "AB28"
						(effects
							(font
								(size 1.27 1.27)
							)
						)
					)
				)
				(pin bidirectional line
					(at 55.88 -31.75 180)
					(length 5.08)
					(name "IO_L6P_T0_13"
						(effects
							(font
								(size 1.27 1.27)
							)
						)
					)
					(number "AA25"
						(effects
							(font
								(size 1.27 1.27)
							)
						)
					)
				)
				(pin bidirectional line
					(at 55.88 -34.29 180)
					(length 5.08)
					(name "IO_L6N_T0_VREF_13"
						(effects
							(font
								(size 1.27 1.27)
							)
						)
					)
					(number "AB25"
						(effects
							(font
								(size 1.27 1.27)
							)
						)
					)
				)
				(pin bidirectional line
					(at 55.88 -36.83 180)
					(length 5.08)
					(name "IO_L7P_T1_13"
						(effects
							(font
								(size 1.27 1.27)
							)
						)
					)
					(number "AC29"
						(effects
							(font
								(size 1.27 1.27)
							)
						)
					)
				)
				(pin bidirectional line
					(at 55.88 -39.37 180)
					(length 5.08)
					(name "IO_L7N_T1_13"
						(effects
							(font
								(size 1.27 1.27)
							)
						)
					)
					(number "AC30"
						(effects
							(font
								(size 1.27 1.27)
							)
						)
					)
				)
				(pin bidirectional line
					(at 55.88 -41.91 180)
					(length 5.08)
					(name "IO_L8P_T1_13"
						(effects
							(font
								(size 1.27 1.27)
							)
						)
					)
					(number "Y30"
						(effects
							(font
								(size 1.27 1.27)
							)
						)
					)
				)
				(pin bidirectional line
					(at 55.88 -44.45 180)
					(length 5.08)
					(name "IO_L8N_T1_13"
						(effects
							(font
								(size 1.27 1.27)
							)
						)
					)
					(number "AA30"
						(effects
							(font
								(size 1.27 1.27)
							)
						)
					)
				)
				(pin bidirectional line
					(at 55.88 -46.99 180)
					(length 5.08)
					(name "IO_L9P_T1_DQS_13"
						(effects
							(font
								(size 1.27 1.27)
							)
						)
					)
					(number "AD29"
						(effects
							(font
								(size 1.27 1.27)
							)
						)
					)
				)
				(pin bidirectional line
					(at 55.88 -49.53 180)
					(length 5.08)
					(name "IO_L9N_T1_DQS_13"
						(effects
							(font
								(size 1.27 1.27)
							)
						)
					)
					(number "AE29"
						(effects
							(font
								(size 1.27 1.27)
							)
						)
					)
				)
				(pin bidirectional line
					(at 55.88 -52.07 180)
					(length 5.08)
					(name "IO_L10P_T1_13"
						(effects
							(font
								(size 1.27 1.27)
							)
						)
					)
					(number "AB29"
						(effects
							(font
								(size 1.27 1.27)
							)
						)
					)
				)
				(pin bidirectional line
					(at 55.88 -54.61 180)
					(length 5.08)
					(name "IO_L10N_T1_13"
						(effects
							(font
								(size 1.27 1.27)
							)
						)
					)
					(number "AB30"
						(effects
							(font
								(size 1.27 1.27)
							)
						)
					)
				)
				(pin bidirectional line
					(at 55.88 -57.15 180)
					(length 5.08)
					(name "IO_L11P_T1_SRCC_13"
						(effects
							(font
								(size 1.27 1.27)
							)
						)
					)
					(number "AD27"
						(effects
							(font
								(size 1.27 1.27)
							)
						)
					)
				)
				(pin bidirectional line
					(at 55.88 -59.69 180)
					(length 5.08)
					(name "IO_L11N_T1_SRCC_13"
						(effects
							(font
								(size 1.27 1.27)
							)
						)
					)
					(number "AD28"
						(effects
							(font
								(size 1.27 1.27)
							)
						)
					)
				)
				(pin bidirectional line
					(at 55.88 -62.23 180)
					(length 5.08)
					(name "IO_L12P_T1_MRCC_13"
						(effects
							(font
								(size 1.27 1.27)
							)
						)
					)
					(number "AB27"
						(effects
							(font
								(size 1.27 1.27)
							)
						)
					)
				)
				(pin bidirectional line
					(at 55.88 -64.77 180)
					(length 5.08)
					(name "IO_L12N_T1_MRCC_13"
						(effects
							(font
								(size 1.27 1.27)
							)
						)
					)
					(number "AC27"
						(effects
							(font
								(size 1.27 1.27)
							)
						)
					)
				)
				(pin bidirectional line
					(at 55.88 -67.31 180)
					(length 5.08)
					(name "IO_L13P_T2_MRCC_13"
						(effects
							(font
								(size 1.27 1.27)
							)
						)
					)
					(number "AG29"
						(effects
							(font
								(size 1.27 1.27)
							)
						)
					)
				)
				(pin bidirectional line
					(at 55.88 -69.85 180)
					(length 5.08)
					(name "IO_L13N_T2_MRCC_13"
						(effects
							(font
								(size 1.27 1.27)
							)
						)
					)
					(number "AH29"
						(effects
							(font
								(size 1.27 1.27)
							)
						)
					)
				)
				(pin bidirectional line
					(at 55.88 -72.39 180)
					(length 5.08)
					(name "IO_L14P_T2_SRCC_13"
						(effects
							(font
								(size 1.27 1.27)
							)
						)
					)
					(number "AE28"
						(effects
							(font
								(size 1.27 1.27)
							)
						)
					)
				)
				(pin bidirectional line
					(at 55.88 -74.93 180)
					(length 5.08)
					(name "IO_L14N_T2_SRCC_13"
						(effects
							(font
								(size 1.27 1.27)
							)
						)
					)
					(number "AF28"
						(effects
							(font
								(size 1.27 1.27)
							)
						)
					)
				)
				(pin bidirectional line
					(at 55.88 -77.47 180)
					(length 5.08)
					(name "IO_L15P_T2_DQS_13"
						(effects
							(font
								(size 1.27 1.27)
							)
						)
					)
					(number "AK29"
						(effects
							(font
								(size 1.27 1.27)
							)
						)
					)
				)
				(pin bidirectional line
					(at 55.88 -80.01 180)
					(length 5.08)
					(name "IO_L15N_T2_DQS_13"
						(effects
							(font
								(size 1.27 1.27)
							)
						)
					)
					(number "AK30"
						(effects
							(font
								(size 1.27 1.27)
							)
						)
					)
				)
				(pin bidirectional line
					(at 55.88 -82.55 180)
					(length 5.08)
					(name "IO_L16P_T2_13"
						(effects
							(font
								(size 1.27 1.27)
							)
						)
					)
					(number "AE30"
						(effects
							(font
								(size 1.27 1.27)
							)
						)
					)
				)
				(pin bidirectional line
					(at 55.88 -85.09 180)
					(length 5.08)
					(name "IO_L16N_T2_13"
						(effects
							(font
								(size 1.27 1.27)
							)
						)
					)
					(number "AF30"
						(effects
							(font
								(size 1.27 1.27)
							)
						)
					)
				)
				(pin bidirectional line
					(at 55.88 -87.63 180)
					(length 5.08)
					(name "IO_L17P_T2_13"
						(effects
							(font
								(size 1.27 1.27)
							)
						)
					)
					(number "AJ28"
						(effects
							(font
								(size 1.27 1.27)
							)
						)
					)
				)
				(pin bidirectional line
					(at 55.88 -90.17 180)
					(length 5.08)
					(name "IO_L17N_T2_13"
						(effects
							(font
								(size 1.27 1.27)
							)
						)
					)
					(number "AJ29"
						(effects
							(font
								(size 1.27 1.27)
							)
						)
					)
				)
				(pin bidirectional line
					(at 55.88 -92.71 180)
					(length 5.08)
					(name "IO_L18P_T2_13"
						(effects
							(font
								(size 1.27 1.27)
							)
						)
					)
					(number "AG30"
						(effects
							(font
								(size 1.27 1.27)
							)
						)
					)
				)
				(pin bidirectional line
					(at 55.88 -95.25 180)
					(length 5.08)
					(name "IO_L18N_T2_13"
						(effects
							(font
								(size 1.27 1.27)
							)
						)
					)
					(number "AH30"
						(effects
							(font
								(size 1.27 1.27)
							)
						)
					)
				)
				(pin bidirectional line
					(at 55.88 -97.79 180)
					(length 5.08)
					(name "IO_L19P_T3_13"
						(effects
							(font
								(size 1.27 1.27)
							)
						)
					)
					(number "AC26"
						(effects
							(font
								(size 1.27 1.27)
							)
						)
					)
				)
				(pin bidirectional line
					(at 55.88 -100.33 180)
					(length 5.08)
					(name "IO_L19N_T3_VREF_13"
						(effects
							(font
								(size 1.27 1.27)
							)
						)
					)
					(number "AD26"
						(effects
							(font
								(size 1.27 1.27)
							)
						)
					)
				)
				(pin bidirectional line
					(at 55.88 -102.87 180)
					(length 5.08)
					(name "IO_L20P_T3_13"
						(effects
							(font
								(size 1.27 1.27)
							)
						)
					)
					(number "AJ27"
						(effects
							(font
								(size 1.27 1.27)
							)
						)
					)
				)
				(pin bidirectional line
					(at 55.88 -105.41 180)
					(length 5.08)
					(name "IO_L20N_T3_13"
						(effects
							(font
								(size 1.27 1.27)
							)
						)
					)
					(number "AK28"
						(effects
							(font
								(size 1.27 1.27)
							)
						)
					)
				)
				(pin bidirectional line
					(at 55.88 -107.95 180)
					(length 5.08)
					(name "IO_L21P_T3_DQS_13"
						(effects
							(font
								(size 1.27 1.27)
							)
						)
					)
					(number "AG27"
						(effects
							(font
								(size 1.27 1.27)
							)
						)
					)
				)
				(pin bidirectional line
					(at 55.88 -110.49 180)
					(length 5.08)
					(name "IO_L21N_T3_DQS_13"
						(effects
							(font
								(size 1.27 1.27)
							)
						)
					)
					(number "AG28"
						(effects
							(font
								(size 1.27 1.27)
							)
						)
					)
				)
				(pin bidirectional line
					(at 55.88 -113.03 180)
					(length 5.08)
					(name "IO_L22P_T3_13"
						(effects
							(font
								(size 1.27 1.27)
							)
						)
					)
					(number "AH26"
						(effects
							(font
								(size 1.27 1.27)
							)
						)
					)
				)
				(pin bidirectional line
					(at 55.88 -115.57 180)
					(length 5.08)
					(name "IO_L22N_T3_13"
						(effects
							(font
								(size 1.27 1.27)
							)
						)
					)
					(number "AH27"
						(effects
							(font
								(size 1.27 1.27)
							)
						)
					)
				)
				(pin bidirectional line
					(at 55.88 -118.11 180)
					(length 5.08)
					(name "IO_L23P_T3_13"
						(effects
							(font
								(size 1.27 1.27)
							)
						)
					)
					(number "AF26"
						(effects
							(font
								(size 1.27 1.27)
							)
						)
					)
				)
				(pin bidirectional line
					(at 55.88 -120.65 180)
					(length 5.08)
					(name "IO_L23N_T3_13"
						(effects
							(font
								(size 1.27 1.27)
							)
						)
					)
					(number "AF27"
						(effects
							(font
								(size 1.27 1.27)
							)
						)
					)
				)
				(pin bidirectional line
					(at 55.88 -123.19 180)
					(length 5.08)
					(name "IO_L24P_T3_13"
						(effects
							(font
								(size 1.27 1.27)
							)
						)
					)
					(number "AJ26"
						(effects
							(font
								(size 1.27 1.27)
							)
						)
					)
				)
				(pin bidirectional line
					(at 55.88 -125.73 180)
					(length 5.08)
					(name "IO_L24N_T3_13"
						(effects
							(font
								(size 1.27 1.27)
							)
						)
					)
					(number "AK26"
						(effects
							(font
								(size 1.27 1.27)
							)
						)
					)
				)
				(pin bidirectional line
					(at 55.88 -128.27 180)
					(length 5.08)
					(name "IO_25_13"
						(effects
							(font
								(size 1.27 1.27)
							)
						)
					)
					(number "AE26"
						(effects
							(font
								(size 1.27 1.27)
							)
						)
					)
				)
			)
			(symbol "XC7K410T-2FFG900I_1_2_1"
				(rectangle
					(start 5.08 5.08)
					(end 64.77 -130.81)
					(stroke
						(width 0.254)
						(type default)
					)
					(fill
						(type background)
					)
				)
				(text "BANK 14"
					(at 15.24 2.54 0)
					(effects
						(font
							(size 1.27 1.27)
							(thickness 0.15)
						)
						(justify left bottom)
					)
				)
				(text "BANK 15"
					(at 45.72 2.54 0)
					(effects
						(font
							(size 1.27 1.27)
							(thickness 0.15)
						)
						(justify left bottom)
					)
				)
				(pin bidirectional line
					(at 0 0 0)
					(length 5.08)
					(name "VCCO_14"
						(effects
							(font
								(size 1.27 1.27)
							)
						)
					)
					(number "P30"
						(effects
							(font
								(size 1.27 1.27)
							)
						)
					)
				)
				(pin passive line
					(at 0 0 0)
					(length 5.08)
					(hide yes)
					(name "VCCO_14"
						(effects
							(font
								(size 1.27 1.27)
							)
						)
					)
					(number "R27"
						(effects
							(font
								(size 1.27 1.27)
							)
						)
					)
				)
				(pin passive line
					(at 0 0 0)
					(length 5.08)
					(hide yes)
					(name "VCCO_14"
						(effects
							(font
								(size 1.27 1.27)
							)
						)
					)
					(number "T24"
						(effects
							(font
								(size 1.27 1.27)
							)
						)
					)
				)
				(pin passive line
					(at 0 0 0)
					(length 5.08)
					(hide yes)
					(name "VCCO_14"
						(effects
							(font
								(size 1.27 1.27)
							)
						)
					)
					(number "U21"
						(effects
							(font
								(size 1.27 1.27)
							)
						)
					)
				)
				(pin passive line
					(at 0 0 0)
					(length 5.08)
					(hide yes)
					(name "VCCO_14"
						(effects
							(font
								(size 1.27 1.27)
							)
						)
					)
					(number "V28"
						(effects
							(font
								(size 1.27 1.27)
							)
						)
					)
				)
				(pin passive line
					(at 0 0 0)
					(length 5.08)
					(hide yes)
					(name "VCCO_14"
						(effects
							(font
								(size 1.27 1.27)
							)
						)
					)
					(number "W25"
						(effects
							(font
								(size 1.27 1.27)
							)
						)
					)
				)
				(pin bidirectional line
					(at 0 -3.81 0)
					(length 5.08)
					(name "IO_0_14"
						(effects
							(font
								(size 1.27 1.27)
							)
						)
					)
					(number "R19"
						(effects
							(font
								(size 1.27 1.27)
							)
						)
					)
				)
				(pin bidirectional line
					(at 0 -6.35 0)
					(length 5.08)
					(name "IO_L1P_T0_D00_MOSI_14"
						(effects
							(font
								(size 1.27 1.27)
							)
						)
					)
					(number "P24"
						(effects
							(font
								(size 1.27 1.27)
							)
						)
					)
				)
				(pin bidirectional line
					(at 0 -8.89 0)
					(length 5.08)
					(name "IO_L1N_T0_D01_DIN_14"
						(effects
							(font
								(size 1.27 1.27)
							)
						)
					)
					(number "R25"
						(effects
							(font
								(size 1.27 1.27)
							)
						)
					)
				)
				(pin bidirectional line
					(at 0 -11.43 0)
					(length 5.08)
					(name "IO_L2P_T0_D02_14"
						(effects
							(font
								(size 1.27 1.27)
							)
						)
					)
					(number "R20"
						(effects
							(font
								(size 1.27 1.27)
							)
						)
					)
				)
				(pin bidirectional line
					(at 0 -13.97 0)
					(length 5.08)
					(name "IO_L2N_T0_D03_14"
						(effects
							(font
								(size 1.27 1.27)
							)
						)
					)
					(number "R21"
						(effects
							(font
								(size 1.27 1.27)
							)
						)
					)
				)
				(pin bidirectional line
					(at 0 -16.51 0)
					(length 5.08)
					(name "IO_L3P_T0_DQS_PUDC_B_14"
						(effects
							(font
								(size 1.27 1.27)
							)
						)
					)
					(number "R23"
						(effects
							(font
								(size 1.27 1.27)
							)
						)
					)
				)
				(pin bidirectional line
					(at 0 -19.05 0)
					(length 5.08)
					(name "IO_L3N_T0_DQS_EMCCLK_14"
						(effects
							(font
								(size 1.27 1.27)
							)
						)
					)
					(number "R24"
						(effects
							(font
								(size 1.27 1.27)
							)
						)
					)
				)
				(pin bidirectional line
					(at 0 -21.59 0)
					(length 5.08)
					(name "IO_L4P_T0_D04_14"
						(effects
							(font
								(size 1.27 1.27)
							)
						)
					)
					(number "T20"
						(effects
							(font
								(size 1.27 1.27)
							)
						)
					)
				)
				(pin bidirectional line
					(at 0 -24.13 0)
					(length 5.08)
					(name "IO_L4N_T0_D05_14"
						(effects
							(font
								(size 1.27 1.27)
							)
						)
					)
					(number "T21"
						(effects
							(font
								(size 1.27 1.27)
							)
						)
					)
				)
				(pin bidirectional line
					(at 0 -26.67 0)
					(length 5.08)
					(name "IO_L5P_T0_D06_14"
						(effects
							(font
								(size 1.27 1.27)
							)
						)
					)
					(number "T22"
						(effects
							(font
								(size 1.27 1.27)
							)
						)
					)
				)
				(pin bidirectional line
					(at 0 -29.21 0)
					(length 5.08)
					(name "IO_L5N_T0_D07_14"
						(effects
							(font
								(size 1.27 1.27)
							)
						)
					)
					(number "T23"
						(effects
							(font
								(size 1.27 1.27)
							)
						)
					)
				)
				(pin bidirectional line
					(at 0 -31.75 0)
					(length 5.08)
					(name "IO_L6P_T0_FCS_B_14"
						(effects
							(font
								(size 1.27 1.27)
							)
						)
					)
					(number "U19"
						(effects
							(font
								(size 1.27 1.27)
							)
						)
					)
				)
				(pin bidirectional line
					(at 0 -34.29 0)
					(length 5.08)
					(name "IO_L6N_T0_D08_VREF_14"
						(effects
							(font
								(size 1.27 1.27)
							)
						)
					)
					(number "U20"
						(effects
							(font
								(size 1.27 1.27)
							)
						)
					)
				)
				(pin bidirectional line
					(at 0 -36.83 0)
					(length 5.08)
					(name "IO_L7P_T1_D09_14"
						(effects
							(font
								(size 1.27 1.27)
							)
						)
					)
					(number "P29"
						(effects
							(font
								(size 1.27 1.27)
							)
						)
					)
				)
				(pin bidirectional line
					(at 0 -39.37 0)
					(length 5.08)
					(name "IO_L7N_T1_D10_14"
						(effects
							(font
								(size 1.27 1.27)
							)
						)
					)
					(number "R29"
						(effects
							(font
								(size 1.27 1.27)
							)
						)
					)
				)
				(pin bidirectional line
					(at 0 -41.91 0)
					(length 5.08)
					(name "IO_L8P_T1_D11_14"
						(effects
							(font
								(size 1.27 1.27)
							)
						)
					)
					(number "P27"
						(effects
							(font
								(size 1.27 1.27)
							)
						)
					)
				)
				(pin bidirectional line
					(at 0 -44.45 0)
					(length 5.08)
					(name "IO_L8N_T1_D12_14"
						(effects
							(font
								(size 1.27 1.27)
							)
						)
					)
					(number "P28"
						(effects
							(font
								(size 1.27 1.27)
							)
						)
					)
				)
				(pin bidirectional line
					(at 0 -46.99 0)
					(length 5.08)
					(name "IO_L9P_T1_DQS_14"
						(effects
							(font
								(size 1.27 1.27)
							)
						)
					)
					(number "R30"
						(effects
							(font
								(size 1.27 1.27)
							)
						)
					)
				)
				(pin bidirectional line
					(at 0 -49.53 0)
					(length 5.08)
					(name "IO_L9N_T1_DQS_D13_14"
						(effects
							(font
								(size 1.27 1.27)
							)
						)
					)
					(number "T30"
						(effects
							(font
								(size 1.27 1.27)
							)
						)
					)
				)
				(pin bidirectional line
					(at 0 -52.07 0)
					(length 5.08)
					(name "IO_L10P_T1_D14_14"
						(effects
							(font
								(size 1.27 1.27)
							)
						)
					)
					(number "P26"
						(effects
							(font
								(size 1.27 1.27)
							)
						)
					)
				)
				(pin bidirectional line
					(at 0 -54.61 0)
					(length 5.08)
					(name "IO_L10N_T1_D15_14"
						(effects
							(font
								(size 1.27 1.27)
							)
						)
					)
					(number "R26"
						(effects
							(font
								(size 1.27 1.27)
							)
						)
					)
				)
				(pin bidirectional line
					(at 0 -57.15 0)
					(length 5.08)
					(name "IO_L11P_T1_SRCC_14"
						(effects
							(font
								(size 1.27 1.27)
							)
						)
					)
					(number "R28"
						(effects
							(font
								(size 1.27 1.27)
							)
						)
					)
				)
				(pin bidirectional line
					(at 0 -59.69 0)
					(length 5.08)
					(name "IO_L11N_T1_SRCC_14"
						(effects
							(font
								(size 1.27 1.27)
							)
						)
					)
					(number "T28"
						(effects
							(font
								(size 1.27 1.27)
							)
						)
					)
				)
				(pin bidirectional line
					(at 0 -62.23 0)
					(length 5.08)
					(name "IO_L12P_T1_MRCC_14"
						(effects
							(font
								(size 1.27 1.27)
							)
						)
					)
					(number "T26"
						(effects
							(font
								(size 1.27 1.27)
							)
						)
					)
				)
				(pin bidirectional line
					(at 0 -64.77 0)
					(length 5.08)
					(name "IO_L12N_T1_MRCC_14"
						(effects
							(font
								(size 1.27 1.27)
							)
						)
					)
					(number "T27"
						(effects
							(font
								(size 1.27 1.27)
							)
						)
					)
				)
				(pin bidirectional line
					(at 0 -67.31 0)
					(length 5.08)
					(name "IO_L13P_T2_MRCC_14"
						(effects
							(font
								(size 1.27 1.27)
							)
						)
					)
					(number "U27"
						(effects
							(font
								(size 1.27 1.27)
							)
						)
					)
				)
				(pin bidirectional line
					(at 0 -69.85 0)
					(length 5.08)
					(name "IO_L13N_T2_MRCC_14"
						(effects
							(font
								(size 1.27 1.27)
							)
						)
					)
					(number "U28"
						(effects
							(font
								(size 1.27 1.27)
							)
						)
					)
				)
				(pin bidirectional line
					(at 0 -72.39 0)
					(length 5.08)
					(name "IO_L14P_T2_SRCC_14"
						(effects
							(font
								(size 1.27 1.27)
							)
						)
					)
					(number "T25"
						(effects
							(font
								(size 1.27 1.27)
							)
						)
					)
				)
				(pin bidirectional line
					(at 0 -74.93 0)
					(length 5.08)
					(name "IO_L14N_T2_SRCC_14"
						(effects
							(font
								(size 1.27 1.27)
							)
						)
					)
					(number "U25"
						(effects
							(font
								(size 1.27 1.27)
							)
						)
					)
				)
				(pin bidirectional line
					(at 0 -77.47 0)
					(length 5.08)
					(name "IO_L15P_T2_DQS_RDWR_B_14"
						(effects
							(font
								(size 1.27 1.27)
							)
						)
					)
					(number "U29"
						(effects
							(font
								(size 1.27 1.27)
							)
						)
					)
				)
				(pin bidirectional line
					(at 0 -80.01 0)
					(length 5.08)
					(name "IO_L15N_T2_DQS_DOUT_CSO_B_14"
						(effects
							(font
								(size 1.27 1.27)
							)
						)
					)
					(number "U30"
						(effects
							(font
								(size 1.27 1.27)
							)
						)
					)
				)
				(pin bidirectional line
					(at 0 -82.55 0)
					(length 5.08)
					(name "IO_L16P_T2_CSI_B_14"
						(effects
							(font
								(size 1.27 1.27)
							)
						)
					)
					(number "V26"
						(effects
							(font
								(size 1.27 1.27)
							)
						)
					)
				)
				(pin bidirectional line
					(at 0 -85.09 0)
					(length 5.08)
					(name "IO_L16N_T2_A15_D31_14"
						(effects
							(font
								(size 1.27 1.27)
							)
						)
					)
					(number "V27"
						(effects
							(font
								(size 1.27 1.27)
							)
						)
					)
				)
				(pin bidirectional line
					(at 0 -87.63 0)
					(length 5.08)
					(name "IO_L17P_T2_A14_D30_14"
						(effects
							(font
								(size 1.27 1.27)
							)
						)
					)
					(number "V29"
						(effects
							(font
								(size 1.27 1.27)
							)
						)
					)
				)
				(pin bidirectional line
					(at 0 -90.17 0)
					(length 5.08)
					(name "IO_L17N_T2_A13_D29_14"
						(effects
							(font
								(size 1.27 1.27)
							)
						)
					)
					(number "V30"
						(effects
							(font
								(size 1.27 1.27)
							)
						)
					)
				)
				(pin bidirectional line
					(at 0 -92.71 0)
					(length 5.08)
					(name "IO_L18P_T2_A12_D28_14"
						(effects
							(font
								(size 1.27 1.27)
							)
						)
					)
					(number "V25"
						(effects
							(font
								(size 1.27 1.27)
							)
						)
					)
				)
				(pin bidirectional line
					(at 0 -95.25 0)
					(length 5.08)
					(name "IO_L18N_T2_A11_D27_14"
						(effects
							(font
								(size 1.27 1.27)
							)
						)
					)
					(number "W26"
						(effects
							(font
								(size 1.27 1.27)
							)
						)
					)
				)
				(pin bidirectional line
					(at 0 -97.79 0)
					(length 5.08)
					(name "IO_L19P_T3_A10_D26_14"
						(effects
							(font
								(size 1.27 1.27)
							)
						)
					)
					(number "V19"
						(effects
							(font
								(size 1.27 1.27)
							)
						)
					)
				)
				(pin bidirectional line
					(at 0 -100.33 0)
					(length 5.08)
					(name "IO_L19N_T3_A09_D25_VREF_14"
						(effects
							(font
								(size 1.27 1.27)
							)
						)
					)
					(number "V20"
						(effects
							(font
								(size 1.27 1.27)
							)
						)
					)
				)
				(pin bidirectional line
					(at 0 -102.87 0)
					(length 5.08)
					(name "IO_L20P_T3_A08_D24_14"
						(effects
							(font
								(size 1.27 1.27)
							)
						)
					)
					(number "W23"
						(effects
							(font
								(size 1.27 1.27)
							)
						)
					)
				)
				(pin bidirectional line
					(at 0 -105.41 0)
					(length 5.08)
					(name "IO_L20N_T3_A07_D23_14"
						(effects
							(font
								(size 1.27 1.27)
							)
						)
					)
					(number "W24"
						(effects
							(font
								(size 1.27 1.27)
							)
						)
					)
				)
				(pin bidirectional line
					(at 0 -107.95 0)
					(length 5.08)
					(name "IO_L21P_T3_DQS_14"
						(effects
							(font
								(size 1.27 1.27)
							)
						)
					)
					(number "U22"
						(effects
							(font
								(size 1.27 1.27)
							)
						)
					)
				)
				(pin bidirectional line
					(at 0 -110.49 0)
					(length 5.08)
					(name "IO_L21N_T3_DQS_A06_D22_14"
						(effects
							(font
								(size 1.27 1.27)
							)
						)
					)
					(number "U23"
						(effects
							(font
								(size 1.27 1.27)
							)
						)
					)
				)
				(pin bidirectional line
					(at 0 -113.03 0)
					(length 5.08)
					(name "IO_L22P_T3_A05_D21_14"
						(effects
							(font
								(size 1.27 1.27)
							)
						)
					)
					(number "V21"
						(effects
							(font
								(size 1.27 1.27)
							)
						)
					)
				)
				(pin bidirectional line
					(at 0 -115.57 0)
					(length 5.08)
					(name "IO_L22N_T3_A04_D20_14"
						(effects
							(font
								(size 1.27 1.27)
							)
						)
					)
					(number "V22"
						(effects
							(font
								(size 1.27 1.27)
							)
						)
					)
				)
				(pin bidirectional line
					(at 0 -118.11 0)
					(length 5.08)
					(name "IO_L23P_T3_A03_D19_14"
						(effects
							(font
								(size 1.27 1.27)
							)
						)
					)
					(number "U24"
						(effects
							(font
								(size 1.27 1.27)
							)
						)
					)
				)
				(pin bidirectional line
					(at 0 -120.65 0)
					(length 5.08)
					(name "IO_L23N_T3_A02_D18_14"
						(effects
							(font
								(size 1.27 1.27)
							)
						)
					)
					(number "V24"
						(effects
							(font
								(size 1.27 1.27)
							)
						)
					)
				)
				(pin bidirectional line
					(at 0 -123.19 0)
					(length 5.08)
					(name "IO_L24P_T3_A01_D17_14"
						(effects
							(font
								(size 1.27 1.27)
							)
						)
					)
					(number "W21"
						(effects
							(font
								(size 1.27 1.27)
							)
						)
					)
				)
				(pin bidirectional line
					(at 0 -125.73 0)
					(length 5.08)
					(name "IO_L24N_T3_A00_D16_14"
						(effects
							(font
								(size 1.27 1.27)
							)
						)
					)
					(number "W22"
						(effects
							(font
								(size 1.27 1.27)
							)
						)
					)
				)
				(pin bidirectional line
					(at 0 -128.27 0)
					(length 5.08)
					(name "IO_25_14"
						(effects
							(font
								(size 1.27 1.27)
							)
						)
					)
					(number "W19"
						(effects
							(font
								(size 1.27 1.27)
							)
						)
					)
				)
				(pin bidirectional line
					(at 69.85 0 180)
					(length 5.08)
					(name "VCCO_15"
						(effects
							(font
								(size 1.27 1.27)
							)
						)
					)
					(number "J25"
						(effects
							(font
								(size 1.27 1.27)
							)
						)
					)
				)
				(pin passive line
					(at 69.85 0 180)
					(length 5.08)
					(hide yes)
					(name "VCCO_15"
						(effects
							(font
								(size 1.27 1.27)
							)
						)
					)
					(number "K22"
						(effects
							(font
								(size 1.27 1.27)
							)
						)
					)
				)
				(pin passive line
					(at 69.85 0 180)
					(length 5.08)
					(hide yes)
					(name "VCCO_15"
						(effects
							(font
								(size 1.27 1.27)
							)
						)
					)
					(number "L29"
						(effects
							(font
								(size 1.27 1.27)
							)
						)
					)
				)
				(pin passive line
					(at 69.85 0 180)
					(length 5.08)
					(hide yes)
					(name "VCCO_15"
						(effects
							(font
								(size 1.27 1.27)
							)
						)
					)
					(number "M26"
						(effects
							(font
								(size 1.27 1.27)
							)
						)
					)
				)
				(pin passive line
					(at 69.85 0 180)
					(length 5.08)
					(hide yes)
					(name "VCCO_15"
						(effects
							(font
								(size 1.27 1.27)
							)
						)
					)
					(number "N23"
						(effects
							(font
								(size 1.27 1.27)
							)
						)
					)
				)
				(pin passive line
					(at 69.85 0 180)
					(length 5.08)
					(hide yes)
					(name "VCCO_15"
						(effects
							(font
								(size 1.27 1.27)
							)
						)
					)
					(number "P20"
						(effects
							(font
								(size 1.27 1.27)
							)
						)
					)
				)
				(pin bidirectional line
					(at 69.85 -3.81 180)
					(length 5.08)
					(name "IO_0_15"
						(effects
							(font
								(size 1.27 1.27)
							)
						)
					)
					(number "M19"
						(effects
							(font
								(size 1.27 1.27)
							)
						)
					)
				)
				(pin bidirectional line
					(at 69.85 -6.35 180)
					(length 5.08)
					(name "IO_L1P_T0_AD0P_15"
						(effects
							(font
								(size 1.27 1.27)
							)
						)
					)
					(number "J23"
						(effects
							(font
								(size 1.27 1.27)
							)
						)
					)
				)
				(pin bidirectional line
					(at 69.85 -8.89 180)
					(length 5.08)
					(name "IO_L1N_T0_AD0N_15"
						(effects
							(font
								(size 1.27 1.27)
							)
						)
					)
					(number "J24"
						(effects
							(font
								(size 1.27 1.27)
							)
						)
					)
				)
				(pin bidirectional line
					(at 69.85 -11.43 180)
					(length 5.08)
					(name "IO_L2P_T0_AD8P_15"
						(effects
							(font
								(size 1.27 1.27)
							)
						)
					)
					(number "L22"
						(effects
							(font
								(size 1.27 1.27)
							)
						)
					)
				)
				(pin bidirectional line
					(at 69.85 -13.97 180)
					(length 5.08)
					(name "IO_L2N_T0_AD8N_15"
						(effects
							(font
								(size 1.27 1.27)
							)
						)
					)
					(number "L23"
						(effects
							(font
								(size 1.27 1.27)
							)
						)
					)
				)
				(pin bidirectional line
					(at 69.85 -16.51 180)
					(length 5.08)
					(name "IO_L3P_T0_DQS_AD1P_15"
						(effects
							(font
								(size 1.27 1.27)
							)
						)
					)
					(number "K23"
						(effects
							(font
								(size 1.27 1.27)
							)
						)
					)
				)
				(pin bidirectional line
					(at 69.85 -19.05 180)
					(length 5.08)
					(name "IO_L3N_T0_DQS_AD1N_15"
						(effects
							(font
								(size 1.27 1.27)
							)
						)
					)
					(number "K24"
						(effects
							(font
								(size 1.27 1.27)
							)
						)
					)
				)
				(pin bidirectional line
					(at 69.85 -21.59 180)
					(length 5.08)
					(name "IO_L4P_T0_AD9P_15"
						(effects
							(font
								(size 1.27 1.27)
							)
						)
					)
					(number "L21"
						(effects
							(font
								(size 1.27 1.27)
							)
						)
					)
				)
				(pin bidirectional line
					(at 69.85 -24.13 180)
					(length 5.08)
					(name "IO_L4N_T0_AD9N_15"
						(effects
							(font
								(size 1.27 1.27)
							)
						)
					)
					(number "K21"
						(effects
							(font
								(size 1.27 1.27)
							)
						)
					)
				)
				(pin bidirectional line
					(at 69.85 -26.67 180)
					(length 5.08)
					(name "IO_L5P_T0_AD2P_15"
						(effects
							(font
								(size 1.27 1.27)
							)
						)
					)
					(number "J21"
						(effects
							(font
								(size 1.27 1.27)
							)
						)
					)
				)
				(pin bidirectional line
					(at 69.85 -29.21 180)
					(length 5.08)
					(name "IO_L5N_T0_AD2N_15"
						(effects
							(font
								(size 1.27 1.27)
							)
						)
					)
					(number "J22"
						(effects
							(font
								(size 1.27 1.27)
							)
						)
					)
				)
				(pin bidirectional line
					(at 69.85 -31.75 180)
					(length 5.08)
					(name "IO_L6P_T0_15"
						(effects
							(font
								(size 1.27 1.27)
							)
						)
					)
					(number "M20"
						(effects
							(font
								(size 1.27 1.27)
							)
						)
					)
				)
				(pin bidirectional line
					(at 69.85 -34.29 180)
					(length 5.08)
					(name "IO_L6N_T0_VREF_15"
						(effects
							(font
								(size 1.27 1.27)
							)
						)
					)
					(number "L20"
						(effects
							(font
								(size 1.27 1.27)
							)
						)
					)
				)
				(pin bidirectional line
					(at 69.85 -36.83 180)
					(length 5.08)
					(name "IO_L7P_T1_AD10P_15"
						(effects
							(font
								(size 1.27 1.27)
							)
						)
					)
					(number "J29"
						(effects
							(font
								(size 1.27 1.27)
							)
						)
					)
				)
				(pin bidirectional line
					(at 69.85 -39.37 180)
					(length 5.08)
					(name "IO_L7N_T1_AD10N_15"
						(effects
							(font
								(size 1.27 1.27)
							)
						)
					)
					(number "H29"
						(effects
							(font
								(size 1.27 1.27)
							)
						)
					)
				)
				(pin bidirectional line
					(at 69.85 -41.91 180)
					(length 5.08)
					(name "IO_L8P_T1_AD3P_15"
						(effects
							(font
								(size 1.27 1.27)
							)
						)
					)
					(number "J27"
						(effects
							(font
								(size 1.27 1.27)
							)
						)
					)
				)
				(pin bidirectional line
					(at 69.85 -44.45 180)
					(length 5.08)
					(name "IO_L8N_T1_AD3N_15"
						(effects
							(font
								(size 1.27 1.27)
							)
						)
					)
					(number "J28"
						(effects
							(font
								(size 1.27 1.27)
							)
						)
					)
				)
				(pin bidirectional line
					(at 69.85 -46.99 180)
					(length 5.08)
					(name "IO_L9P_T1_DQS_AD11P_15"
						(effects
							(font
								(size 1.27 1.27)
							)
						)
					)
					(number "L30"
						(effects
							(font
								(size 1.27 1.27)
							)
						)
					)
				)
				(pin bidirectional line
					(at 69.85 -49.53 180)
					(length 5.08)
					(name "IO_L9N_T1_DQS_AD11N_15"
						(effects
							(font
								(size 1.27 1.27)
							)
						)
					)
					(number "K30"
						(effects
							(font
								(size 1.27 1.27)
							)
						)
					)
				)
				(pin bidirectional line
					(at 69.85 -52.07 180)
					(length 5.08)
					(name "IO_L10P_T1_AD4P_15"
						(effects
							(font
								(size 1.27 1.27)
							)
						)
					)
					(number "K26"
						(effects
							(font
								(size 1.27 1.27)
							)
						)
					)
				)
				(pin bidirectional line
					(at 69.85 -54.61 180)
					(length 5.08)
					(name "IO_L10N_T1_AD4N_15"
						(effects
							(font
								(size 1.27 1.27)
							)
						)
					)
					(number "J26"
						(effects
							(font
								(size 1.27 1.27)
							)
						)
					)
				)
				(pin bidirectional line
					(at 69.85 -57.15 180)
					(length 5.08)
					(name "IO_L11P_T1_SRCC_AD12P_15"
						(effects
							(font
								(size 1.27 1.27)
							)
						)
					)
					(number "L26"
						(effects
							(font
								(size 1.27 1.27)
							)
						)
					)
				)
				(pin bidirectional line
					(at 69.85 -59.69 180)
					(length 5.08)
					(name "IO_L11N_T1_SRCC_AD12N_15"
						(effects
							(font
								(size 1.27 1.27)
							)
						)
					)
					(number "L27"
						(effects
							(font
								(size 1.27 1.27)
							)
						)
					)
				)
				(pin bidirectional line
					(at 69.85 -62.23 180)
					(length 5.08)
					(name "IO_L12P_T1_MRCC_AD5P_15"
						(effects
							(font
								(size 1.27 1.27)
							)
						)
					)
					(number "L25"
						(effects
							(font
								(size 1.27 1.27)
							)
						)
					)
				)
				(pin bidirectional line
					(at 69.85 -64.77 180)
					(length 5.08)
					(name "IO_L12N_T1_MRCC_AD5N_15"
						(effects
							(font
								(size 1.27 1.27)
							)
						)
					)
					(number "K25"
						(effects
							(font
								(size 1.27 1.27)
							)
						)
					)
				)
				(pin bidirectional line
					(at 69.85 -67.31 180)
					(length 5.08)
					(name "IO_L13P_T2_MRCC_15"
						(effects
							(font
								(size 1.27 1.27)
							)
						)
					)
					(number "K28"
						(effects
							(font
								(size 1.27 1.27)
							)
						)
					)
				)
				(pin bidirectional line
					(at 69.85 -69.85 180)
					(length 5.08)
					(name "IO_L13N_T2_MRCC_15"
						(effects
							(font
								(size 1.27 1.27)
							)
						)
					)
					(number "K29"
						(effects
							(font
								(size 1.27 1.27)
							)
						)
					)
				)
				(pin bidirectional line
					(at 69.85 -72.39 180)
					(length 5.08)
					(name "IO_L14P_T2_SRCC_15"
						(effects
							(font
								(size 1.27 1.27)
							)
						)
					)
					(number "M28"
						(effects
							(font
								(size 1.27 1.27)
							)
						)
					)
				)
				(pin bidirectional line
					(at 69.85 -74.93 180)
					(length 5.08)
					(name "IO_L14N_T2_SRCC_15"
						(effects
							(font
								(size 1.27 1.27)
							)
						)
					)
					(number "L28"
						(effects
							(font
								(size 1.27 1.27)
							)
						)
					)
				)
				(pin bidirectional line
					(at 69.85 -77.47 180)
					(length 5.08)
					(name "IO_L15P_T2_DQS_15"
						(effects
							(font
								(size 1.27 1.27)
							)
						)
					)
					(number "M29"
						(effects
							(font
								(size 1.27 1.27)
							)
						)
					)
				)
				(pin bidirectional line
					(at 69.85 -80.01 180)
					(length 5.08)
					(name "IO_L15N_T2_DQS_ADV_B_15"
						(effects
							(font
								(size 1.27 1.27)
							)
						)
					)
					(number "M30"
						(effects
							(font
								(size 1.27 1.27)
							)
						)
					)
				)
				(pin bidirectional line
					(at 69.85 -82.55 180)
					(length 5.08)
					(name "IO_L16P_T2_A28_15"
						(effects
							(font
								(size 1.27 1.27)
							)
						)
					)
					(number "N27"
						(effects
							(font
								(size 1.27 1.27)
							)
						)
					)
				)
				(pin bidirectional line
					(at 69.85 -85.09 180)
					(length 5.08)
					(name "IO_L16N_T2_A27_15"
						(effects
							(font
								(size 1.27 1.27)
							)
						)
					)
					(number "M27"
						(effects
							(font
								(size 1.27 1.27)
							)
						)
					)
				)
				(pin bidirectional line
					(at 69.85 -87.63 180)
					(length 5.08)
					(name "IO_L17P_T2_A26_15"
						(effects
							(font
								(size 1.27 1.27)
							)
						)
					)
					(number "N29"
						(effects
							(font
								(size 1.27 1.27)
							)
						)
					)
				)
				(pin bidirectional line
					(at 69.85 -90.17 180)
					(length 5.08)
					(name "IO_L17N_T2_A25_15"
						(effects
							(font
								(size 1.27 1.27)
							)
						)
					)
					(number "N30"
						(effects
							(font
								(size 1.27 1.27)
							)
						)
					)
				)
				(pin bidirectional line
					(at 69.85 -92.71 180)
					(length 5.08)
					(name "IO_L18P_T2_A24_15"
						(effects
							(font
								(size 1.27 1.27)
							)
						)
					)
					(number "N25"
						(effects
							(font
								(size 1.27 1.27)
							)
						)
					)
				)
				(pin bidirectional line
					(at 69.85 -95.25 180)
					(length 5.08)
					(name "IO_L18N_T2_A23_15"
						(effects
							(font
								(size 1.27 1.27)
							)
						)
					)
					(number "N26"
						(effects
							(font
								(size 1.27 1.27)
							)
						)
					)
				)
				(pin bidirectional line
					(at 69.85 -97.79 180)
					(length 5.08)
					(name "IO_L19P_T3_A22_15"
						(effects
							(font
								(size 1.27 1.27)
							)
						)
					)
					(number "N19"
						(effects
							(font
								(size 1.27 1.27)
							)
						)
					)
				)
				(pin bidirectional line
					(at 69.85 -100.33 180)
					(length 5.08)
					(name "IO_L19N_T3_A21_VREF_15"
						(effects
							(font
								(size 1.27 1.27)
							)
						)
					)
					(number "N20"
						(effects
							(font
								(size 1.27 1.27)
							)
						)
					)
				)
				(pin bidirectional line
					(at 69.85 -102.87 180)
					(length 5.08)
					(name "IO_L20P_T3_A20_15"
						(effects
							(font
								(size 1.27 1.27)
							)
						)
					)
					(number "N21"
						(effects
							(font
								(size 1.27 1.27)
							)
						)
					)
				)
				(pin bidirectional line
					(at 69.85 -105.41 180)
					(length 5.08)
					(name "IO_L20N_T3_A19_15"
						(effects
							(font
								(size 1.27 1.27)
							)
						)
					)
					(number "N22"
						(effects
							(font
								(size 1.27 1.27)
							)
						)
					)
				)
				(pin bidirectional line
					(at 69.85 -107.95 180)
					(length 5.08)
					(name "IO_L21P_T3_DQS_15"
						(effects
							(font
								(size 1.27 1.27)
							)
						)
					)
					(number "P23"
						(effects
							(font
								(size 1.27 1.27)
							)
						)
					)
				)
				(pin bidirectional line
					(at 69.85 -110.49 180)
					(length 5.08)
					(name "IO_L21N_T3_DQS_A18_15"
						(effects
							(font
								(size 1.27 1.27)
							)
						)
					)
					(number "N24"
						(effects
							(font
								(size 1.27 1.27)
							)
						)
					)
				)
				(pin bidirectional line
					(at 69.85 -113.03 180)
					(length 5.08)
					(name "IO_L22P_T3_A17_15"
						(effects
							(font
								(size 1.27 1.27)
							)
						)
					)
					(number "P21"
						(effects
							(font
								(size 1.27 1.27)
							)
						)
					)
				)
				(pin bidirectional line
					(at 69.85 -115.57 180)
					(length 5.08)
					(name "IO_L22N_T3_A16_15"
						(effects
							(font
								(size 1.27 1.27)
							)
						)
					)
					(number "P22"
						(effects
							(font
								(size 1.27 1.27)
							)
						)
					)
				)
				(pin bidirectional line
					(at 69.85 -118.11 180)
					(length 5.08)
					(name "IO_L23P_T3_FOE_B_15"
						(effects
							(font
								(size 1.27 1.27)
							)
						)
					)
					(number "M24"
						(effects
							(font
								(size 1.27 1.27)
							)
						)
					)
				)
				(pin bidirectional line
					(at 69.85 -120.65 180)
					(length 5.08)
					(name "IO_L23N_T3_FWE_B_15"
						(effects
							(font
								(size 1.27 1.27)
							)
						)
					)
					(number "M25"
						(effects
							(font
								(size 1.27 1.27)
							)
						)
					)
				)
				(pin bidirectional line
					(at 69.85 -123.19 180)
					(length 5.08)
					(name "IO_L24P_T3_RS1_15"
						(effects
							(font
								(size 1.27 1.27)
							)
						)
					)
					(number "M22"
						(effects
							(font
								(size 1.27 1.27)
							)
						)
					)
				)
				(pin bidirectional line
					(at 69.85 -125.73 180)
					(length 5.08)
					(name "IO_L24N_T3_RS0_15"
						(effects
							(font
								(size 1.27 1.27)
							)
						)
					)
					(number "M23"
						(effects
							(font
								(size 1.27 1.27)
							)
						)
					)
				)
				(pin bidirectional line
					(at 69.85 -128.27 180)
					(length 5.08)
					(name "IO_25_15"
						(effects
							(font
								(size 1.27 1.27)
							)
						)
					)
					(number "P19"
						(effects
							(font
								(size 1.27 1.27)
							)
						)
					)
				)
			)
			(symbol "XC7K410T-2FFG900I_1_3_1"
				(rectangle
					(start 5.08 5.08)
					(end 49.53 -130.81)
					(stroke
						(width 0.254)
						(type default)
					)
					(fill
						(type background)
					)
				)
				(text "BANK 16"
					(at 15.24 2.54 0)
					(effects
						(font
							(size 1.27 1.27)
							(thickness 0.15)
						)
						(justify left bottom)
					)
				)
				(text "BANK 17"
					(at 30.48 2.54 0)
					(effects
						(font
							(size 1.27 1.27)
							(thickness 0.15)
						)
						(justify left bottom)
					)
				)
				(pin bidirectional line
					(at 0 0 0)
					(length 5.08)
					(name "VCCO_16"
						(effects
							(font
								(size 1.27 1.27)
							)
						)
					)
					(number "A29"
						(effects
							(font
								(size 1.27 1.27)
							)
						)
					)
				)
				(pin passive line
					(at 0 0 0)
					(length 5.08)
					(hide yes)
					(name "VCCO_16"
						(effects
							(font
								(size 1.27 1.27)
							)
						)
					)
					(number "B26"
						(effects
							(font
								(size 1.27 1.27)
							)
						)
					)
				)
				(pin passive line
					(at 0 0 0)
					(length 5.08)
					(hide yes)
					(name "VCCO_16"
						(effects
							(font
								(size 1.27 1.27)
							)
						)
					)
					(number "C23"
						(effects
							(font
								(size 1.27 1.27)
							)
						)
					)
				)
				(pin passive line
					(at 0 0 0)
					(length 5.08)
					(hide yes)
					(name "VCCO_16"
						(effects
							(font
								(size 1.27 1.27)
							)
						)
					)
					(number "D30"
						(effects
							(font
								(size 1.27 1.27)
							)
						)
					)
				)
				(pin passive line
					(at 0 0 0)
					(length 5.08)
					(hide yes)
					(name "VCCO_16"
						(effects
							(font
								(size 1.27 1.27)
							)
						)
					)
					(number "E27"
						(effects
							(font
								(size 1.27 1.27)
							)
						)
					)
				)
				(pin passive line
					(at 0 0 0)
					(length 5.08)
					(hide yes)
					(name "VCCO_16"
						(effects
							(font
								(size 1.27 1.27)
							)
						)
					)
					(number "F24"
						(effects
							(font
								(size 1.27 1.27)
							)
						)
					)
				)
				(pin passive line
					(at 0 0 0)
					(length 5.08)
					(hide yes)
					(name "VCCO_16"
						(effects
							(font
								(size 1.27 1.27)
							)
						)
					)
					(number "H28"
						(effects
							(font
								(size 1.27 1.27)
							)
						)
					)
				)
				(pin bidirectional line
					(at 0 -3.81 0)
					(length 5.08)
					(name "IO_0_16"
						(effects
							(font
								(size 1.27 1.27)
							)
						)
					)
					(number "F23"
						(effects
							(font
								(size 1.27 1.27)
							)
						)
					)
				)
				(pin bidirectional line
					(at 0 -6.35 0)
					(length 5.08)
					(name "IO_L1P_T0_16"
						(effects
							(font
								(size 1.27 1.27)
							)
						)
					)
					(number "B23"
						(effects
							(font
								(size 1.27 1.27)
							)
						)
					)
				)
				(pin bidirectional line
					(at 0 -8.89 0)
					(length 5.08)
					(name "IO_L1N_T0_16"
						(effects
							(font
								(size 1.27 1.27)
							)
						)
					)
					(number "A23"
						(effects
							(font
								(size 1.27 1.27)
							)
						)
					)
				)
				(pin bidirectional line
					(at 0 -11.43 0)
					(length 5.08)
					(name "IO_L2P_T0_16"
						(effects
							(font
								(size 1.27 1.27)
							)
						)
					)
					(number "E23"
						(effects
							(font
								(size 1.27 1.27)
							)
						)
					)
				)
				(pin bidirectional line
					(at 0 -13.97 0)
					(length 5.08)
					(name "IO_L2N_T0_16"
						(effects
							(font
								(size 1.27 1.27)
							)
						)
					)
					(number "D23"
						(effects
							(font
								(size 1.27 1.27)
							)
						)
					)
				)
				(pin bidirectional line
					(at 0 -16.51 0)
					(length 5.08)
					(name "IO_L3P_T0_DQS_16"
						(effects
							(font
								(size 1.27 1.27)
							)
						)
					)
					(number "F25"
						(effects
							(font
								(size 1.27 1.27)
							)
						)
					)
				)
				(pin bidirectional line
					(at 0 -19.05 0)
					(length 5.08)
					(name "IO_L3N_T0_DQS_16"
						(effects
							(font
								(size 1.27 1.27)
							)
						)
					)
					(number "E25"
						(effects
							(font
								(size 1.27 1.27)
							)
						)
					)
				)
				(pin bidirectional line
					(at 0 -21.59 0)
					(length 5.08)
					(name "IO_L4P_T0_16"
						(effects
							(font
								(size 1.27 1.27)
							)
						)
					)
					(number "E24"
						(effects
							(font
								(size 1.27 1.27)
							)
						)
					)
				)
				(pin bidirectional line
					(at 0 -24.13 0)
					(length 5.08)
					(name "IO_L4N_T0_16"
						(effects
							(font
								(size 1.27 1.27)
							)
						)
					)
					(number "D24"
						(effects
							(font
								(size 1.27 1.27)
							)
						)
					)
				)
				(pin bidirectional line
					(at 0 -26.67 0)
					(length 5.08)
					(name "IO_L5P_T0_16"
						(effects
							(font
								(size 1.27 1.27)
							)
						)
					)
					(number "F26"
						(effects
							(font
								(size 1.27 1.27)
							)
						)
					)
				)
				(pin bidirectional line
					(at 0 -29.21 0)
					(length 5.08)
					(name "IO_L5N_T0_16"
						(effects
							(font
								(size 1.27 1.27)
							)
						)
					)
					(number "E26"
						(effects
							(font
								(size 1.27 1.27)
							)
						)
					)
				)
				(pin bidirectional line
					(at 0 -31.75 0)
					(length 5.08)
					(name "IO_L6P_T0_16"
						(effects
							(font
								(size 1.27 1.27)
							)
						)
					)
					(number "G23"
						(effects
							(font
								(size 1.27 1.27)
							)
						)
					)
				)
				(pin bidirectional line
					(at 0 -34.29 0)
					(length 5.08)
					(name "IO_L6N_T0_VREF_16"
						(effects
							(font
								(size 1.27 1.27)
							)
						)
					)
					(number "G24"
						(effects
							(font
								(size 1.27 1.27)
							)
						)
					)
				)
				(pin bidirectional line
					(at 0 -36.83 0)
					(length 5.08)
					(name "IO_L7P_T1_16"
						(effects
							(font
								(size 1.27 1.27)
							)
						)
					)
					(number "B27"
						(effects
							(font
								(size 1.27 1.27)
							)
						)
					)
				)
				(pin bidirectional line
					(at 0 -39.37 0)
					(length 5.08)
					(name "IO_L7N_T1_16"
						(effects
							(font
								(size 1.27 1.27)
							)
						)
					)
					(number "A27"
						(effects
							(font
								(size 1.27 1.27)
							)
						)
					)
				)
				(pin bidirectional line
					(at 0 -41.91 0)
					(length 5.08)
					(name "IO_L8P_T1_16"
						(effects
							(font
								(size 1.27 1.27)
							)
						)
					)
					(number "C24"
						(effects
							(font
								(size 1.27 1.27)
							)
						)
					)
				)
				(pin bidirectional line
					(at 0 -44.45 0)
					(length 5.08)
					(name "IO_L8N_T1_16"
						(effects
							(font
								(size 1.27 1.27)
							)
						)
					)
					(number "B24"
						(effects
							(font
								(size 1.27 1.27)
							)
						)
					)
				)
				(pin bidirectional line
					(at 0 -46.99 0)
					(length 5.08)
					(name "IO_L9P_T1_DQS_16"
						(effects
							(font
								(size 1.27 1.27)
							)
						)
					)
					(number "B28"
						(effects
							(font
								(size 1.27 1.27)
							)
						)
					)
				)
				(pin bidirectional line
					(at 0 -49.53 0)
					(length 5.08)
					(name "IO_L9N_T1_DQS_16"
						(effects
							(font
								(size 1.27 1.27)
							)
						)
					)
					(number "A28"
						(effects
							(font
								(size 1.27 1.27)
							)
						)
					)
				)
				(pin bidirectional line
					(at 0 -52.07 0)
					(length 5.08)
					(name "IO_L10P_T1_16"
						(effects
							(font
								(size 1.27 1.27)
							)
						)
					)
					(number "A25"
						(effects
							(font
								(size 1.27 1.27)
							)
						)
					)
				)
				(pin bidirectional line
					(at 0 -54.61 0)
					(length 5.08)
					(name "IO_L10N_T1_16"
						(effects
							(font
								(size 1.27 1.27)
							)
						)
					)
					(number "A26"
						(effects
							(font
								(size 1.27 1.27)
							)
						)
					)
				)
				(pin bidirectional line
					(at 0 -57.15 0)
					(length 5.08)
					(name "IO_L11P_T1_SRCC_16"
						(effects
							(font
								(size 1.27 1.27)
							)
						)
					)
					(number "D26"
						(effects
							(font
								(size 1.27 1.27)
							)
						)
					)
				)
				(pin bidirectional line
					(at 0 -59.69 0)
					(length 5.08)
					(name "IO_L11N_T1_SRCC_16"
						(effects
							(font
								(size 1.27 1.27)
							)
						)
					)
					(number "C26"
						(effects
							(font
								(size 1.27 1.27)
							)
						)
					)
				)
				(pin bidirectional line
					(at 0 -62.23 0)
					(length 5.08)
					(name "IO_L12P_T1_MRCC_16"
						(effects
							(font
								(size 1.27 1.27)
							)
						)
					)
					(number "C25"
						(effects
							(font
								(size 1.27 1.27)
							)
						)
					)
				)
				(pin bidirectional line
					(at 0 -64.77 0)
					(length 5.08)
					(name "IO_L12N_T1_MRCC_16"
						(effects
							(font
								(size 1.27 1.27)
							)
						)
					)
					(number "B25"
						(effects
							(font
								(size 1.27 1.27)
							)
						)
					)
				)
				(pin bidirectional line
					(at 0 -67.31 0)
					(length 5.08)
					(name "IO_L13P_T2_MRCC_16"
						(effects
							(font
								(size 1.27 1.27)
							)
						)
					)
					(number "D27"
						(effects
							(font
								(size 1.27 1.27)
							)
						)
					)
				)
				(pin bidirectional line
					(at 0 -69.85 0)
					(length 5.08)
					(name "IO_L13N_T2_MRCC_16"
						(effects
							(font
								(size 1.27 1.27)
							)
						)
					)
					(number "C27"
						(effects
							(font
								(size 1.27 1.27)
							)
						)
					)
				)
				(pin bidirectional line
					(at 0 -72.39 0)
					(length 5.08)
					(name "IO_L14P_T2_SRCC_16"
						(effects
							(font
								(size 1.27 1.27)
							)
						)
					)
					(number "E28"
						(effects
							(font
								(size 1.27 1.27)
							)
						)
					)
				)
				(pin bidirectional line
					(at 0 -74.93 0)
					(length 5.08)
					(name "IO_L14N_T2_SRCC_16"
						(effects
							(font
								(size 1.27 1.27)
							)
						)
					)
					(number "D28"
						(effects
							(font
								(size 1.27 1.27)
							)
						)
					)
				)
				(pin bidirectional line
					(at 0 -77.47 0)
					(length 5.08)
					(name "IO_L15P_T2_DQS_16"
						(effects
							(font
								(size 1.27 1.27)
							)
						)
					)
					(number "C29"
						(effects
							(font
								(size 1.27 1.27)
							)
						)
					)
				)
				(pin bidirectional line
					(at 0 -80.01 0)
					(length 5.08)
					(name "IO_L15N_T2_DQS_16"
						(effects
							(font
								(size 1.27 1.27)
							)
						)
					)
					(number "B29"
						(effects
							(font
								(size 1.27 1.27)
							)
						)
					)
				)
				(pin bidirectional line
					(at 0 -82.55 0)
					(length 5.08)
					(name "IO_L16P_T2_16"
						(effects
							(font
								(size 1.27 1.27)
							)
						)
					)
					(number "D29"
						(effects
							(font
								(size 1.27 1.27)
							)
						)
					)
				)
				(pin bidirectional line
					(at 0 -85.09 0)
					(length 5.08)
					(name "IO_L16N_T2_16"
						(effects
							(font
								(size 1.27 1.27)
							)
						)
					)
					(number "C30"
						(effects
							(font
								(size 1.27 1.27)
							)
						)
					)
				)
				(pin bidirectional line
					(at 0 -87.63 0)
					(length 5.08)
					(name "IO_L17P_T2_16"
						(effects
							(font
								(size 1.27 1.27)
							)
						)
					)
					(number "B30"
						(effects
							(font
								(size 1.27 1.27)
							)
						)
					)
				)
				(pin bidirectional line
					(at 0 -90.17 0)
					(length 5.08)
					(name "IO_L17N_T2_16"
						(effects
							(font
								(size 1.27 1.27)
							)
						)
					)
					(number "A30"
						(effects
							(font
								(size 1.27 1.27)
							)
						)
					)
				)
				(pin bidirectional line
					(at 0 -92.71 0)
					(length 5.08)
					(name "IO_L18P_T2_16"
						(effects
							(font
								(size 1.27 1.27)
							)
						)
					)
					(number "E29"
						(effects
							(font
								(size 1.27 1.27)
							)
						)
					)
				)
				(pin bidirectional line
					(at 0 -95.25 0)
					(length 5.08)
					(name "IO_L18N_T2_16"
						(effects
							(font
								(size 1.27 1.27)
							)
						)
					)
					(number "E30"
						(effects
							(font
								(size 1.27 1.27)
							)
						)
					)
				)
				(pin bidirectional line
					(at 0 -97.79 0)
					(length 5.08)
					(name "IO_L19P_T3_16"
						(effects
							(font
								(size 1.27 1.27)
							)
						)
					)
					(number "H24"
						(effects
							(font
								(size 1.27 1.27)
							)
						)
					)
				)
				(pin bidirectional line
					(at 0 -100.33 0)
					(length 5.08)
					(name "IO_L19N_T3_VREF_16"
						(effects
							(font
								(size 1.27 1.27)
							)
						)
					)
					(number "H25"
						(effects
							(font
								(size 1.27 1.27)
							)
						)
					)
				)
				(pin bidirectional line
					(at 0 -102.87 0)
					(length 5.08)
					(name "IO_L20P_T3_16"
						(effects
							(font
								(size 1.27 1.27)
							)
						)
					)
					(number "G28"
						(effects
							(font
								(size 1.27 1.27)
							)
						)
					)
				)
				(pin bidirectional line
					(at 0 -105.41 0)
					(length 5.08)
					(name "IO_L20N_T3_16"
						(effects
							(font
								(size 1.27 1.27)
							)
						)
					)
					(number "F28"
						(effects
							(font
								(size 1.27 1.27)
							)
						)
					)
				)
				(pin bidirectional line
					(at 0 -107.95 0)
					(length 5.08)
					(name "IO_L21P_T3_DQS_16"
						(effects
							(font
								(size 1.27 1.27)
							)
						)
					)
					(number "G27"
						(effects
							(font
								(size 1.27 1.27)
							)
						)
					)
				)
				(pin bidirectional line
					(at 0 -110.49 0)
					(length 5.08)
					(name "IO_L21N_T3_DQS_16"
						(effects
							(font
								(size 1.27 1.27)
							)
						)
					)
					(number "F27"
						(effects
							(font
								(size 1.27 1.27)
							)
						)
					)
				)
				(pin bidirectional line
					(at 0 -113.03 0)
					(length 5.08)
					(name "IO_L22P_T3_16"
						(effects
							(font
								(size 1.27 1.27)
							)
						)
					)
					(number "G29"
						(effects
							(font
								(size 1.27 1.27)
							)
						)
					)
				)
				(pin bidirectional line
					(at 0 -115.57 0)
					(length 5.08)
					(name "IO_L22N_T3_16"
						(effects
							(font
								(size 1.27 1.27)
							)
						)
					)
					(number "F30"
						(effects
							(font
								(size 1.27 1.27)
							)
						)
					)
				)
				(pin bidirectional line
					(at 0 -118.11 0)
					(length 5.08)
					(name "IO_L23P_T3_16"
						(effects
							(font
								(size 1.27 1.27)
							)
						)
					)
					(number "H26"
						(effects
							(font
								(size 1.27 1.27)
							)
						)
					)
				)
				(pin bidirectional line
					(at 0 -120.65 0)
					(length 5.08)
					(name "IO_L23N_T3_16"
						(effects
							(font
								(size 1.27 1.27)
							)
						)
					)
					(number "H27"
						(effects
							(font
								(size 1.27 1.27)
							)
						)
					)
				)
				(pin bidirectional line
					(at 0 -123.19 0)
					(length 5.08)
					(name "IO_L24P_T3_16"
						(effects
							(font
								(size 1.27 1.27)
							)
						)
					)
					(number "H30"
						(effects
							(font
								(size 1.27 1.27)
							)
						)
					)
				)
				(pin bidirectional line
					(at 0 -125.73 0)
					(length 5.08)
					(name "IO_L24N_T3_16"
						(effects
							(font
								(size 1.27 1.27)
							)
						)
					)
					(number "G30"
						(effects
							(font
								(size 1.27 1.27)
							)
						)
					)
				)
				(pin bidirectional line
					(at 0 -128.27 0)
					(length 5.08)
					(name "IO_25_16"
						(effects
							(font
								(size 1.27 1.27)
							)
						)
					)
					(number "G25"
						(effects
							(font
								(size 1.27 1.27)
							)
						)
					)
				)
				(pin bidirectional line
					(at 54.61 0 180)
					(length 5.08)
					(name "VCCO_17"
						(effects
							(font
								(size 1.27 1.27)
							)
						)
					)
					(number "A19"
						(effects
							(font
								(size 1.27 1.27)
							)
						)
					)
				)
				(pin passive line
					(at 54.61 0 180)
					(length 5.08)
					(hide yes)
					(name "VCCO_17"
						(effects
							(font
								(size 1.27 1.27)
							)
						)
					)
					(number "B16"
						(effects
							(font
								(size 1.27 1.27)
							)
						)
					)
				)
				(pin passive line
					(at 54.61 0 180)
					(length 5.08)
					(hide yes)
					(name "VCCO_17"
						(effects
							(font
								(size 1.27 1.27)
							)
						)
					)
					(number "D20"
						(effects
							(font
								(size 1.27 1.27)
							)
						)
					)
				)
				(pin passive line
					(at 54.61 0 180)
					(length 5.08)
					(hide yes)
					(name "VCCO_17"
						(effects
							(font
								(size 1.27 1.27)
							)
						)
					)
					(number "E17"
						(effects
							(font
								(size 1.27 1.27)
							)
						)
					)
				)
				(pin passive line
					(at 54.61 0 180)
					(length 5.08)
					(hide yes)
					(name "VCCO_17"
						(effects
							(font
								(size 1.27 1.27)
							)
						)
					)
					(number "G21"
						(effects
							(font
								(size 1.27 1.27)
							)
						)
					)
				)
				(pin passive line
					(at 54.61 0 180)
					(length 5.08)
					(hide yes)
					(name "VCCO_17"
						(effects
							(font
								(size 1.27 1.27)
							)
						)
					)
					(number "H18"
						(effects
							(font
								(size 1.27 1.27)
							)
						)
					)
				)
				(pin passive line
					(at 54.61 0 180)
					(length 5.08)
					(hide yes)
					(name "VCCO_17"
						(effects
							(font
								(size 1.27 1.27)
							)
						)
					)
					(number "L19"
						(effects
							(font
								(size 1.27 1.27)
							)
						)
					)
				)
				(pin bidirectional line
					(at 54.61 -3.81 180)
					(length 5.08)
					(name "IO_0_17"
						(effects
							(font
								(size 1.27 1.27)
							)
						)
					)
					(number "G19"
						(effects
							(font
								(size 1.27 1.27)
							)
						)
					)
				)
				(pin bidirectional line
					(at 54.61 -6.35 180)
					(length 5.08)
					(name "IO_L1P_T0_17"
						(effects
							(font
								(size 1.27 1.27)
							)
						)
					)
					(number "K18"
						(effects
							(font
								(size 1.27 1.27)
							)
						)
					)
				)
				(pin bidirectional line
					(at 54.61 -8.89 180)
					(length 5.08)
					(name "IO_L1N_T0_17"
						(effects
							(font
								(size 1.27 1.27)
							)
						)
					)
					(number "J18"
						(effects
							(font
								(size 1.27 1.27)
							)
						)
					)
				)
				(pin bidirectional line
					(at 54.61 -11.43 180)
					(length 5.08)
					(name "IO_L2P_T0_17"
						(effects
							(font
								(size 1.27 1.27)
							)
						)
					)
					(number "H20"
						(effects
							(font
								(size 1.27 1.27)
							)
						)
					)
				)
				(pin bidirectional line
					(at 54.61 -13.97 180)
					(length 5.08)
					(name "IO_L2N_T0_17"
						(effects
							(font
								(size 1.27 1.27)
							)
						)
					)
					(number "G20"
						(effects
							(font
								(size 1.27 1.27)
							)
						)
					)
				)
				(pin bidirectional line
					(at 54.61 -16.51 180)
					(length 5.08)
					(name "IO_L3P_T0_DQS_17"
						(effects
							(font
								(size 1.27 1.27)
							)
						)
					)
					(number "J17"
						(effects
							(font
								(size 1.27 1.27)
							)
						)
					)
				)
				(pin bidirectional line
					(at 54.61 -19.05 180)
					(length 5.08)
					(name "IO_L3N_T0_DQS_17"
						(effects
							(font
								(size 1.27 1.27)
							)
						)
					)
					(number "H17"
						(effects
							(font
								(size 1.27 1.27)
							)
						)
					)
				)
				(pin bidirectional line
					(at 54.61 -21.59 180)
					(length 5.08)
					(name "IO_L4P_T0_17"
						(effects
							(font
								(size 1.27 1.27)
							)
						)
					)
					(number "J19"
						(effects
							(font
								(size 1.27 1.27)
							)
						)
					)
				)
				(pin bidirectional line
					(at 54.61 -24.13 180)
					(length 5.08)
					(name "IO_L4N_T0_17"
						(effects
							(font
								(size 1.27 1.27)
							)
						)
					)
					(number "H19"
						(effects
							(font
								(size 1.27 1.27)
							)
						)
					)
				)
				(pin bidirectional line
					(at 54.61 -26.67 180)
					(length 5.08)
					(name "IO_L5P_T0_17"
						(effects
							(font
								(size 1.27 1.27)
							)
						)
					)
					(number "L17"
						(effects
							(font
								(size 1.27 1.27)
							)
						)
					)
				)
				(pin bidirectional line
					(at 54.61 -29.21 180)
					(length 5.08)
					(name "IO_L5N_T0_17"
						(effects
							(font
								(size 1.27 1.27)
							)
						)
					)
					(number "L18"
						(effects
							(font
								(size 1.27 1.27)
							)
						)
					)
				)
				(pin bidirectional line
					(at 54.61 -31.75 180)
					(length 5.08)
					(name "IO_L6P_T0_17"
						(effects
							(font
								(size 1.27 1.27)
							)
						)
					)
					(number "K19"
						(effects
							(font
								(size 1.27 1.27)
							)
						)
					)
				)
				(pin bidirectional line
					(at 54.61 -34.29 180)
					(length 5.08)
					(name "IO_L6N_T0_VREF_17"
						(effects
							(font
								(size 1.27 1.27)
							)
						)
					)
					(number "K20"
						(effects
							(font
								(size 1.27 1.27)
							)
						)
					)
				)
				(pin bidirectional line
					(at 54.61 -36.83 180)
					(length 5.08)
					(name "IO_L7P_T1_17"
						(effects
							(font
								(size 1.27 1.27)
							)
						)
					)
					(number "H21"
						(effects
							(font
								(size 1.27 1.27)
							)
						)
					)
				)
				(pin bidirectional line
					(at 54.61 -39.37 180)
					(length 5.08)
					(name "IO_L7N_T1_17"
						(effects
							(font
								(size 1.27 1.27)
							)
						)
					)
					(number "H22"
						(effects
							(font
								(size 1.27 1.27)
							)
						)
					)
				)
				(pin bidirectional line
					(at 54.61 -41.91 180)
					(length 5.08)
					(name "IO_L8P_T1_17"
						(effects
							(font
								(size 1.27 1.27)
							)
						)
					)
					(number "D21"
						(effects
							(font
								(size 1.27 1.27)
							)
						)
					)
				)
				(pin bidirectional line
					(at 54.61 -44.45 180)
					(length 5.08)
					(name "IO_L8N_T1_17"
						(effects
							(font
								(size 1.27 1.27)
							)
						)
					)
					(number "C21"
						(effects
							(font
								(size 1.27 1.27)
							)
						)
					)
				)
				(pin bidirectional line
					(at 54.61 -46.99 180)
					(length 5.08)
					(name "IO_L9P_T1_DQS_17"
						(effects
							(font
								(size 1.27 1.27)
							)
						)
					)
					(number "G22"
						(effects
							(font
								(size 1.27 1.27)
							)
						)
					)
				)
				(pin bidirectional line
					(at 54.61 -49.53 180)
					(length 5.08)
					(name "IO_L9N_T1_DQS_17"
						(effects
							(font
								(size 1.27 1.27)
							)
						)
					)
					(number "F22"
						(effects
							(font
								(size 1.27 1.27)
							)
						)
					)
				)
				(pin bidirectional line
					(at 54.61 -52.07 180)
					(length 5.08)
					(name "IO_L10P_T1_17"
						(effects
							(font
								(size 1.27 1.27)
							)
						)
					)
					(number "D22"
						(effects
							(font
								(size 1.27 1.27)
							)
						)
					)
				)
				(pin bidirectional line
					(at 54.61 -54.61 180)
					(length 5.08)
					(name "IO_L10N_T1_17"
						(effects
							(font
								(size 1.27 1.27)
							)
						)
					)
					(number "C22"
						(effects
							(font
								(size 1.27 1.27)
							)
						)
					)
				)
				(pin bidirectional line
					(at 54.61 -57.15 180)
					(length 5.08)
					(name "IO_L11P_T1_SRCC_17"
						(effects
							(font
								(size 1.27 1.27)
							)
						)
					)
					(number "F21"
						(effects
							(font
								(size 1.27 1.27)
							)
						)
					)
				)
				(pin bidirectional line
					(at 54.61 -59.69 180)
					(length 5.08)
					(name "IO_L11N_T1_SRCC_17"
						(effects
							(font
								(size 1.27 1.27)
							)
						)
					)
					(number "E21"
						(effects
							(font
								(size 1.27 1.27)
							)
						)
					)
				)
				(pin bidirectional line
					(at 54.61 -62.23 180)
					(length 5.08)
					(name "IO_L12P_T1_MRCC_17"
						(effects
							(font
								(size 1.27 1.27)
							)
						)
					)
					(number "F20"
						(effects
							(font
								(size 1.27 1.27)
							)
						)
					)
				)
				(pin bidirectional line
					(at 54.61 -64.77 180)
					(length 5.08)
					(name "IO_L12N_T1_MRCC_17"
						(effects
							(font
								(size 1.27 1.27)
							)
						)
					)
					(number "E20"
						(effects
							(font
								(size 1.27 1.27)
							)
						)
					)
				)
				(pin bidirectional line
					(at 54.61 -67.31 180)
					(length 5.08)
					(name "IO_L13P_T2_MRCC_17"
						(effects
							(font
								(size 1.27 1.27)
							)
						)
					)
					(number "D17"
						(effects
							(font
								(size 1.27 1.27)
							)
						)
					)
				)
				(pin bidirectional line
					(at 54.61 -69.85 180)
					(length 5.08)
					(name "IO_L13N_T2_MRCC_17"
						(effects
							(font
								(size 1.27 1.27)
							)
						)
					)
					(number "D18"
						(effects
							(font
								(size 1.27 1.27)
							)
						)
					)
				)
				(pin bidirectional line
					(at 54.61 -72.39 180)
					(length 5.08)
					(name "IO_L14P_T2_SRCC_17"
						(effects
							(font
								(size 1.27 1.27)
							)
						)
					)
					(number "E19"
						(effects
							(font
								(size 1.27 1.27)
							)
						)
					)
				)
				(pin bidirectional line
					(at 54.61 -74.93 180)
					(length 5.08)
					(name "IO_L14N_T2_SRCC_17"
						(effects
							(font
								(size 1.27 1.27)
							)
						)
					)
					(number "D19"
						(effects
							(font
								(size 1.27 1.27)
							)
						)
					)
				)
				(pin bidirectional line
					(at 54.61 -77.47 180)
					(length 5.08)
					(name "IO_L15P_T2_DQS_17"
						(effects
							(font
								(size 1.27 1.27)
							)
						)
					)
					(number "D16"
						(effects
							(font
								(size 1.27 1.27)
							)
						)
					)
				)
				(pin bidirectional line
					(at 54.61 -80.01 180)
					(length 5.08)
					(name "IO_L15N_T2_DQS_17"
						(effects
							(font
								(size 1.27 1.27)
							)
						)
					)
					(number "C16"
						(effects
							(font
								(size 1.27 1.27)
							)
						)
					)
				)
				(pin bidirectional line
					(at 54.61 -82.55 180)
					(length 5.08)
					(name "IO_L16P_T2_17"
						(effects
							(font
								(size 1.27 1.27)
							)
						)
					)
					(number "G18"
						(effects
							(font
								(size 1.27 1.27)
							)
						)
					)
				)
				(pin bidirectional line
					(at 54.61 -85.09 180)
					(length 5.08)
					(name "IO_L16N_T2_17"
						(effects
							(font
								(size 1.27 1.27)
							)
						)
					)
					(number "F18"
						(effects
							(font
								(size 1.27 1.27)
							)
						)
					)
				)
				(pin bidirectional line
					(at 54.61 -87.63 180)
					(length 5.08)
					(name "IO_L17P_T2_17"
						(effects
							(font
								(size 1.27 1.27)
							)
						)
					)
					(number "C17"
						(effects
							(font
								(size 1.27 1.27)
							)
						)
					)
				)
				(pin bidirectional line
					(at 54.61 -90.17 180)
					(length 5.08)
					(name "IO_L17N_T2_17"
						(effects
							(font
								(size 1.27 1.27)
							)
						)
					)
					(number "B17"
						(effects
							(font
								(size 1.27 1.27)
							)
						)
					)
				)
				(pin bidirectional line
					(at 54.61 -92.71 180)
					(length 5.08)
					(name "IO_L18P_T2_17"
						(effects
							(font
								(size 1.27 1.27)
							)
						)
					)
					(number "G17"
						(effects
							(font
								(size 1.27 1.27)
							)
						)
					)
				)
				(pin bidirectional line
					(at 54.61 -95.25 180)
					(length 5.08)
					(name "IO_L18N_T2_17"
						(effects
							(font
								(size 1.27 1.27)
							)
						)
					)
					(number "F17"
						(effects
							(font
								(size 1.27 1.27)
							)
						)
					)
				)
				(pin bidirectional line
					(at 54.61 -97.79 180)
					(length 5.08)
					(name "IO_L19P_T3_17"
						(effects
							(font
								(size 1.27 1.27)
							)
						)
					)
					(number "C20"
						(effects
							(font
								(size 1.27 1.27)
							)
						)
					)
				)
				(pin bidirectional line
					(at 54.61 -100.33 180)
					(length 5.08)
					(name "IO_L19N_T3_VREF_17"
						(effects
							(font
								(size 1.27 1.27)
							)
						)
					)
					(number "B20"
						(effects
							(font
								(size 1.27 1.27)
							)
						)
					)
				)
				(pin bidirectional line
					(at 54.61 -102.87 180)
					(length 5.08)
					(name "IO_L20P_T3_17"
						(effects
							(font
								(size 1.27 1.27)
							)
						)
					)
					(number "A16"
						(effects
							(font
								(size 1.27 1.27)
							)
						)
					)
				)
				(pin bidirectional line
					(at 54.61 -105.41 180)
					(length 5.08)
					(name "IO_L20N_T3_17"
						(effects
							(font
								(size 1.27 1.27)
							)
						)
					)
					(number "A17"
						(effects
							(font
								(size 1.27 1.27)
							)
						)
					)
				)
				(pin bidirectional line
					(at 54.61 -107.95 180)
					(length 5.08)
					(name "IO_L21P_T3_DQS_17"
						(effects
							(font
								(size 1.27 1.27)
							)
						)
					)
					(number "A20"
						(effects
							(font
								(size 1.27 1.27)
							)
						)
					)
				)
				(pin bidirectional line
					(at 54.61 -110.49 180)
					(length 5.08)
					(name "IO_L21N_T3_DQS_17"
						(effects
							(font
								(size 1.27 1.27)
							)
						)
					)
					(number "A21"
						(effects
							(font
								(size 1.27 1.27)
							)
						)
					)
				)
				(pin bidirectional line
					(at 54.61 -113.03 180)
					(length 5.08)
					(name "IO_L22P_T3_17"
						(effects
							(font
								(size 1.27 1.27)
							)
						)
					)
					(number "B18"
						(effects
							(font
								(size 1.27 1.27)
							)
						)
					)
				)
				(pin bidirectional line
					(at 54.61 -115.57 180)
					(length 5.08)
					(name "IO_L22N_T3_17"
						(effects
							(font
								(size 1.27 1.27)
							)
						)
					)
					(number "A18"
						(effects
							(font
								(size 1.27 1.27)
							)
						)
					)
				)
				(pin bidirectional line
					(at 54.61 -118.11 180)
					(length 5.08)
					(name "IO_L23P_T3_17"
						(effects
							(font
								(size 1.27 1.27)
							)
						)
					)
					(number "B22"
						(effects
							(font
								(size 1.27 1.27)
							)
						)
					)
				)
				(pin bidirectional line
					(at 54.61 -120.65 180)
					(length 5.08)
					(name "IO_L23N_T3_17"
						(effects
							(font
								(size 1.27 1.27)
							)
						)
					)
					(number "A22"
						(effects
							(font
								(size 1.27 1.27)
							)
						)
					)
				)
				(pin bidirectional line
					(at 54.61 -123.19 180)
					(length 5.08)
					(name "IO_L24P_T3_17"
						(effects
							(font
								(size 1.27 1.27)
							)
						)
					)
					(number "C19"
						(effects
							(font
								(size 1.27 1.27)
							)
						)
					)
				)
				(pin bidirectional line
					(at 54.61 -125.73 180)
					(length 5.08)
					(name "IO_L24N_T3_17"
						(effects
							(font
								(size 1.27 1.27)
							)
						)
					)
					(number "B19"
						(effects
							(font
								(size 1.27 1.27)
							)
						)
					)
				)
				(pin bidirectional line
					(at 54.61 -128.27 180)
					(length 5.08)
					(name "IO_25_17"
						(effects
							(font
								(size 1.27 1.27)
							)
						)
					)
					(number "E18"
						(effects
							(font
								(size 1.27 1.27)
							)
						)
					)
				)
			)
			(symbol "XC7K410T-2FFG900I_1_4_1"
				(rectangle
					(start 5.08 5.08)
					(end 48.26 -130.81)
					(stroke
						(width 0.254)
						(type default)
					)
					(fill
						(type background)
					)
				)
				(text "BANK 18"
					(at 17.78 2.54 0)
					(effects
						(font
							(size 1.27 1.27)
							(thickness 0.15)
						)
						(justify left bottom)
					)
				)
				(text "BANK 32"
					(at 29.21 2.54 0)
					(effects
						(font
							(size 1.27 1.27)
							(thickness 0.15)
						)
						(justify left bottom)
					)
				)
				(pin bidirectional line
					(at 0 0 0)
					(length 5.08)
					(name "VCCO_18"
						(effects
							(font
								(size 1.27 1.27)
							)
						)
					)
					(number "C13"
						(effects
							(font
								(size 1.27 1.27)
							)
						)
					)
				)
				(pin passive line
					(at 0 0 0)
					(length 5.08)
					(hide yes)
					(name "VCCO_18"
						(effects
							(font
								(size 1.27 1.27)
							)
						)
					)
					(number "D10"
						(effects
							(font
								(size 1.27 1.27)
							)
						)
					)
				)
				(pin passive line
					(at 0 0 0)
					(length 5.08)
					(hide yes)
					(name "VCCO_18"
						(effects
							(font
								(size 1.27 1.27)
							)
						)
					)
					(number "F14"
						(effects
							(font
								(size 1.27 1.27)
							)
						)
					)
				)
				(pin passive line
					(at 0 0 0)
					(length 5.08)
					(hide yes)
					(name "VCCO_18"
						(effects
							(font
								(size 1.27 1.27)
							)
						)
					)
					(number "G11"
						(effects
							(font
								(size 1.27 1.27)
							)
						)
					)
				)
				(pin passive line
					(at 0 0 0)
					(length 5.08)
					(hide yes)
					(name "VCCO_18"
						(effects
							(font
								(size 1.27 1.27)
							)
						)
					)
					(number "J15"
						(effects
							(font
								(size 1.27 1.27)
							)
						)
					)
				)
				(pin passive line
					(at 0 0 0)
					(length 5.08)
					(hide yes)
					(name "VCCO_18"
						(effects
							(font
								(size 1.27 1.27)
							)
						)
					)
					(number "K12"
						(effects
							(font
								(size 1.27 1.27)
							)
						)
					)
				)
				(pin bidirectional line
					(at 0 -3.81 0)
					(length 5.08)
					(name "IO_0_18"
						(effects
							(font
								(size 1.27 1.27)
							)
						)
					)
					(number "G12"
						(effects
							(font
								(size 1.27 1.27)
							)
						)
					)
				)
				(pin bidirectional line
					(at 0 -6.35 0)
					(length 5.08)
					(name "IO_L1P_T0_18"
						(effects
							(font
								(size 1.27 1.27)
							)
						)
					)
					(number "L16"
						(effects
							(font
								(size 1.27 1.27)
							)
						)
					)
				)
				(pin bidirectional line
					(at 0 -8.89 0)
					(length 5.08)
					(name "IO_L1N_T0_18"
						(effects
							(font
								(size 1.27 1.27)
							)
						)
					)
					(number "K16"
						(effects
							(font
								(size 1.27 1.27)
							)
						)
					)
				)
				(pin bidirectional line
					(at 0 -11.43 0)
					(length 5.08)
					(name "IO_L2P_T0_18"
						(effects
							(font
								(size 1.27 1.27)
							)
						)
					)
					(number "L15"
						(effects
							(font
								(size 1.27 1.27)
							)
						)
					)
				)
				(pin bidirectional line
					(at 0 -13.97 0)
					(length 5.08)
					(name "IO_L2N_T0_18"
						(effects
							(font
								(size 1.27 1.27)
							)
						)
					)
					(number "K15"
						(effects
							(font
								(size 1.27 1.27)
							)
						)
					)
				)
				(pin bidirectional line
					(at 0 -16.51 0)
					(length 5.08)
					(name "IO_L3P_T0_DQS_18"
						(effects
							(font
								(size 1.27 1.27)
							)
						)
					)
					(number "L12"
						(effects
							(font
								(size 1.27 1.27)
							)
						)
					)
				)
				(pin bidirectional line
					(at 0 -19.05 0)
					(length 5.08)
					(name "IO_L3N_T0_DQS_18"
						(effects
							(font
								(size 1.27 1.27)
							)
						)
					)
					(number "L13"
						(effects
							(font
								(size 1.27 1.27)
							)
						)
					)
				)
				(pin bidirectional line
					(at 0 -21.59 0)
					(length 5.08)
					(name "IO_L4P_T0_18"
						(effects
							(font
								(size 1.27 1.27)
							)
						)
					)
					(number "K13"
						(effects
							(font
								(size 1.27 1.27)
							)
						)
					)
				)
				(pin bidirectional line
					(at 0 -24.13 0)
					(length 5.08)
					(name "IO_L4N_T0_18"
						(effects
							(font
								(size 1.27 1.27)
							)
						)
					)
					(number "J13"
						(effects
							(font
								(size 1.27 1.27)
							)
						)
					)
				)
				(pin bidirectional line
					(at 0 -26.67 0)
					(length 5.08)
					(name "IO_L5P_T0_18"
						(effects
							(font
								(size 1.27 1.27)
							)
						)
					)
					(number "K14"
						(effects
							(font
								(size 1.27 1.27)
							)
						)
					)
				)
				(pin bidirectional line
					(at 0 -29.21 0)
					(length 5.08)
					(name "IO_L5N_T0_18"
						(effects
							(font
								(size 1.27 1.27)
							)
						)
					)
					(number "J14"
						(effects
							(font
								(size 1.27 1.27)
							)
						)
					)
				)
				(pin bidirectional line
					(at 0 -31.75 0)
					(length 5.08)
					(name "IO_L6P_T0_18"
						(effects
							(font
								(size 1.27 1.27)
							)
						)
					)
					(number "L11"
						(effects
							(font
								(size 1.27 1.27)
							)
						)
					)
				)
				(pin bidirectional line
					(at 0 -34.29 0)
					(length 5.08)
					(name "IO_L6N_T0_VREF_18"
						(effects
							(font
								(size 1.27 1.27)
							)
						)
					)
					(number "K11"
						(effects
							(font
								(size 1.27 1.27)
							)
						)
					)
				)
				(pin bidirectional line
					(at 0 -36.83 0)
					(length 5.08)
					(name "IO_L7P_T1_18"
						(effects
							(font
								(size 1.27 1.27)
							)
						)
					)
					(number "H15"
						(effects
							(font
								(size 1.27 1.27)
							)
						)
					)
				)
				(pin bidirectional line
					(at 0 -39.37 0)
					(length 5.08)
					(name "IO_L7N_T1_18"
						(effects
							(font
								(size 1.27 1.27)
							)
						)
					)
					(number "G15"
						(effects
							(font
								(size 1.27 1.27)
							)
						)
					)
				)
				(pin bidirectional line
					(at 0 -41.91 0)
					(length 5.08)
					(name "IO_L8P_T1_18"
						(effects
							(font
								(size 1.27 1.27)
							)
						)
					)
					(number "J11"
						(effects
							(font
								(size 1.27 1.27)
							)
						)
					)
				)
				(pin bidirectional line
					(at 0 -44.45 0)
					(length 5.08)
					(name "IO_L8N_T1_18"
						(effects
							(font
								(size 1.27 1.27)
							)
						)
					)
					(number "J12"
						(effects
							(font
								(size 1.27 1.27)
							)
						)
					)
				)
				(pin bidirectional line
					(at 0 -46.99 0)
					(length 5.08)
					(name "IO_L9P_T1_DQS_18"
						(effects
							(font
								(size 1.27 1.27)
							)
						)
					)
					(number "J16"
						(effects
							(font
								(size 1.27 1.27)
							)
						)
					)
				)
				(pin bidirectional line
					(at 0 -49.53 0)
					(length 5.08)
					(name "IO_L9N_T1_DQS_18"
						(effects
							(font
								(size 1.27 1.27)
							)
						)
					)
					(number "H16"
						(effects
							(font
								(size 1.27 1.27)
							)
						)
					)
				)
				(pin bidirectional line
					(at 0 -52.07 0)
					(length 5.08)
					(name "IO_L10P_T1_18"
						(effects
							(font
								(size 1.27 1.27)
							)
						)
					)
					(number "H11"
						(effects
							(font
								(size 1.27 1.27)
							)
						)
					)
				)
				(pin bidirectional line
					(at 0 -54.61 0)
					(length 5.08)
					(name "IO_L10N_T1_18"
						(effects
							(font
								(size 1.27 1.27)
							)
						)
					)
					(number "H12"
						(effects
							(font
								(size 1.27 1.27)
							)
						)
					)
				)
				(pin bidirectional line
					(at 0 -57.15 0)
					(length 5.08)
					(name "IO_L11P_T1_SRCC_18"
						(effects
							(font
								(size 1.27 1.27)
							)
						)
					)
					(number "H14"
						(effects
							(font
								(size 1.27 1.27)
							)
						)
					)
				)
				(pin bidirectional line
					(at 0 -59.69 0)
					(length 5.08)
					(name "IO_L11N_T1_SRCC_18"
						(effects
							(font
								(size 1.27 1.27)
							)
						)
					)
					(number "G14"
						(effects
							(font
								(size 1.27 1.27)
							)
						)
					)
				)
				(pin bidirectional line
					(at 0 -62.23 0)
					(length 5.08)
					(name "IO_L12P_T1_MRCC_18"
						(effects
							(font
								(size 1.27 1.27)
							)
						)
					)
					(number "G13"
						(effects
							(font
								(size 1.27 1.27)
							)
						)
					)
				)
				(pin bidirectional line
					(at 0 -64.77 0)
					(length 5.08)
					(name "IO_L12N_T1_MRCC_18"
						(effects
							(font
								(size 1.27 1.27)
							)
						)
					)
					(number "F13"
						(effects
							(font
								(size 1.27 1.27)
							)
						)
					)
				)
				(pin bidirectional line
					(at 0 -67.31 0)
					(length 5.08)
					(name "IO_L13P_T2_MRCC_18"
						(effects
							(font
								(size 1.27 1.27)
							)
						)
					)
					(number "D12"
						(effects
							(font
								(size 1.27 1.27)
							)
						)
					)
				)
				(pin bidirectional line
					(at 0 -69.85 0)
					(length 5.08)
					(name "IO_L13N_T2_MRCC_18"
						(effects
							(font
								(size 1.27 1.27)
							)
						)
					)
					(number "D13"
						(effects
							(font
								(size 1.27 1.27)
							)
						)
					)
				)
				(pin bidirectional line
					(at 0 -72.39 0)
					(length 5.08)
					(name "IO_L14P_T2_SRCC_18"
						(effects
							(font
								(size 1.27 1.27)
							)
						)
					)
					(number "F12"
						(effects
							(font
								(size 1.27 1.27)
							)
						)
					)
				)
				(pin bidirectional line
					(at 0 -74.93 0)
					(length 5.08)
					(name "IO_L14N_T2_SRCC_18"
						(effects
							(font
								(size 1.27 1.27)
							)
						)
					)
					(number "E13"
						(effects
							(font
								(size 1.27 1.27)
							)
						)
					)
				)
				(pin bidirectional line
					(at 0 -77.47 0)
					(length 5.08)
					(name "IO_L15P_T2_DQS_18"
						(effects
							(font
								(size 1.27 1.27)
							)
						)
					)
					(number "C12"
						(effects
							(font
								(size 1.27 1.27)
							)
						)
					)
				)
				(pin bidirectional line
					(at 0 -80.01 0)
					(length 5.08)
					(name "IO_L15N_T2_DQS_18"
						(effects
							(font
								(size 1.27 1.27)
							)
						)
					)
					(number "B12"
						(effects
							(font
								(size 1.27 1.27)
							)
						)
					)
				)
				(pin bidirectional line
					(at 0 -82.55 0)
					(length 5.08)
					(name "IO_L16P_T2_18"
						(effects
							(font
								(size 1.27 1.27)
							)
						)
					)
					(number "F11"
						(effects
							(font
								(size 1.27 1.27)
							)
						)
					)
				)
				(pin bidirectional line
					(at 0 -85.09 0)
					(length 5.08)
					(name "IO_L16N_T2_18"
						(effects
							(font
								(size 1.27 1.27)
							)
						)
					)
					(number "E11"
						(effects
							(font
								(size 1.27 1.27)
							)
						)
					)
				)
				(pin bidirectional line
					(at 0 -87.63 0)
					(length 5.08)
					(name "IO_L17P_T2_18"
						(effects
							(font
								(size 1.27 1.27)
							)
						)
					)
					(number "A11"
						(effects
							(font
								(size 1.27 1.27)
							)
						)
					)
				)
				(pin bidirectional line
					(at 0 -90.17 0)
					(length 5.08)
					(name "IO_L17N_T2_18"
						(effects
							(font
								(size 1.27 1.27)
							)
						)
					)
					(number "A12"
						(effects
							(font
								(size 1.27 1.27)
							)
						)
					)
				)
				(pin bidirectional line
					(at 0 -92.71 0)
					(length 5.08)
					(name "IO_L18P_T2_18"
						(effects
							(font
								(size 1.27 1.27)
							)
						)
					)
					(number "D11"
						(effects
							(font
								(size 1.27 1.27)
							)
						)
					)
				)
				(pin bidirectional line
					(at 0 -95.25 0)
					(length 5.08)
					(name "IO_L18N_T2_18"
						(effects
							(font
								(size 1.27 1.27)
							)
						)
					)
					(number "C11"
						(effects
							(font
								(size 1.27 1.27)
							)
						)
					)
				)
				(pin bidirectional line
					(at 0 -97.79 0)
					(length 5.08)
					(name "IO_L19P_T3_18"
						(effects
							(font
								(size 1.27 1.27)
							)
						)
					)
					(number "F15"
						(effects
							(font
								(size 1.27 1.27)
							)
						)
					)
				)
				(pin bidirectional line
					(at 0 -100.33 0)
					(length 5.08)
					(name "IO_L19N_T3_VREF_18"
						(effects
							(font
								(size 1.27 1.27)
							)
						)
					)
					(number "E16"
						(effects
							(font
								(size 1.27 1.27)
							)
						)
					)
				)
				(pin bidirectional line
					(at 0 -102.87 0)
					(length 5.08)
					(name "IO_L20P_T3_18"
						(effects
							(font
								(size 1.27 1.27)
							)
						)
					)
					(number "E14"
						(effects
							(font
								(size 1.27 1.27)
							)
						)
					)
				)
				(pin bidirectional line
					(at 0 -105.41 0)
					(length 5.08)
					(name "IO_L20N_T3_18"
						(effects
							(font
								(size 1.27 1.27)
							)
						)
					)
					(number "E15"
						(effects
							(font
								(size 1.27 1.27)
							)
						)
					)
				)
				(pin bidirectional line
					(at 0 -107.95 0)
					(length 5.08)
					(name "IO_L21P_T3_DQS_18"
						(effects
							(font
								(size 1.27 1.27)
							)
						)
					)
					(number "D14"
						(effects
							(font
								(size 1.27 1.27)
							)
						)
					)
				)
				(pin bidirectional line
					(at 0 -110.49 0)
					(length 5.08)
					(name "IO_L21N_T3_DQS_18"
						(effects
							(font
								(size 1.27 1.27)
							)
						)
					)
					(number "C14"
						(effects
							(font
								(size 1.27 1.27)
							)
						)
					)
				)
				(pin bidirectional line
					(at 0 -113.03 0)
					(length 5.08)
					(name "IO_L22P_T3_18"
						(effects
							(font
								(size 1.27 1.27)
							)
						)
					)
					(number "B13"
						(effects
							(font
								(size 1.27 1.27)
							)
						)
					)
				)
				(pin bidirectional line
					(at 0 -115.57 0)
					(length 5.08)
					(name "IO_L22N_T3_18"
						(effects
							(font
								(size 1.27 1.27)
							)
						)
					)
					(number "A13"
						(effects
							(font
								(size 1.27 1.27)
							)
						)
					)
				)
				(pin bidirectional line
					(at 0 -118.11 0)
					(length 5.08)
					(name "IO_L23P_T3_18"
						(effects
							(font
								(size 1.27 1.27)
							)
						)
					)
					(number "C15"
						(effects
							(font
								(size 1.27 1.27)
							)
						)
					)
				)
				(pin bidirectional line
					(at 0 -120.65 0)
					(length 5.08)
					(name "IO_L23N_T3_18"
						(effects
							(font
								(size 1.27 1.27)
							)
						)
					)
					(number "B15"
						(effects
							(font
								(size 1.27 1.27)
							)
						)
					)
				)
				(pin bidirectional line
					(at 0 -123.19 0)
					(length 5.08)
					(name "IO_L24P_T3_18"
						(effects
							(font
								(size 1.27 1.27)
							)
						)
					)
					(number "B14"
						(effects
							(font
								(size 1.27 1.27)
							)
						)
					)
				)
				(pin bidirectional line
					(at 0 -125.73 0)
					(length 5.08)
					(name "IO_L24N_T3_18"
						(effects
							(font
								(size 1.27 1.27)
							)
						)
					)
					(number "A15"
						(effects
							(font
								(size 1.27 1.27)
							)
						)
					)
				)
				(pin bidirectional line
					(at 0 -128.27 0)
					(length 5.08)
					(name "IO_25_18"
						(effects
							(font
								(size 1.27 1.27)
							)
						)
					)
					(number "F16"
						(effects
							(font
								(size 1.27 1.27)
							)
						)
					)
				)
				(pin bidirectional line
					(at 53.34 0 180)
					(length 5.08)
					(name "VCCO_32"
						(effects
							(font
								(size 1.27 1.27)
							)
						)
					)
					(number "AA19"
						(effects
							(font
								(size 1.27 1.27)
							)
						)
					)
				)
				(pin passive line
					(at 53.34 0 180)
					(length 5.08)
					(hide yes)
					(name "VCCO_32"
						(effects
							(font
								(size 1.27 1.27)
							)
						)
					)
					(number "AB16"
						(effects
							(font
								(size 1.27 1.27)
							)
						)
					)
				)
				(pin passive line
					(at 53.34 0 180)
					(length 5.08)
					(hide yes)
					(name "VCCO_32"
						(effects
							(font
								(size 1.27 1.27)
							)
						)
					)
					(number "AE17"
						(effects
							(font
								(size 1.27 1.27)
							)
						)
					)
				)
				(pin passive line
					(at 53.34 0 180)
					(length 5.08)
					(hide yes)
					(name "VCCO_32"
						(effects
							(font
								(size 1.27 1.27)
							)
						)
					)
					(number "AF14"
						(effects
							(font
								(size 1.27 1.27)
							)
						)
					)
				)
				(pin passive line
					(at 53.34 0 180)
					(length 5.08)
					(hide yes)
					(name "VCCO_32"
						(effects
							(font
								(size 1.27 1.27)
							)
						)
					)
					(number "AH18"
						(effects
							(font
								(size 1.27 1.27)
							)
						)
					)
				)
				(pin passive line
					(at 53.34 0 180)
					(length 5.08)
					(hide yes)
					(name "VCCO_32"
						(effects
							(font
								(size 1.27 1.27)
							)
						)
					)
					(number "AJ15"
						(effects
							(font
								(size 1.27 1.27)
							)
						)
					)
				)
				(pin bidirectional line
					(at 53.34 -3.81 180)
					(length 5.08)
					(name "IO_0_VRN_32"
						(effects
							(font
								(size 1.27 1.27)
							)
						)
					)
					(number "Y14"
						(effects
							(font
								(size 1.27 1.27)
							)
						)
					)
				)
				(pin bidirectional line
					(at 53.34 -6.35 180)
					(length 5.08)
					(name "IO_L1P_T0_32"
						(effects
							(font
								(size 1.27 1.27)
							)
						)
					)
					(number "AK16"
						(effects
							(font
								(size 1.27 1.27)
							)
						)
					)
				)
				(pin bidirectional line
					(at 53.34 -8.89 180)
					(length 5.08)
					(name "IO_L1N_T0_32"
						(effects
							(font
								(size 1.27 1.27)
							)
						)
					)
					(number "AK15"
						(effects
							(font
								(size 1.27 1.27)
							)
						)
					)
				)
				(pin bidirectional line
					(at 53.34 -11.43 180)
					(length 5.08)
					(name "IO_L2P_T0_32"
						(effects
							(font
								(size 1.27 1.27)
							)
						)
					)
					(number "AG15"
						(effects
							(font
								(size 1.27 1.27)
							)
						)
					)
				)
				(pin bidirectional line
					(at 53.34 -13.97 180)
					(length 5.08)
					(name "IO_L2N_T0_32"
						(effects
							(font
								(size 1.27 1.27)
							)
						)
					)
					(number "AH15"
						(effects
							(font
								(size 1.27 1.27)
							)
						)
					)
				)
				(pin bidirectional line
					(at 53.34 -16.51 180)
					(length 5.08)
					(name "IO_L3P_T0_DQS_32"
						(effects
							(font
								(size 1.27 1.27)
							)
						)
					)
					(number "AH16"
						(effects
							(font
								(size 1.27 1.27)
							)
						)
					)
				)
				(pin bidirectional line
					(at 53.34 -19.05 180)
					(length 5.08)
					(name "IO_L3N_T0_DQS_32"
						(effects
							(font
								(size 1.27 1.27)
							)
						)
					)
					(number "AJ16"
						(effects
							(font
								(size 1.27 1.27)
							)
						)
					)
				)
				(pin bidirectional line
					(at 53.34 -21.59 180)
					(length 5.08)
					(name "IO_L4P_T0_32"
						(effects
							(font
								(size 1.27 1.27)
							)
						)
					)
					(number "AF15"
						(effects
							(font
								(size 1.27 1.27)
							)
						)
					)
				)
				(pin bidirectional line
					(at 53.34 -24.13 180)
					(length 5.08)
					(name "IO_L4N_T0_32"
						(effects
							(font
								(size 1.27 1.27)
							)
						)
					)
					(number "AG14"
						(effects
							(font
								(size 1.27 1.27)
							)
						)
					)
				)
				(pin bidirectional line
					(at 53.34 -26.67 180)
					(length 5.08)
					(name "IO_L5P_T0_32"
						(effects
							(font
								(size 1.27 1.27)
							)
						)
					)
					(number "AH17"
						(effects
							(font
								(size 1.27 1.27)
							)
						)
					)
				)
				(pin bidirectional line
					(at 53.34 -29.21 180)
					(length 5.08)
					(name "IO_L5N_T0_32"
						(effects
							(font
								(size 1.27 1.27)
							)
						)
					)
					(number "AJ17"
						(effects
							(font
								(size 1.27 1.27)
							)
						)
					)
				)
				(pin bidirectional line
					(at 53.34 -31.75 180)
					(length 5.08)
					(name "IO_L6P_T0_32"
						(effects
							(font
								(size 1.27 1.27)
							)
						)
					)
					(number "AE16"
						(effects
							(font
								(size 1.27 1.27)
							)
						)
					)
				)
				(pin bidirectional line
					(at 53.34 -34.29 180)
					(length 5.08)
					(name "IO_L6N_T0_VREF_32"
						(effects
							(font
								(size 1.27 1.27)
							)
						)
					)
					(number "AF16"
						(effects
							(font
								(size 1.27 1.27)
							)
						)
					)
				)
				(pin bidirectional line
					(at 53.34 -36.83 180)
					(length 5.08)
					(name "IO_L7P_T1_32"
						(effects
							(font
								(size 1.27 1.27)
							)
						)
					)
					(number "AJ19"
						(effects
							(font
								(size 1.27 1.27)
							)
						)
					)
				)
				(pin bidirectional line
					(at 53.34 -39.37 180)
					(length 5.08)
					(name "IO_L7N_T1_32"
						(effects
							(font
								(size 1.27 1.27)
							)
						)
					)
					(number "AK19"
						(effects
							(font
								(size 1.27 1.27)
							)
						)
					)
				)
				(pin bidirectional line
					(at 53.34 -41.91 180)
					(length 5.08)
					(name "IO_L8P_T1_32"
						(effects
							(font
								(size 1.27 1.27)
							)
						)
					)
					(number "AG19"
						(effects
							(font
								(size 1.27 1.27)
							)
						)
					)
				)
				(pin bidirectional line
					(at 53.34 -44.45 180)
					(length 5.08)
					(name "IO_L8N_T1_32"
						(effects
							(font
								(size 1.27 1.27)
							)
						)
					)
					(number "AH19"
						(effects
							(font
								(size 1.27 1.27)
							)
						)
					)
				)
				(pin bidirectional line
					(at 53.34 -46.99 180)
					(length 5.08)
					(name "IO_L9P_T1_DQS_32"
						(effects
							(font
								(size 1.27 1.27)
							)
						)
					)
					(number "AJ18"
						(effects
							(font
								(size 1.27 1.27)
							)
						)
					)
				)
				(pin bidirectional line
					(at 53.34 -49.53 180)
					(length 5.08)
					(name "IO_L9N_T1_DQS_32"
						(effects
							(font
								(size 1.27 1.27)
							)
						)
					)
					(number "AK18"
						(effects
							(font
								(size 1.27 1.27)
							)
						)
					)
				)
				(pin bidirectional line
					(at 53.34 -52.07 180)
					(length 5.08)
					(name "IO_L10P_T1_32"
						(effects
							(font
								(size 1.27 1.27)
							)
						)
					)
					(number "AD19"
						(effects
							(font
								(size 1.27 1.27)
							)
						)
					)
				)
				(pin bidirectional line
					(at 53.34 -54.61 180)
					(length 5.08)
					(name "IO_L10N_T1_32"
						(effects
							(font
								(size 1.27 1.27)
							)
						)
					)
					(number "AE19"
						(effects
							(font
								(size 1.27 1.27)
							)
						)
					)
				)
				(pin bidirectional line
					(at 53.34 -57.15 180)
					(length 5.08)
					(name "IO_L11P_T1_SRCC_32"
						(effects
							(font
								(size 1.27 1.27)
							)
						)
					)
					(number "AF18"
						(effects
							(font
								(size 1.27 1.27)
							)
						)
					)
				)
				(pin bidirectional line
					(at 53.34 -59.69 180)
					(length 5.08)
					(name "IO_L11N_T1_SRCC_32"
						(effects
							(font
								(size 1.27 1.27)
							)
						)
					)
					(number "AG18"
						(effects
							(font
								(size 1.27 1.27)
							)
						)
					)
				)
				(pin bidirectional line
					(at 53.34 -62.23 180)
					(length 5.08)
					(name "IO_L12P_T1_MRCC_32"
						(effects
							(font
								(size 1.27 1.27)
							)
						)
					)
					(number "AF17"
						(effects
							(font
								(size 1.27 1.27)
							)
						)
					)
				)
				(pin bidirectional line
					(at 53.34 -64.77 180)
					(length 5.08)
					(name "IO_L12N_T1_MRCC_32"
						(effects
							(font
								(size 1.27 1.27)
							)
						)
					)
					(number "AG17"
						(effects
							(font
								(size 1.27 1.27)
							)
						)
					)
				)
				(pin bidirectional line
					(at 53.34 -67.31 180)
					(length 5.08)
					(name "IO_L13P_T2_MRCC_32"
						(effects
							(font
								(size 1.27 1.27)
							)
						)
					)
					(number "AD18"
						(effects
							(font
								(size 1.27 1.27)
							)
						)
					)
				)
				(pin bidirectional line
					(at 53.34 -69.85 180)
					(length 5.08)
					(name "IO_L13N_T2_MRCC_32"
						(effects
							(font
								(size 1.27 1.27)
							)
						)
					)
					(number "AE18"
						(effects
							(font
								(size 1.27 1.27)
							)
						)
					)
				)
				(pin bidirectional line
					(at 53.34 -72.39 180)
					(length 5.08)
					(name "IO_L14P_T2_SRCC_32"
						(effects
							(font
								(size 1.27 1.27)
							)
						)
					)
					(number "AD17"
						(effects
							(font
								(size 1.27 1.27)
							)
						)
					)
				)
				(pin bidirectional line
					(at 53.34 -74.93 180)
					(length 5.08)
					(name "IO_L14N_T2_SRCC_32"
						(effects
							(font
								(size 1.27 1.27)
							)
						)
					)
					(number "AD16"
						(effects
							(font
								(size 1.27 1.27)
							)
						)
					)
				)
				(pin bidirectional line
					(at 53.34 -77.47 180)
					(length 5.08)
					(name "IO_L15P_T2_DQS_32"
						(effects
							(font
								(size 1.27 1.27)
							)
						)
					)
					(number "Y19"
						(effects
							(font
								(size 1.27 1.27)
							)
						)
					)
				)
				(pin bidirectional line
					(at 53.34 -80.01 180)
					(length 5.08)
					(name "IO_L15N_T2_DQS_32"
						(effects
							(font
								(size 1.27 1.27)
							)
						)
					)
					(number "Y18"
						(effects
							(font
								(size 1.27 1.27)
							)
						)
					)
				)
				(pin bidirectional line
					(at 53.34 -82.55 180)
					(length 5.08)
					(name "IO_L16P_T2_32"
						(effects
							(font
								(size 1.27 1.27)
							)
						)
					)
					(number "AA18"
						(effects
							(font
								(size 1.27 1.27)
							)
						)
					)
				)
				(pin bidirectional line
					(at 53.34 -85.09 180)
					(length 5.08)
					(name "IO_L16N_T2_32"
						(effects
							(font
								(size 1.27 1.27)
							)
						)
					)
					(number "AB18"
						(effects
							(font
								(size 1.27 1.27)
							)
						)
					)
				)
				(pin bidirectional line
					(at 53.34 -87.63 180)
					(length 5.08)
					(name "IO_L17P_T2_32"
						(effects
							(font
								(size 1.27 1.27)
							)
						)
					)
					(number "AB19"
						(effects
							(font
								(size 1.27 1.27)
							)
						)
					)
				)
				(pin bidirectional line
					(at 53.34 -90.17 180)
					(length 5.08)
					(name "IO_L17N_T2_32"
						(effects
							(font
								(size 1.27 1.27)
							)
						)
					)
					(number "AC19"
						(effects
							(font
								(size 1.27 1.27)
							)
						)
					)
				)
				(pin bidirectional line
					(at 53.34 -92.71 180)
					(length 5.08)
					(name "IO_L18P_T2_32"
						(effects
							(font
								(size 1.27 1.27)
							)
						)
					)
					(number "AB17"
						(effects
							(font
								(size 1.27 1.27)
							)
						)
					)
				)
				(pin bidirectional line
					(at 53.34 -95.25 180)
					(length 5.08)
					(name "IO_L18N_T2_32"
						(effects
							(font
								(size 1.27 1.27)
							)
						)
					)
					(number "AC17"
						(effects
							(font
								(size 1.27 1.27)
							)
						)
					)
				)
				(pin bidirectional line
					(at 53.34 -97.79 180)
					(length 5.08)
					(name "IO_L19P_T3_32"
						(effects
							(font
								(size 1.27 1.27)
							)
						)
					)
					(number "AE15"
						(effects
							(font
								(size 1.27 1.27)
							)
						)
					)
				)
				(pin bidirectional line
					(at 53.34 -100.33 180)
					(length 5.08)
					(name "IO_L19N_T3_VREF_32"
						(effects
							(font
								(size 1.27 1.27)
							)
						)
					)
					(number "AE14"
						(effects
							(font
								(size 1.27 1.27)
							)
						)
					)
				)
				(pin bidirectional line
					(at 53.34 -102.87 180)
					(length 5.08)
					(name "IO_L20P_T3_32"
						(effects
							(font
								(size 1.27 1.27)
							)
						)
					)
					(number "AA15"
						(effects
							(font
								(size 1.27 1.27)
							)
						)
					)
				)
				(pin bidirectional line
					(at 53.34 -105.41 180)
					(length 5.08)
					(name "IO_L20N_T3_32"
						(effects
							(font
								(size 1.27 1.27)
							)
						)
					)
					(number "AB15"
						(effects
							(font
								(size 1.27 1.27)
							)
						)
					)
				)
				(pin bidirectional line
					(at 53.34 -107.95 180)
					(length 5.08)
					(name "IO_L21P_T3_DQS_32"
						(effects
							(font
								(size 1.27 1.27)
							)
						)
					)
					(number "AC16"
						(effects
							(font
								(size 1.27 1.27)
							)
						)
					)
				)
				(pin bidirectional line
					(at 53.34 -110.49 180)
					(length 5.08)
					(name "IO_L21N_T3_DQS_32"
						(effects
							(font
								(size 1.27 1.27)
							)
						)
					)
					(number "AC15"
						(effects
							(font
								(size 1.27 1.27)
							)
						)
					)
				)
				(pin bidirectional line
					(at 53.34 -113.03 180)
					(length 5.08)
					(name "IO_L22P_T3_32"
						(effects
							(font
								(size 1.27 1.27)
							)
						)
					)
					(number "AC14"
						(effects
							(font
								(size 1.27 1.27)
							)
						)
					)
				)
				(pin bidirectional line
					(at 53.34 -115.57 180)
					(length 5.08)
					(name "IO_L22N_T3_32"
						(effects
							(font
								(size 1.27 1.27)
							)
						)
					)
					(number "AD14"
						(effects
							(font
								(size 1.27 1.27)
							)
						)
					)
				)
				(pin bidirectional line
					(at 53.34 -118.11 180)
					(length 5.08)
					(name "IO_L23P_T3_32"
						(effects
							(font
								(size 1.27 1.27)
							)
						)
					)
					(number "AA17"
						(effects
							(font
								(size 1.27 1.27)
							)
						)
					)
				)
				(pin bidirectional line
					(at 53.34 -120.65 180)
					(length 5.08)
					(name "IO_L23N_T3_32"
						(effects
							(font
								(size 1.27 1.27)
							)
						)
					)
					(number "AA16"
						(effects
							(font
								(size 1.27 1.27)
							)
						)
					)
				)
				(pin bidirectional line
					(at 53.34 -123.19 180)
					(length 5.08)
					(name "IO_L24P_T3_32"
						(effects
							(font
								(size 1.27 1.27)
							)
						)
					)
					(number "Y16"
						(effects
							(font
								(size 1.27 1.27)
							)
						)
					)
				)
				(pin bidirectional line
					(at 53.34 -125.73 180)
					(length 5.08)
					(name "IO_L24N_T3_32"
						(effects
							(font
								(size 1.27 1.27)
							)
						)
					)
					(number "Y15"
						(effects
							(font
								(size 1.27 1.27)
							)
						)
					)
				)
				(pin bidirectional line
					(at 53.34 -128.27 180)
					(length 5.08)
					(name "IO_25_VRP_32"
						(effects
							(font
								(size 1.27 1.27)
							)
						)
					)
					(number "AB14"
						(effects
							(font
								(size 1.27 1.27)
							)
						)
					)
				)
			)
			(symbol "XC7K410T-2FFG900I_1_5_1"
				(rectangle
					(start 5.08 5.08)
					(end 49.53 -130.81)
					(stroke
						(width 0.254)
						(type default)
					)
					(fill
						(type background)
					)
				)
				(text "BANK 33"
					(at 17.78 2.54 0)
					(effects
						(font
							(size 1.27 1.27)
							(thickness 0.15)
						)
						(justify left bottom)
					)
				)
				(text "BANK 34"
					(at 30.48 2.54 0)
					(effects
						(font
							(size 1.27 1.27)
							(thickness 0.15)
						)
						(justify left bottom)
					)
				)
				(pin bidirectional line
					(at 0 0 0)
					(length 5.08)
					(name "VCCO_33"
						(effects
							(font
								(size 1.27 1.27)
							)
						)
					)
					(number "AA9"
						(effects
							(font
								(size 1.27 1.27)
							)
						)
					)
				)
				(pin passive line
					(at 0 0 0)
					(length 5.08)
					(hide yes)
					(name "VCCO_33"
						(effects
							(font
								(size 1.27 1.27)
							)
						)
					)
					(number "AC13"
						(effects
							(font
								(size 1.27 1.27)
							)
						)
					)
				)
				(pin passive line
					(at 0 0 0)
					(length 5.08)
					(hide yes)
					(name "VCCO_33"
						(effects
							(font
								(size 1.27 1.27)
							)
						)
					)
					(number "AD10"
						(effects
							(font
								(size 1.27 1.27)
							)
						)
					)
				)
				(pin passive line
					(at 0 0 0)
					(length 5.08)
					(hide yes)
					(name "VCCO_33"
						(effects
							(font
								(size 1.27 1.27)
							)
						)
					)
					(number "AG11"
						(effects
							(font
								(size 1.27 1.27)
							)
						)
					)
				)
				(pin passive line
					(at 0 0 0)
					(length 5.08)
					(hide yes)
					(name "VCCO_33"
						(effects
							(font
								(size 1.27 1.27)
							)
						)
					)
					(number "AK12"
						(effects
							(font
								(size 1.27 1.27)
							)
						)
					)
				)
				(pin passive line
					(at 0 0 0)
					(length 5.08)
					(hide yes)
					(name "VCCO_33"
						(effects
							(font
								(size 1.27 1.27)
							)
						)
					)
					(number "Y12"
						(effects
							(font
								(size 1.27 1.27)
							)
						)
					)
				)
				(pin bidirectional line
					(at 0 -3.81 0)
					(length 5.08)
					(name "IO_0_VRN_33"
						(effects
							(font
								(size 1.27 1.27)
							)
						)
					)
					(number "Y13"
						(effects
							(font
								(size 1.27 1.27)
							)
						)
					)
				)
				(pin bidirectional line
					(at 0 -6.35 0)
					(length 5.08)
					(name "IO_L1P_T0_33"
						(effects
							(font
								(size 1.27 1.27)
							)
						)
					)
					(number "AA12"
						(effects
							(font
								(size 1.27 1.27)
							)
						)
					)
				)
				(pin bidirectional line
					(at 0 -8.89 0)
					(length 5.08)
					(name "IO_L1N_T0_33"
						(effects
							(font
								(size 1.27 1.27)
							)
						)
					)
					(number "AB12"
						(effects
							(font
								(size 1.27 1.27)
							)
						)
					)
				)
				(pin bidirectional line
					(at 0 -11.43 0)
					(length 5.08)
					(name "IO_L2P_T0_33"
						(effects
							(font
								(size 1.27 1.27)
							)
						)
					)
					(number "AA8"
						(effects
							(font
								(size 1.27 1.27)
							)
						)
					)
				)
				(pin bidirectional line
					(at 0 -13.97 0)
					(length 5.08)
					(name "IO_L2N_T0_33"
						(effects
							(font
								(size 1.27 1.27)
							)
						)
					)
					(number "AB8"
						(effects
							(font
								(size 1.27 1.27)
							)
						)
					)
				)
				(pin bidirectional line
					(at 0 -16.51 0)
					(length 5.08)
					(name "IO_L3P_T0_DQS_33"
						(effects
							(font
								(size 1.27 1.27)
							)
						)
					)
					(number "AB9"
						(effects
							(font
								(size 1.27 1.27)
							)
						)
					)
				)
				(pin bidirectional line
					(at 0 -19.05 0)
					(length 5.08)
					(name "IO_L3N_T0_DQS_33"
						(effects
							(font
								(size 1.27 1.27)
							)
						)
					)
					(number "AC9"
						(effects
							(font
								(size 1.27 1.27)
							)
						)
					)
				)
				(pin bidirectional line
					(at 0 -21.59 0)
					(length 5.08)
					(name "IO_L4P_T0_33"
						(effects
							(font
								(size 1.27 1.27)
							)
						)
					)
					(number "Y11"
						(effects
							(font
								(size 1.27 1.27)
							)
						)
					)
				)
				(pin bidirectional line
					(at 0 -24.13 0)
					(length 5.08)
					(name "IO_L4N_T0_33"
						(effects
							(font
								(size 1.27 1.27)
							)
						)
					)
					(number "Y10"
						(effects
							(font
								(size 1.27 1.27)
							)
						)
					)
				)
				(pin bidirectional line
					(at 0 -26.67 0)
					(length 5.08)
					(name "IO_L5P_T0_33"
						(effects
							(font
								(size 1.27 1.27)
							)
						)
					)
					(number "AA11"
						(effects
							(font
								(size 1.27 1.27)
							)
						)
					)
				)
				(pin bidirectional line
					(at 0 -29.21 0)
					(length 5.08)
					(name "IO_L5N_T0_33"
						(effects
							(font
								(size 1.27 1.27)
							)
						)
					)
					(number "AA10"
						(effects
							(font
								(size 1.27 1.27)
							)
						)
					)
				)
				(pin bidirectional line
					(at 0 -31.75 0)
					(length 5.08)
					(name "IO_L6P_T0_33"
						(effects
							(font
								(size 1.27 1.27)
							)
						)
					)
					(number "AA13"
						(effects
							(font
								(size 1.27 1.27)
							)
						)
					)
				)
				(pin bidirectional line
					(at 0 -34.29 0)
					(length 5.08)
					(name "IO_L6N_T0_VREF_33"
						(effects
							(font
								(size 1.27 1.27)
							)
						)
					)
					(number "AB13"
						(effects
							(font
								(size 1.27 1.27)
							)
						)
					)
				)
				(pin bidirectional line
					(at 0 -36.83 0)
					(length 5.08)
					(name "IO_L7P_T1_33"
						(effects
							(font
								(size 1.27 1.27)
							)
						)
					)
					(number "AB10"
						(effects
							(font
								(size 1.27 1.27)
							)
						)
					)
				)
				(pin bidirectional line
					(at 0 -39.37 0)
					(length 5.08)
					(name "IO_L7N_T1_33"
						(effects
							(font
								(size 1.27 1.27)
							)
						)
					)
					(number "AC10"
						(effects
							(font
								(size 1.27 1.27)
							)
						)
					)
				)
				(pin bidirectional line
					(at 0 -41.91 0)
					(length 5.08)
					(name "IO_L8P_T1_33"
						(effects
							(font
								(size 1.27 1.27)
							)
						)
					)
					(number "AD8"
						(effects
							(font
								(size 1.27 1.27)
							)
						)
					)
				)
				(pin bidirectional line
					(at 0 -44.45 0)
					(length 5.08)
					(name "IO_L8N_T1_33"
						(effects
							(font
								(size 1.27 1.27)
							)
						)
					)
					(number "AE8"
						(effects
							(font
								(size 1.27 1.27)
							)
						)
					)
				)
				(pin bidirectional line
					(at 0 -46.99 0)
					(length 5.08)
					(name "IO_L9P_T1_DQS_33"
						(effects
							(font
								(size 1.27 1.27)
							)
						)
					)
					(number "AC12"
						(effects
							(font
								(size 1.27 1.27)
							)
						)
					)
				)
				(pin bidirectional line
					(at 0 -49.53 0)
					(length 5.08)
					(name "IO_L9N_T1_DQS_33"
						(effects
							(font
								(size 1.27 1.27)
							)
						)
					)
					(number "AC11"
						(effects
							(font
								(size 1.27 1.27)
							)
						)
					)
				)
				(pin bidirectional line
					(at 0 -52.07 0)
					(length 5.08)
					(name "IO_L10P_T1_33"
						(effects
							(font
								(size 1.27 1.27)
							)
						)
					)
					(number "AD9"
						(effects
							(font
								(size 1.27 1.27)
							)
						)
					)
				)
				(pin bidirectional line
					(at 0 -54.61 0)
					(length 5.08)
					(name "IO_L10N_T1_33"
						(effects
							(font
								(size 1.27 1.27)
							)
						)
					)
					(number "AE9"
						(effects
							(font
								(size 1.27 1.27)
							)
						)
					)
				)
				(pin bidirectional line
					(at 0 -57.15 0)
					(length 5.08)
					(name "IO_L11P_T1_SRCC_33"
						(effects
							(font
								(size 1.27 1.27)
							)
						)
					)
					(number "AE11"
						(effects
							(font
								(size 1.27 1.27)
							)
						)
					)
				)
				(pin bidirectional line
					(at 0 -59.69 0)
					(length 5.08)
					(name "IO_L11N_T1_SRCC_33"
						(effects
							(font
								(size 1.27 1.27)
							)
						)
					)
					(number "AF11"
						(effects
							(font
								(size 1.27 1.27)
							)
						)
					)
				)
				(pin bidirectional line
					(at 0 -62.23 0)
					(length 5.08)
					(name "IO_L12P_T1_MRCC_33"
						(effects
							(font
								(size 1.27 1.27)
							)
						)
					)
					(number "AD12"
						(effects
							(font
								(size 1.27 1.27)
							)
						)
					)
				)
				(pin bidirectional line
					(at 0 -64.77 0)
					(length 5.08)
					(name "IO_L12N_T1_MRCC_33"
						(effects
							(font
								(size 1.27 1.27)
							)
						)
					)
					(number "AD11"
						(effects
							(font
								(size 1.27 1.27)
							)
						)
					)
				)
				(pin bidirectional line
					(at 0 -67.31 0)
					(length 5.08)
					(name "IO_L13P_T2_MRCC_33"
						(effects
							(font
								(size 1.27 1.27)
							)
						)
					)
					(number "AG10"
						(effects
							(font
								(size 1.27 1.27)
							)
						)
					)
				)
				(pin bidirectional line
					(at 0 -69.85 0)
					(length 5.08)
					(name "IO_L13N_T2_MRCC_33"
						(effects
							(font
								(size 1.27 1.27)
							)
						)
					)
					(number "AH10"
						(effects
							(font
								(size 1.27 1.27)
							)
						)
					)
				)
				(pin bidirectional line
					(at 0 -72.39 0)
					(length 5.08)
					(name "IO_L14P_T2_SRCC_33"
						(effects
							(font
								(size 1.27 1.27)
							)
						)
					)
					(number "AE10"
						(effects
							(font
								(size 1.27 1.27)
							)
						)
					)
				)
				(pin bidirectional line
					(at 0 -74.93 0)
					(length 5.08)
					(name "IO_L14N_T2_SRCC_33"
						(effects
							(font
								(size 1.27 1.27)
							)
						)
					)
					(number "AF10"
						(effects
							(font
								(size 1.27 1.27)
							)
						)
					)
				)
				(pin bidirectional line
					(at 0 -77.47 0)
					(length 5.08)
					(name "IO_L15P_T2_DQS_33"
						(effects
							(font
								(size 1.27 1.27)
							)
						)
					)
					(number "AJ9"
						(effects
							(font
								(size 1.27 1.27)
							)
						)
					)
				)
				(pin bidirectional line
					(at 0 -80.01 0)
					(length 5.08)
					(name "IO_L15N_T2_DQS_33"
						(effects
							(font
								(size 1.27 1.27)
							)
						)
					)
					(number "AK9"
						(effects
							(font
								(size 1.27 1.27)
							)
						)
					)
				)
				(pin bidirectional line
					(at 0 -82.55 0)
					(length 5.08)
					(name "IO_L16P_T2_33"
						(effects
							(font
								(size 1.27 1.27)
							)
						)
					)
					(number "AG9"
						(effects
							(font
								(size 1.27 1.27)
							)
						)
					)
				)
				(pin bidirectional line
					(at 0 -85.09 0)
					(length 5.08)
					(name "IO_L16N_T2_33"
						(effects
							(font
								(size 1.27 1.27)
							)
						)
					)
					(number "AH9"
						(effects
							(font
								(size 1.27 1.27)
							)
						)
					)
				)
				(pin bidirectional line
					(at 0 -87.63 0)
					(length 5.08)
					(name "IO_L17P_T2_33"
						(effects
							(font
								(size 1.27 1.27)
							)
						)
					)
					(number "AK11"
						(effects
							(font
								(size 1.27 1.27)
							)
						)
					)
				)
				(pin bidirectional line
					(at 0 -90.17 0)
					(length 5.08)
					(name "IO_L17N_T2_33"
						(effects
							(font
								(size 1.27 1.27)
							)
						)
					)
					(number "AK10"
						(effects
							(font
								(size 1.27 1.27)
							)
						)
					)
				)
				(pin bidirectional line
					(at 0 -92.71 0)
					(length 5.08)
					(name "IO_L18P_T2_33"
						(effects
							(font
								(size 1.27 1.27)
							)
						)
					)
					(number "AH11"
						(effects
							(font
								(size 1.27 1.27)
							)
						)
					)
				)
				(pin bidirectional line
					(at 0 -95.25 0)
					(length 5.08)
					(name "IO_L18N_T2_33"
						(effects
							(font
								(size 1.27 1.27)
							)
						)
					)
					(number "AJ11"
						(effects
							(font
								(size 1.27 1.27)
							)
						)
					)
				)
				(pin bidirectional line
					(at 0 -97.79 0)
					(length 5.08)
					(name "IO_L19P_T3_33"
						(effects
							(font
								(size 1.27 1.27)
							)
						)
					)
					(number "AE13"
						(effects
							(font
								(size 1.27 1.27)
							)
						)
					)
				)
				(pin bidirectional line
					(at 0 -100.33 0)
					(length 5.08)
					(name "IO_L19N_T3_VREF_33"
						(effects
							(font
								(size 1.27 1.27)
							)
						)
					)
					(number "AF13"
						(effects
							(font
								(size 1.27 1.27)
							)
						)
					)
				)
				(pin bidirectional line
					(at 0 -102.87 0)
					(length 5.08)
					(name "IO_L20P_T3_33"
						(effects
							(font
								(size 1.27 1.27)
							)
						)
					)
					(number "AK14"
						(effects
							(font
								(size 1.27 1.27)
							)
						)
					)
				)
				(pin bidirectional line
					(at 0 -105.41 0)
					(length 5.08)
					(name "IO_L20N_T3_33"
						(effects
							(font
								(size 1.27 1.27)
							)
						)
					)
					(number "AK13"
						(effects
							(font
								(size 1.27 1.27)
							)
						)
					)
				)
				(pin bidirectional line
					(at 0 -107.95 0)
					(length 5.08)
					(name "IO_L21P_T3_DQS_33"
						(effects
							(font
								(size 1.27 1.27)
							)
						)
					)
					(number "AH14"
						(effects
							(font
								(size 1.27 1.27)
							)
						)
					)
				)
				(pin bidirectional line
					(at 0 -110.49 0)
					(length 5.08)
					(name "IO_L21N_T3_DQS_33"
						(effects
							(font
								(size 1.27 1.27)
							)
						)
					)
					(number "AJ14"
						(effects
							(font
								(size 1.27 1.27)
							)
						)
					)
				)
				(pin bidirectional line
					(at 0 -113.03 0)
					(length 5.08)
					(name "IO_L22P_T3_33"
						(effects
							(font
								(size 1.27 1.27)
							)
						)
					)
					(number "AJ13"
						(effects
							(font
								(size 1.27 1.27)
							)
						)
					)
				)
				(pin bidirectional line
					(at 0 -115.57 0)
					(length 5.08)
					(name "IO_L22N_T3_33"
						(effects
							(font
								(size 1.27 1.27)
							)
						)
					)
					(number "AJ12"
						(effects
							(font
								(size 1.27 1.27)
							)
						)
					)
				)
				(pin bidirectional line
					(at 0 -118.11 0)
					(length 5.08)
					(name "IO_L23P_T3_33"
						(effects
							(font
								(size 1.27 1.27)
							)
						)
					)
					(number "AF12"
						(effects
							(font
								(size 1.27 1.27)
							)
						)
					)
				)
				(pin bidirectional line
					(at 0 -120.65 0)
					(length 5.08)
					(name "IO_L23N_T3_33"
						(effects
							(font
								(size 1.27 1.27)
							)
						)
					)
					(number "AG12"
						(effects
							(font
								(size 1.27 1.27)
							)
						)
					)
				)
				(pin bidirectional line
					(at 0 -123.19 0)
					(length 5.08)
					(name "IO_L24P_T3_33"
						(effects
							(font
								(size 1.27 1.27)
							)
						)
					)
					(number "AG13"
						(effects
							(font
								(size 1.27 1.27)
							)
						)
					)
				)
				(pin bidirectional line
					(at 0 -125.73 0)
					(length 5.08)
					(name "IO_L24N_T3_33"
						(effects
							(font
								(size 1.27 1.27)
							)
						)
					)
					(number "AH12"
						(effects
							(font
								(size 1.27 1.27)
							)
						)
					)
				)
				(pin bidirectional line
					(at 0 -128.27 0)
					(length 5.08)
					(name "IO_25_VRP_33"
						(effects
							(font
								(size 1.27 1.27)
							)
						)
					)
					(number "AD13"
						(effects
							(font
								(size 1.27 1.27)
							)
						)
					)
				)
				(pin bidirectional line
					(at 54.61 0 180)
					(length 5.08)
					(name "VCCO_34"
						(effects
							(font
								(size 1.27 1.27)
							)
						)
					)
					(number "AC3"
						(effects
							(font
								(size 1.27 1.27)
							)
						)
					)
				)
				(pin passive line
					(at 54.61 0 180)
					(length 5.08)
					(hide yes)
					(name "VCCO_34"
						(effects
							(font
								(size 1.27 1.27)
							)
						)
					)
					(number "AE7"
						(effects
							(font
								(size 1.27 1.27)
							)
						)
					)
				)
				(pin passive line
					(at 54.61 0 180)
					(length 5.08)
					(hide yes)
					(name "VCCO_34"
						(effects
							(font
								(size 1.27 1.27)
							)
						)
					)
					(number "AF4"
						(effects
							(font
								(size 1.27 1.27)
							)
						)
					)
				)
				(pin passive line
					(at 54.61 0 180)
					(length 5.08)
					(hide yes)
					(name "VCCO_34"
						(effects
							(font
								(size 1.27 1.27)
							)
						)
					)
					(number "AG1"
						(effects
							(font
								(size 1.27 1.27)
							)
						)
					)
				)
				(pin passive line
					(at 54.61 0 180)
					(length 5.08)
					(hide yes)
					(name "VCCO_34"
						(effects
							(font
								(size 1.27 1.27)
							)
						)
					)
					(number "AH8"
						(effects
							(font
								(size 1.27 1.27)
							)
						)
					)
				)
				(pin passive line
					(at 54.61 0 180)
					(length 5.08)
					(hide yes)
					(name "VCCO_34"
						(effects
							(font
								(size 1.27 1.27)
							)
						)
					)
					(number "AJ5"
						(effects
							(font
								(size 1.27 1.27)
							)
						)
					)
				)
				(pin passive line
					(at 54.61 0 180)
					(length 5.08)
					(hide yes)
					(name "VCCO_34"
						(effects
							(font
								(size 1.27 1.27)
							)
						)
					)
					(number "AK2"
						(effects
							(font
								(size 1.27 1.27)
							)
						)
					)
				)
				(pin bidirectional line
					(at 54.61 -3.81 180)
					(length 5.08)
					(name "IO_0_VRN_34"
						(effects
							(font
								(size 1.27 1.27)
							)
						)
					)
					(number "AC6"
						(effects
							(font
								(size 1.27 1.27)
							)
						)
					)
				)
				(pin bidirectional line
					(at 54.61 -6.35 180)
					(length 5.08)
					(name "IO_L1P_T0_34"
						(effects
							(font
								(size 1.27 1.27)
							)
						)
					)
					(number "AD4"
						(effects
							(font
								(size 1.27 1.27)
							)
						)
					)
				)
				(pin bidirectional line
					(at 54.61 -8.89 180)
					(length 5.08)
					(name "IO_L1N_T0_34"
						(effects
							(font
								(size 1.27 1.27)
							)
						)
					)
					(number "AD3"
						(effects
							(font
								(size 1.27 1.27)
							)
						)
					)
				)
				(pin bidirectional line
					(at 54.61 -11.43 180)
					(length 5.08)
					(name "IO_L2P_T0_34"
						(effects
							(font
								(size 1.27 1.27)
							)
						)
					)
					(number "AC2"
						(effects
							(font
								(size 1.27 1.27)
							)
						)
					)
				)
				(pin bidirectional line
					(at 54.61 -13.97 180)
					(length 5.08)
					(name "IO_L2N_T0_34"
						(effects
							(font
								(size 1.27 1.27)
							)
						)
					)
					(number "AC1"
						(effects
							(font
								(size 1.27 1.27)
							)
						)
					)
				)
				(pin bidirectional line
					(at 54.61 -16.51 180)
					(length 5.08)
					(name "IO_L3P_T0_DQS_34"
						(effects
							(font
								(size 1.27 1.27)
							)
						)
					)
					(number "AD2"
						(effects
							(font
								(size 1.27 1.27)
							)
						)
					)
				)
				(pin bidirectional line
					(at 54.61 -19.05 180)
					(length 5.08)
					(name "IO_L3N_T0_DQS_34"
						(effects
							(font
								(size 1.27 1.27)
							)
						)
					)
					(number "AD1"
						(effects
							(font
								(size 1.27 1.27)
							)
						)
					)
				)
				(pin bidirectional line
					(at 54.61 -21.59 180)
					(length 5.08)
					(name "IO_L4P_T0_34"
						(effects
							(font
								(size 1.27 1.27)
							)
						)
					)
					(number "AC5"
						(effects
							(font
								(size 1.27 1.27)
							)
						)
					)
				)
				(pin bidirectional line
					(at 54.61 -24.13 180)
					(length 5.08)
					(name "IO_L4N_T0_34"
						(effects
							(font
								(size 1.27 1.27)
							)
						)
					)
					(number "AC4"
						(effects
							(font
								(size 1.27 1.27)
							)
						)
					)
				)
				(pin bidirectional line
					(at 54.61 -26.67 180)
					(length 5.08)
					(name "IO_L5P_T0_34"
						(effects
							(font
								(size 1.27 1.27)
							)
						)
					)
					(number "AD6"
						(effects
							(font
								(size 1.27 1.27)
							)
						)
					)
				)
				(pin bidirectional line
					(at 54.61 -29.21 180)
					(length 5.08)
					(name "IO_L5N_T0_34"
						(effects
							(font
								(size 1.27 1.27)
							)
						)
					)
					(number "AE6"
						(effects
							(font
								(size 1.27 1.27)
							)
						)
					)
				)
				(pin bidirectional line
					(at 54.61 -31.75 180)
					(length 5.08)
					(name "IO_L6P_T0_34"
						(effects
							(font
								(size 1.27 1.27)
							)
						)
					)
					(number "AC7"
						(effects
							(font
								(size 1.27 1.27)
							)
						)
					)
				)
				(pin bidirectional line
					(at 54.61 -34.29 180)
					(length 5.08)
					(name "IO_L6N_T0_VREF_34"
						(effects
							(font
								(size 1.27 1.27)
							)
						)
					)
					(number "AD7"
						(effects
							(font
								(size 1.27 1.27)
							)
						)
					)
				)
				(pin bidirectional line
					(at 54.61 -36.83 180)
					(length 5.08)
					(name "IO_L7P_T1_34"
						(effects
							(font
								(size 1.27 1.27)
							)
						)
					)
					(number "AF3"
						(effects
							(font
								(size 1.27 1.27)
							)
						)
					)
				)
				(pin bidirectional line
					(at 54.61 -39.37 180)
					(length 5.08)
					(name "IO_L7N_T1_34"
						(effects
							(font
								(size 1.27 1.27)
							)
						)
					)
					(number "AF2"
						(effects
							(font
								(size 1.27 1.27)
							)
						)
					)
				)
				(pin bidirectional line
					(at 54.61 -41.91 180)
					(length 5.08)
					(name "IO_L8P_T1_34"
						(effects
							(font
								(size 1.27 1.27)
							)
						)
					)
					(number "AE1"
						(effects
							(font
								(size 1.27 1.27)
							)
						)
					)
				)
				(pin bidirectional line
					(at 54.61 -44.45 180)
					(length 5.08)
					(name "IO_L8N_T1_34"
						(effects
							(font
								(size 1.27 1.27)
							)
						)
					)
					(number "AF1"
						(effects
							(font
								(size 1.27 1.27)
							)
						)
					)
				)
				(pin bidirectional line
					(at 54.61 -46.99 180)
					(length 5.08)
					(name "IO_L9P_T1_DQS_34"
						(effects
							(font
								(size 1.27 1.27)
							)
						)
					)
					(number "AG4"
						(effects
							(font
								(size 1.27 1.27)
							)
						)
					)
				)
				(pin bidirectional line
					(at 54.61 -49.53 180)
					(length 5.08)
					(name "IO_L9N_T1_DQS_34"
						(effects
							(font
								(size 1.27 1.27)
							)
						)
					)
					(number "AG3"
						(effects
							(font
								(size 1.27 1.27)
							)
						)
					)
				)
				(pin bidirectional line
					(at 54.61 -52.07 180)
					(length 5.08)
					(name "IO_L10P_T1_34"
						(effects
							(font
								(size 1.27 1.27)
							)
						)
					)
					(number "AE4"
						(effects
							(font
								(size 1.27 1.27)
							)
						)
					)
				)
				(pin bidirectional line
					(at 54.61 -54.61 180)
					(length 5.08)
					(name "IO_L10N_T1_34"
						(effects
							(font
								(size 1.27 1.27)
							)
						)
					)
					(number "AE3"
						(effects
							(font
								(size 1.27 1.27)
							)
						)
					)
				)
				(pin bidirectional line
					(at 54.61 -57.15 180)
					(length 5.08)
					(name "IO_L11P_T1_SRCC_34"
						(effects
							(font
								(size 1.27 1.27)
							)
						)
					)
					(number "AE5"
						(effects
							(font
								(size 1.27 1.27)
							)
						)
					)
				)
				(pin bidirectional line
					(at 54.61 -59.69 180)
					(length 5.08)
					(name "IO_L11N_T1_SRCC_34"
						(effects
							(font
								(size 1.27 1.27)
							)
						)
					)
					(number "AF5"
						(effects
							(font
								(size 1.27 1.27)
							)
						)
					)
				)
				(pin bidirectional line
					(at 54.61 -62.23 180)
					(length 5.08)
					(name "IO_L12P_T1_MRCC_34"
						(effects
							(font
								(size 1.27 1.27)
							)
						)
					)
					(number "AF6"
						(effects
							(font
								(size 1.27 1.27)
							)
						)
					)
				)
				(pin bidirectional line
					(at 54.61 -64.77 180)
					(length 5.08)
					(name "IO_L12N_T1_MRCC_34"
						(effects
							(font
								(size 1.27 1.27)
							)
						)
					)
					(number "AG5"
						(effects
							(font
								(size 1.27 1.27)
							)
						)
					)
				)
				(pin bidirectional line
					(at 54.61 -67.31 180)
					(length 5.08)
					(name "IO_L13P_T2_MRCC_34"
						(effects
							(font
								(size 1.27 1.27)
							)
						)
					)
					(number "AH4"
						(effects
							(font
								(size 1.27 1.27)
							)
						)
					)
				)
				(pin bidirectional line
					(at 54.61 -69.85 180)
					(length 5.08)
					(name "IO_L13N_T2_MRCC_34"
						(effects
							(font
								(size 1.27 1.27)
							)
						)
					)
					(number "AJ4"
						(effects
							(font
								(size 1.27 1.27)
							)
						)
					)
				)
				(pin bidirectional line
					(at 54.61 -72.39 180)
					(length 5.08)
					(name "IO_L14P_T2_SRCC_34"
						(effects
							(font
								(size 1.27 1.27)
							)
						)
					)
					(number "AH6"
						(effects
							(font
								(size 1.27 1.27)
							)
						)
					)
				)
				(pin bidirectional line
					(at 54.61 -74.93 180)
					(length 5.08)
					(name "IO_L14N_T2_SRCC_34"
						(effects
							(font
								(size 1.27 1.27)
							)
						)
					)
					(number "AH5"
						(effects
							(font
								(size 1.27 1.27)
							)
						)
					)
				)
				(pin bidirectional line
					(at 54.61 -77.47 180)
					(length 5.08)
					(name "IO_L15P_T2_DQS_34"
						(effects
							(font
								(size 1.27 1.27)
							)
						)
					)
					(number "AG2"
						(effects
							(font
								(size 1.27 1.27)
							)
						)
					)
				)
				(pin bidirectional line
					(at 54.61 -80.01 180)
					(length 5.08)
					(name "IO_L15N_T2_DQS_34"
						(effects
							(font
								(size 1.27 1.27)
							)
						)
					)
					(number "AH1"
						(effects
							(font
								(size 1.27 1.27)
							)
						)
					)
				)
				(pin bidirectional line
					(at 54.61 -82.55 180)
					(length 5.08)
					(name "IO_L16P_T2_34"
						(effects
							(font
								(size 1.27 1.27)
							)
						)
					)
					(number "AH2"
						(effects
							(font
								(size 1.27 1.27)
							)
						)
					)
				)
				(pin bidirectional line
					(at 54.61 -85.09 180)
					(length 5.08)
					(name "IO_L16N_T2_34"
						(effects
							(font
								(size 1.27 1.27)
							)
						)
					)
					(number "AJ2"
						(effects
							(font
								(size 1.27 1.27)
							)
						)
					)
				)
				(pin bidirectional line
					(at 54.61 -87.63 180)
					(length 5.08)
					(name "IO_L17P_T2_34"
						(effects
							(font
								(size 1.27 1.27)
							)
						)
					)
					(number "AJ1"
						(effects
							(font
								(size 1.27 1.27)
							)
						)
					)
				)
				(pin bidirectional line
					(at 54.61 -90.17 180)
					(length 5.08)
					(name "IO_L17N_T2_34"
						(effects
							(font
								(size 1.27 1.27)
							)
						)
					)
					(number "AK1"
						(effects
							(font
								(size 1.27 1.27)
							)
						)
					)
				)
				(pin bidirectional line
					(at 54.61 -92.71 180)
					(length 5.08)
					(name "IO_L18P_T2_34"
						(effects
							(font
								(size 1.27 1.27)
							)
						)
					)
					(number "AJ3"
						(effects
							(font
								(size 1.27 1.27)
							)
						)
					)
				)
				(pin bidirectional line
					(at 54.61 -95.25 180)
					(length 5.08)
					(name "IO_L18N_T2_34"
						(effects
							(font
								(size 1.27 1.27)
							)
						)
					)
					(number "AK3"
						(effects
							(font
								(size 1.27 1.27)
							)
						)
					)
				)
				(pin bidirectional line
					(at 54.61 -97.79 180)
					(length 5.08)
					(name "IO_L19P_T3_34"
						(effects
							(font
								(size 1.27 1.27)
							)
						)
					)
					(number "AF8"
						(effects
							(font
								(size 1.27 1.27)
							)
						)
					)
				)
				(pin bidirectional line
					(at 54.61 -100.33 180)
					(length 5.08)
					(name "IO_L19N_T3_VREF_34"
						(effects
							(font
								(size 1.27 1.27)
							)
						)
					)
					(number "AG8"
						(effects
							(font
								(size 1.27 1.27)
							)
						)
					)
				)
				(pin bidirectional line
					(at 54.61 -102.87 180)
					(length 5.08)
					(name "IO_L20P_T3_34"
						(effects
							(font
								(size 1.27 1.27)
							)
						)
					)
					(number "AF7"
						(effects
							(font
								(size 1.27 1.27)
							)
						)
					)
				)
				(pin bidirectional line
					(at 54.61 -105.41 180)
					(length 5.08)
					(name "IO_L20N_T3_34"
						(effects
							(font
								(size 1.27 1.27)
							)
						)
					)
					(number "AG7"
						(effects
							(font
								(size 1.27 1.27)
							)
						)
					)
				)
				(pin bidirectional line
					(at 54.61 -107.95 180)
					(length 5.08)
					(name "IO_L21P_T3_DQS_34"
						(effects
							(font
								(size 1.27 1.27)
							)
						)
					)
					(number "AH7"
						(effects
							(font
								(size 1.27 1.27)
							)
						)
					)
				)
				(pin bidirectional line
					(at 54.61 -110.49 180)
					(length 5.08)
					(name "IO_L21N_T3_DQS_34"
						(effects
							(font
								(size 1.27 1.27)
							)
						)
					)
					(number "AJ7"
						(effects
							(font
								(size 1.27 1.27)
							)
						)
					)
				)
				(pin bidirectional line
					(at 54.61 -113.03 180)
					(length 5.08)
					(name "IO_L22P_T3_34"
						(effects
							(font
								(size 1.27 1.27)
							)
						)
					)
					(number "AJ6"
						(effects
							(font
								(size 1.27 1.27)
							)
						)
					)
				)
				(pin bidirectional line
					(at 54.61 -115.57 180)
					(length 5.08)
					(name "IO_L22N_T3_34"
						(effects
							(font
								(size 1.27 1.27)
							)
						)
					)
					(number "AK6"
						(effects
							(font
								(size 1.27 1.27)
							)
						)
					)
				)
				(pin bidirectional line
					(at 54.61 -118.11 180)
					(length 5.08)
					(name "IO_L23P_T3_34"
						(effects
							(font
								(size 1.27 1.27)
							)
						)
					)
					(number "AJ8"
						(effects
							(font
								(size 1.27 1.27)
							)
						)
					)
				)
				(pin bidirectional line
					(at 54.61 -120.65 180)
					(length 5.08)
					(name "IO_L23N_T3_34"
						(effects
							(font
								(size 1.27 1.27)
							)
						)
					)
					(number "AK8"
						(effects
							(font
								(size 1.27 1.27)
							)
						)
					)
				)
				(pin bidirectional line
					(at 54.61 -123.19 180)
					(length 5.08)
					(name "IO_L24P_T3_34"
						(effects
							(font
								(size 1.27 1.27)
							)
						)
					)
					(number "AK5"
						(effects
							(font
								(size 1.27 1.27)
							)
						)
					)
				)
				(pin bidirectional line
					(at 54.61 -125.73 180)
					(length 5.08)
					(name "IO_L24N_T3_34"
						(effects
							(font
								(size 1.27 1.27)
							)
						)
					)
					(number "AK4"
						(effects
							(font
								(size 1.27 1.27)
							)
						)
					)
				)
				(pin bidirectional line
					(at 54.61 -128.27 180)
					(length 5.08)
					(name "IO_25_VRP_34"
						(effects
							(font
								(size 1.27 1.27)
							)
						)
					)
					(number "AB7"
						(effects
							(font
								(size 1.27 1.27)
							)
						)
					)
				)
			)
			(symbol "XC7K410T-2FFG900I_1_6_1"
				(rectangle
					(start 5.08 5.08)
					(end 43.18 -53.34)
					(stroke
						(width 0.254)
						(type default)
					)
					(fill
						(type background)
					)
				)
				(text "GTX 115"
					(at 8.89 2.54 0)
					(effects
						(font
							(size 1.27 1.27)
							(thickness 0.15)
						)
						(justify left bottom)
					)
				)
				(text "GTX 116"
					(at 29.21 2.54 0)
					(effects
						(font
							(size 1.27 1.27)
							(thickness 0.15)
						)
						(justify left bottom)
					)
				)
				(pin bidirectional line
					(at 0 0 0)
					(length 5.08)
					(name "MGTXTXP0_115"
						(effects
							(font
								(size 1.27 1.27)
							)
						)
					)
					(number "Y2"
						(effects
							(font
								(size 1.27 1.27)
							)
						)
					)
				)
				(pin bidirectional line
					(at 0 -2.54 0)
					(length 5.08)
					(name "MGTXTXN0_115"
						(effects
							(font
								(size 1.27 1.27)
							)
						)
					)
					(number "Y1"
						(effects
							(font
								(size 1.27 1.27)
							)
						)
					)
				)
				(pin bidirectional line
					(at 0 -5.08 0)
					(length 5.08)
					(name "MGTXTXP1_115"
						(effects
							(font
								(size 1.27 1.27)
							)
						)
					)
					(number "V2"
						(effects
							(font
								(size 1.27 1.27)
							)
						)
					)
				)
				(pin bidirectional line
					(at 0 -7.62 0)
					(length 5.08)
					(name "MGTXTXN1_115"
						(effects
							(font
								(size 1.27 1.27)
							)
						)
					)
					(number "V1"
						(effects
							(font
								(size 1.27 1.27)
							)
						)
					)
				)
				(pin bidirectional line
					(at 0 -10.16 0)
					(length 5.08)
					(name "MGTXTXP2_115"
						(effects
							(font
								(size 1.27 1.27)
							)
						)
					)
					(number "U4"
						(effects
							(font
								(size 1.27 1.27)
							)
						)
					)
				)
				(pin bidirectional line
					(at 0 -12.7 0)
					(length 5.08)
					(name "MGTXTXN2_115"
						(effects
							(font
								(size 1.27 1.27)
							)
						)
					)
					(number "U3"
						(effects
							(font
								(size 1.27 1.27)
							)
						)
					)
				)
				(pin bidirectional line
					(at 0 -15.24 0)
					(length 5.08)
					(name "MGTXTXP3_115"
						(effects
							(font
								(size 1.27 1.27)
							)
						)
					)
					(number "T2"
						(effects
							(font
								(size 1.27 1.27)
							)
						)
					)
				)
				(pin bidirectional line
					(at 0 -17.78 0)
					(length 5.08)
					(name "MGTXTXN3_115"
						(effects
							(font
								(size 1.27 1.27)
							)
						)
					)
					(number "T1"
						(effects
							(font
								(size 1.27 1.27)
							)
						)
					)
				)
				(pin bidirectional line
					(at 0 -21.59 0)
					(length 5.08)
					(name "MGTXRXP0_115"
						(effects
							(font
								(size 1.27 1.27)
							)
						)
					)
					(number "AA4"
						(effects
							(font
								(size 1.27 1.27)
							)
						)
					)
				)
				(pin bidirectional line
					(at 0 -24.13 0)
					(length 5.08)
					(name "MGTXRXN0_115"
						(effects
							(font
								(size 1.27 1.27)
							)
						)
					)
					(number "AA3"
						(effects
							(font
								(size 1.27 1.27)
							)
						)
					)
				)
				(pin bidirectional line
					(at 0 -26.67 0)
					(length 5.08)
					(name "MGTXRXP1_115"
						(effects
							(font
								(size 1.27 1.27)
							)
						)
					)
					(number "Y6"
						(effects
							(font
								(size 1.27 1.27)
							)
						)
					)
				)
				(pin bidirectional line
					(at 0 -29.21 0)
					(length 5.08)
					(name "MGTXRXN1_115"
						(effects
							(font
								(size 1.27 1.27)
							)
						)
					)
					(number "Y5"
						(effects
							(font
								(size 1.27 1.27)
							)
						)
					)
				)
				(pin bidirectional line
					(at 0 -31.75 0)
					(length 5.08)
					(name "MGTXRXP2_115"
						(effects
							(font
								(size 1.27 1.27)
							)
						)
					)
					(number "W4"
						(effects
							(font
								(size 1.27 1.27)
							)
						)
					)
				)
				(pin bidirectional line
					(at 0 -34.29 0)
					(length 5.08)
					(name "MGTXRXN2_115"
						(effects
							(font
								(size 1.27 1.27)
							)
						)
					)
					(number "W3"
						(effects
							(font
								(size 1.27 1.27)
							)
						)
					)
				)
				(pin bidirectional line
					(at 0 -36.83 0)
					(length 5.08)
					(name "MGTXRXP3_115"
						(effects
							(font
								(size 1.27 1.27)
							)
						)
					)
					(number "V6"
						(effects
							(font
								(size 1.27 1.27)
							)
						)
					)
				)
				(pin bidirectional line
					(at 0 -39.37 0)
					(length 5.08)
					(name "MGTXRXN3_115"
						(effects
							(font
								(size 1.27 1.27)
							)
						)
					)
					(number "V5"
						(effects
							(font
								(size 1.27 1.27)
							)
						)
					)
				)
				(pin bidirectional line
					(at 0 -43.18 0)
					(length 5.08)
					(name "MGTREFCLK0P_115"
						(effects
							(font
								(size 1.27 1.27)
							)
						)
					)
					(number "R8"
						(effects
							(font
								(size 1.27 1.27)
							)
						)
					)
				)
				(pin bidirectional line
					(at 0 -45.72 0)
					(length 5.08)
					(name "MGTREFCLK0N_115"
						(effects
							(font
								(size 1.27 1.27)
							)
						)
					)
					(number "R7"
						(effects
							(font
								(size 1.27 1.27)
							)
						)
					)
				)
				(pin bidirectional line
					(at 0 -48.26 0)
					(length 5.08)
					(name "MGTREFCLK1P_115"
						(effects
							(font
								(size 1.27 1.27)
							)
						)
					)
					(number "U8"
						(effects
							(font
								(size 1.27 1.27)
							)
						)
					)
				)
				(pin bidirectional line
					(at 0 -50.8 0)
					(length 5.08)
					(name "MGTREFCLK1N_115"
						(effects
							(font
								(size 1.27 1.27)
							)
						)
					)
					(number "U7"
						(effects
							(font
								(size 1.27 1.27)
							)
						)
					)
				)
				(pin bidirectional line
					(at 48.26 0 180)
					(length 5.08)
					(name "MGTXTXP0_116"
						(effects
							(font
								(size 1.27 1.27)
							)
						)
					)
					(number "P2"
						(effects
							(font
								(size 1.27 1.27)
							)
						)
					)
				)
				(pin bidirectional line
					(at 48.26 -2.54 180)
					(length 5.08)
					(name "MGTXTXN0_116"
						(effects
							(font
								(size 1.27 1.27)
							)
						)
					)
					(number "P1"
						(effects
							(font
								(size 1.27 1.27)
							)
						)
					)
				)
				(pin bidirectional line
					(at 48.26 -5.08 180)
					(length 5.08)
					(name "MGTXTXP1_116"
						(effects
							(font
								(size 1.27 1.27)
							)
						)
					)
					(number "N4"
						(effects
							(font
								(size 1.27 1.27)
							)
						)
					)
				)
				(pin bidirectional line
					(at 48.26 -7.62 180)
					(length 5.08)
					(name "MGTXTXN1_116"
						(effects
							(font
								(size 1.27 1.27)
							)
						)
					)
					(number "N3"
						(effects
							(font
								(size 1.27 1.27)
							)
						)
					)
				)
				(pin bidirectional line
					(at 48.26 -10.16 180)
					(length 5.08)
					(name "MGTXTXP2_116"
						(effects
							(font
								(size 1.27 1.27)
							)
						)
					)
					(number "M2"
						(effects
							(font
								(size 1.27 1.27)
							)
						)
					)
				)
				(pin bidirectional line
					(at 48.26 -12.7 180)
					(length 5.08)
					(name "MGTXTXN2_116"
						(effects
							(font
								(size 1.27 1.27)
							)
						)
					)
					(number "M1"
						(effects
							(font
								(size 1.27 1.27)
							)
						)
					)
				)
				(pin bidirectional line
					(at 48.26 -15.24 180)
					(length 5.08)
					(name "MGTXTXP3_116"
						(effects
							(font
								(size 1.27 1.27)
							)
						)
					)
					(number "L4"
						(effects
							(font
								(size 1.27 1.27)
							)
						)
					)
				)
				(pin bidirectional line
					(at 48.26 -17.78 180)
					(length 5.08)
					(name "MGTXTXN3_116"
						(effects
							(font
								(size 1.27 1.27)
							)
						)
					)
					(number "L3"
						(effects
							(font
								(size 1.27 1.27)
							)
						)
					)
				)
				(pin bidirectional line
					(at 48.26 -21.59 180)
					(length 5.08)
					(name "MGTXRXP0_116"
						(effects
							(font
								(size 1.27 1.27)
							)
						)
					)
					(number "T6"
						(effects
							(font
								(size 1.27 1.27)
							)
						)
					)
				)
				(pin bidirectional line
					(at 48.26 -24.13 180)
					(length 5.08)
					(name "MGTXRXN0_116"
						(effects
							(font
								(size 1.27 1.27)
							)
						)
					)
					(number "T5"
						(effects
							(font
								(size 1.27 1.27)
							)
						)
					)
				)
				(pin bidirectional line
					(at 48.26 -26.67 180)
					(length 5.08)
					(name "MGTXRXP1_116"
						(effects
							(font
								(size 1.27 1.27)
							)
						)
					)
					(number "R4"
						(effects
							(font
								(size 1.27 1.27)
							)
						)
					)
				)
				(pin bidirectional line
					(at 48.26 -29.21 180)
					(length 5.08)
					(name "MGTXRXN1_116"
						(effects
							(font
								(size 1.27 1.27)
							)
						)
					)
					(number "R3"
						(effects
							(font
								(size 1.27 1.27)
							)
						)
					)
				)
				(pin bidirectional line
					(at 48.26 -31.75 180)
					(length 5.08)
					(name "MGTXRXP2_116"
						(effects
							(font
								(size 1.27 1.27)
							)
						)
					)
					(number "P6"
						(effects
							(font
								(size 1.27 1.27)
							)
						)
					)
				)
				(pin bidirectional line
					(at 48.26 -34.29 180)
					(length 5.08)
					(name "MGTXRXN2_116"
						(effects
							(font
								(size 1.27 1.27)
							)
						)
					)
					(number "P5"
						(effects
							(font
								(size 1.27 1.27)
							)
						)
					)
				)
				(pin bidirectional line
					(at 48.26 -36.83 180)
					(length 5.08)
					(name "MGTXRXP3_116"
						(effects
							(font
								(size 1.27 1.27)
							)
						)
					)
					(number "M6"
						(effects
							(font
								(size 1.27 1.27)
							)
						)
					)
				)
				(pin bidirectional line
					(at 48.26 -39.37 180)
					(length 5.08)
					(name "MGTXRXN3_116"
						(effects
							(font
								(size 1.27 1.27)
							)
						)
					)
					(number "M5"
						(effects
							(font
								(size 1.27 1.27)
							)
						)
					)
				)
				(pin bidirectional line
					(at 48.26 -43.18 180)
					(length 5.08)
					(name "MGTREFCLK0P_116"
						(effects
							(font
								(size 1.27 1.27)
							)
						)
					)
					(number "L8"
						(effects
							(font
								(size 1.27 1.27)
							)
						)
					)
				)
				(pin bidirectional line
					(at 48.26 -45.72 180)
					(length 5.08)
					(name "MGTREFCLK0N_116"
						(effects
							(font
								(size 1.27 1.27)
							)
						)
					)
					(number "L7"
						(effects
							(font
								(size 1.27 1.27)
							)
						)
					)
				)
				(pin bidirectional line
					(at 48.26 -48.26 180)
					(length 5.08)
					(name "MGTREFCLK1P_116"
						(effects
							(font
								(size 1.27 1.27)
							)
						)
					)
					(number "N8"
						(effects
							(font
								(size 1.27 1.27)
							)
						)
					)
				)
				(pin bidirectional line
					(at 48.26 -50.8 180)
					(length 5.08)
					(name "MGTREFCLK1N_116"
						(effects
							(font
								(size 1.27 1.27)
							)
						)
					)
					(number "N7"
						(effects
							(font
								(size 1.27 1.27)
							)
						)
					)
				)
			)
			(symbol "XC7K410T-2FFG900I_1_7_1"
				(rectangle
					(start 5.08 5.08)
					(end 43.18 -53.34)
					(stroke
						(width 0.254)
						(type default)
					)
					(fill
						(type background)
					)
				)
				(text "GTX 117"
					(at 8.89 2.54 0)
					(effects
						(font
							(size 1.27 1.27)
							(thickness 0.15)
						)
						(justify left bottom)
					)
				)
				(text "GTX 118"
					(at 29.21 2.54 0)
					(effects
						(font
							(size 1.27 1.27)
							(thickness 0.15)
						)
						(justify left bottom)
					)
				)
				(pin bidirectional line
					(at 0 0 0)
					(length 5.08)
					(name "MGTXTXP0_117"
						(effects
							(font
								(size 1.27 1.27)
							)
						)
					)
					(number "K2"
						(effects
							(font
								(size 1.27 1.27)
							)
						)
					)
				)
				(pin bidirectional line
					(at 0 -2.54 0)
					(length 5.08)
					(name "MGTXTXN0_117"
						(effects
							(font
								(size 1.27 1.27)
							)
						)
					)
					(number "K1"
						(effects
							(font
								(size 1.27 1.27)
							)
						)
					)
				)
				(pin bidirectional line
					(at 0 -5.08 0)
					(length 5.08)
					(name "MGTXTXP1_117"
						(effects
							(font
								(size 1.27 1.27)
							)
						)
					)
					(number "J4"
						(effects
							(font
								(size 1.27 1.27)
							)
						)
					)
				)
				(pin bidirectional line
					(at 0 -7.62 0)
					(length 5.08)
					(name "MGTXTXN1_117"
						(effects
							(font
								(size 1.27 1.27)
							)
						)
					)
					(number "J3"
						(effects
							(font
								(size 1.27 1.27)
							)
						)
					)
				)
				(pin bidirectional line
					(at 0 -10.16 0)
					(length 5.08)
					(name "MGTXTXP2_117"
						(effects
							(font
								(size 1.27 1.27)
							)
						)
					)
					(number "H2"
						(effects
							(font
								(size 1.27 1.27)
							)
						)
					)
				)
				(pin bidirectional line
					(at 0 -12.7 0)
					(length 5.08)
					(name "MGTXTXN2_117"
						(effects
							(font
								(size 1.27 1.27)
							)
						)
					)
					(number "H1"
						(effects
							(font
								(size 1.27 1.27)
							)
						)
					)
				)
				(pin bidirectional line
					(at 0 -15.24 0)
					(length 5.08)
					(name "MGTXTXP3_117"
						(effects
							(font
								(size 1.27 1.27)
							)
						)
					)
					(number "F2"
						(effects
							(font
								(size 1.27 1.27)
							)
						)
					)
				)
				(pin bidirectional line
					(at 0 -17.78 0)
					(length 5.08)
					(name "MGTXTXN3_117"
						(effects
							(font
								(size 1.27 1.27)
							)
						)
					)
					(number "F1"
						(effects
							(font
								(size 1.27 1.27)
							)
						)
					)
				)
				(pin bidirectional line
					(at 0 -21.59 0)
					(length 5.08)
					(name "MGTXRXP0_117"
						(effects
							(font
								(size 1.27 1.27)
							)
						)
					)
					(number "K6"
						(effects
							(font
								(size 1.27 1.27)
							)
						)
					)
				)
				(pin bidirectional line
					(at 0 -24.13 0)
					(length 5.08)
					(name "MGTXRXN0_117"
						(effects
							(font
								(size 1.27 1.27)
							)
						)
					)
					(number "K5"
						(effects
							(font
								(size 1.27 1.27)
							)
						)
					)
				)
				(pin bidirectional line
					(at 0 -26.67 0)
					(length 5.08)
					(name "MGTXRXP1_117"
						(effects
							(font
								(size 1.27 1.27)
							)
						)
					)
					(number "H6"
						(effects
							(font
								(size 1.27 1.27)
							)
						)
					)
				)
				(pin bidirectional line
					(at 0 -29.21 0)
					(length 5.08)
					(name "MGTXRXN1_117"
						(effects
							(font
								(size 1.27 1.27)
							)
						)
					)
					(number "H5"
						(effects
							(font
								(size 1.27 1.27)
							)
						)
					)
				)
				(pin bidirectional line
					(at 0 -31.75 0)
					(length 5.08)
					(name "MGTXRXP2_117"
						(effects
							(font
								(size 1.27 1.27)
							)
						)
					)
					(number "G4"
						(effects
							(font
								(size 1.27 1.27)
							)
						)
					)
				)
				(pin bidirectional line
					(at 0 -34.29 0)
					(length 5.08)
					(name "MGTXRXN2_117"
						(effects
							(font
								(size 1.27 1.27)
							)
						)
					)
					(number "G3"
						(effects
							(font
								(size 1.27 1.27)
							)
						)
					)
				)
				(pin bidirectional line
					(at 0 -36.83 0)
					(length 5.08)
					(name "MGTXRXP3_117"
						(effects
							(font
								(size 1.27 1.27)
							)
						)
					)
					(number "F6"
						(effects
							(font
								(size 1.27 1.27)
							)
						)
					)
				)
				(pin bidirectional line
					(at 0 -39.37 0)
					(length 5.08)
					(name "MGTXRXN3_117"
						(effects
							(font
								(size 1.27 1.27)
							)
						)
					)
					(number "F5"
						(effects
							(font
								(size 1.27 1.27)
							)
						)
					)
				)
				(pin bidirectional line
					(at 0 -43.18 0)
					(length 5.08)
					(name "MGTREFCLK0P_117"
						(effects
							(font
								(size 1.27 1.27)
							)
						)
					)
					(number "G8"
						(effects
							(font
								(size 1.27 1.27)
							)
						)
					)
				)
				(pin bidirectional line
					(at 0 -45.72 0)
					(length 5.08)
					(name "MGTREFCLK0N_117"
						(effects
							(font
								(size 1.27 1.27)
							)
						)
					)
					(number "G7"
						(effects
							(font
								(size 1.27 1.27)
							)
						)
					)
				)
				(pin bidirectional line
					(at 0 -48.26 0)
					(length 5.08)
					(name "MGTREFCLK1P_117"
						(effects
							(font
								(size 1.27 1.27)
							)
						)
					)
					(number "J8"
						(effects
							(font
								(size 1.27 1.27)
							)
						)
					)
				)
				(pin bidirectional line
					(at 0 -50.8 0)
					(length 5.08)
					(name "MGTREFCLK1N_117"
						(effects
							(font
								(size 1.27 1.27)
							)
						)
					)
					(number "J7"
						(effects
							(font
								(size 1.27 1.27)
							)
						)
					)
				)
				(pin bidirectional line
					(at 48.26 0 180)
					(length 5.08)
					(name "MGTXTXP0_118"
						(effects
							(font
								(size 1.27 1.27)
							)
						)
					)
					(number "D2"
						(effects
							(font
								(size 1.27 1.27)
							)
						)
					)
				)
				(pin bidirectional line
					(at 48.26 -2.54 180)
					(length 5.08)
					(name "MGTXTXN0_118"
						(effects
							(font
								(size 1.27 1.27)
							)
						)
					)
					(number "D1"
						(effects
							(font
								(size 1.27 1.27)
							)
						)
					)
				)
				(pin bidirectional line
					(at 48.26 -5.08 180)
					(length 5.08)
					(name "MGTXTXP1_118"
						(effects
							(font
								(size 1.27 1.27)
							)
						)
					)
					(number "C4"
						(effects
							(font
								(size 1.27 1.27)
							)
						)
					)
				)
				(pin bidirectional line
					(at 48.26 -7.62 180)
					(length 5.08)
					(name "MGTXTXN1_118"
						(effects
							(font
								(size 1.27 1.27)
							)
						)
					)
					(number "C3"
						(effects
							(font
								(size 1.27 1.27)
							)
						)
					)
				)
				(pin bidirectional line
					(at 48.26 -10.16 180)
					(length 5.08)
					(name "MGTXTXP2_118"
						(effects
							(font
								(size 1.27 1.27)
							)
						)
					)
					(number "B2"
						(effects
							(font
								(size 1.27 1.27)
							)
						)
					)
				)
				(pin bidirectional line
					(at 48.26 -12.7 180)
					(length 5.08)
					(name "MGTXTXN2_118"
						(effects
							(font
								(size 1.27 1.27)
							)
						)
					)
					(number "B1"
						(effects
							(font
								(size 1.27 1.27)
							)
						)
					)
				)
				(pin bidirectional line
					(at 48.26 -15.24 180)
					(length 5.08)
					(name "MGTXTXP3_118"
						(effects
							(font
								(size 1.27 1.27)
							)
						)
					)
					(number "A4"
						(effects
							(font
								(size 1.27 1.27)
							)
						)
					)
				)
				(pin bidirectional line
					(at 48.26 -17.78 180)
					(length 5.08)
					(name "MGTXTXN3_118"
						(effects
							(font
								(size 1.27 1.27)
							)
						)
					)
					(number "A3"
						(effects
							(font
								(size 1.27 1.27)
							)
						)
					)
				)
				(pin bidirectional line
					(at 48.26 -21.59 180)
					(length 5.08)
					(name "MGTXRXP0_118"
						(effects
							(font
								(size 1.27 1.27)
							)
						)
					)
					(number "E4"
						(effects
							(font
								(size 1.27 1.27)
							)
						)
					)
				)
				(pin bidirectional line
					(at 48.26 -24.13 180)
					(length 5.08)
					(name "MGTXRXN0_118"
						(effects
							(font
								(size 1.27 1.27)
							)
						)
					)
					(number "E3"
						(effects
							(font
								(size 1.27 1.27)
							)
						)
					)
				)
				(pin bidirectional line
					(at 48.26 -26.67 180)
					(length 5.08)
					(name "MGTXRXP1_118"
						(effects
							(font
								(size 1.27 1.27)
							)
						)
					)
					(number "D6"
						(effects
							(font
								(size 1.27 1.27)
							)
						)
					)
				)
				(pin bidirectional line
					(at 48.26 -29.21 180)
					(length 5.08)
					(name "MGTXRXN1_118"
						(effects
							(font
								(size 1.27 1.27)
							)
						)
					)
					(number "D5"
						(effects
							(font
								(size 1.27 1.27)
							)
						)
					)
				)
				(pin bidirectional line
					(at 48.26 -31.75 180)
					(length 5.08)
					(name "MGTXRXP2_118"
						(effects
							(font
								(size 1.27 1.27)
							)
						)
					)
					(number "B6"
						(effects
							(font
								(size 1.27 1.27)
							)
						)
					)
				)
				(pin bidirectional line
					(at 48.26 -34.29 180)
					(length 5.08)
					(name "MGTXRXN2_118"
						(effects
							(font
								(size 1.27 1.27)
							)
						)
					)
					(number "B5"
						(effects
							(font
								(size 1.27 1.27)
							)
						)
					)
				)
				(pin bidirectional line
					(at 48.26 -36.83 180)
					(length 5.08)
					(name "MGTXRXP3_118"
						(effects
							(font
								(size 1.27 1.27)
							)
						)
					)
					(number "A8"
						(effects
							(font
								(size 1.27 1.27)
							)
						)
					)
				)
				(pin bidirectional line
					(at 48.26 -39.37 180)
					(length 5.08)
					(name "MGTXRXN3_118"
						(effects
							(font
								(size 1.27 1.27)
							)
						)
					)
					(number "A7"
						(effects
							(font
								(size 1.27 1.27)
							)
						)
					)
				)
				(pin bidirectional line
					(at 48.26 -43.18 180)
					(length 5.08)
					(name "MGTREFCLK0P_118"
						(effects
							(font
								(size 1.27 1.27)
							)
						)
					)
					(number "C8"
						(effects
							(font
								(size 1.27 1.27)
							)
						)
					)
				)
				(pin bidirectional line
					(at 48.26 -45.72 180)
					(length 5.08)
					(name "MGTREFCLK0N_118"
						(effects
							(font
								(size 1.27 1.27)
							)
						)
					)
					(number "C7"
						(effects
							(font
								(size 1.27 1.27)
							)
						)
					)
				)
				(pin bidirectional line
					(at 48.26 -48.26 180)
					(length 5.08)
					(name "MGTREFCLK1P_118"
						(effects
							(font
								(size 1.27 1.27)
							)
						)
					)
					(number "E8"
						(effects
							(font
								(size 1.27 1.27)
							)
						)
					)
				)
				(pin bidirectional line
					(at 48.26 -50.8 180)
					(length 5.08)
					(name "MGTREFCLK1N_118"
						(effects
							(font
								(size 1.27 1.27)
							)
						)
					)
					(number "E7"
						(effects
							(font
								(size 1.27 1.27)
							)
						)
					)
				)
			)
			(symbol "XC7K410T-2FFG900I_1_8_1"
				(rectangle
					(start 5.08 2.54)
					(end 24.13 -13.97)
					(stroke
						(width 0.254)
						(type default)
					)
					(fill
						(type background)
					)
				)
				(pin bidirectional line
					(at 0 0 0)
					(length 5.08)
					(name "MGTAVCC"
						(effects
							(font
								(size 1.27 1.27)
							)
						)
					)
					(number "B7"
						(effects
							(font
								(size 1.27 1.27)
							)
						)
					)
				)
				(pin passive line
					(at 0 0 0)
					(length 5.08)
					(hide yes)
					(name "MGTAVCC"
						(effects
							(font
								(size 1.27 1.27)
							)
						)
					)
					(number "D7"
						(effects
							(font
								(size 1.27 1.27)
							)
						)
					)
				)
				(pin passive line
					(at 0 0 0)
					(length 5.08)
					(hide yes)
					(name "MGTAVCC"
						(effects
							(font
								(size 1.27 1.27)
							)
						)
					)
					(number "F7"
						(effects
							(font
								(size 1.27 1.27)
							)
						)
					)
				)
				(pin passive line
					(at 0 0 0)
					(length 5.08)
					(hide yes)
					(name "MGTAVCC"
						(effects
							(font
								(size 1.27 1.27)
							)
						)
					)
					(number "H7"
						(effects
							(font
								(size 1.27 1.27)
							)
						)
					)
				)
				(pin passive line
					(at 0 0 0)
					(length 5.08)
					(hide yes)
					(name "MGTAVCC"
						(effects
							(font
								(size 1.27 1.27)
							)
						)
					)
					(number "K7"
						(effects
							(font
								(size 1.27 1.27)
							)
						)
					)
				)
				(pin passive line
					(at 0 0 0)
					(length 5.08)
					(hide yes)
					(name "MGTAVCC"
						(effects
							(font
								(size 1.27 1.27)
							)
						)
					)
					(number "M7"
						(effects
							(font
								(size 1.27 1.27)
							)
						)
					)
				)
				(pin passive line
					(at 0 0 0)
					(length 5.08)
					(hide yes)
					(name "MGTAVCC"
						(effects
							(font
								(size 1.27 1.27)
							)
						)
					)
					(number "P7"
						(effects
							(font
								(size 1.27 1.27)
							)
						)
					)
				)
				(pin bidirectional line
					(at 0 -2.54 0)
					(length 5.08)
					(name "MGTVCCAUX"
						(effects
							(font
								(size 1.27 1.27)
							)
						)
					)
					(number "T7"
						(effects
							(font
								(size 1.27 1.27)
							)
						)
					)
				)
				(pin passive line
					(at 0 -2.54 0)
					(length 5.08)
					(hide yes)
					(name "MGTVCCAUX"
						(effects
							(font
								(size 1.27 1.27)
							)
						)
					)
					(number "V7"
						(effects
							(font
								(size 1.27 1.27)
							)
						)
					)
				)
				(pin bidirectional line
					(at 0 -6.35 0)
					(length 5.08)
					(name "MGTAVTTRCAL_115"
						(effects
							(font
								(size 1.27 1.27)
							)
						)
					)
					(number "W7"
						(effects
							(font
								(size 1.27 1.27)
							)
						)
					)
				)
				(pin bidirectional line
					(at 0 -8.89 0)
					(length 5.08)
					(name "MGTAVTT"
						(effects
							(font
								(size 1.27 1.27)
							)
						)
					)
					(number "B3"
						(effects
							(font
								(size 1.27 1.27)
							)
						)
					)
				)
				(pin passive line
					(at 0 -8.89 0)
					(length 5.08)
					(hide yes)
					(name "MGTAVTT"
						(effects
							(font
								(size 1.27 1.27)
							)
						)
					)
					(number "C5"
						(effects
							(font
								(size 1.27 1.27)
							)
						)
					)
				)
				(pin passive line
					(at 0 -8.89 0)
					(length 5.08)
					(hide yes)
					(name "MGTAVTT"
						(effects
							(font
								(size 1.27 1.27)
							)
						)
					)
					(number "D3"
						(effects
							(font
								(size 1.27 1.27)
							)
						)
					)
				)
				(pin passive line
					(at 0 -8.89 0)
					(length 5.08)
					(hide yes)
					(name "MGTAVTT"
						(effects
							(font
								(size 1.27 1.27)
							)
						)
					)
					(number "E5"
						(effects
							(font
								(size 1.27 1.27)
							)
						)
					)
				)
				(pin passive line
					(at 0 -8.89 0)
					(length 5.08)
					(hide yes)
					(name "MGTAVTT"
						(effects
							(font
								(size 1.27 1.27)
							)
						)
					)
					(number "F3"
						(effects
							(font
								(size 1.27 1.27)
							)
						)
					)
				)
				(pin passive line
					(at 0 -8.89 0)
					(length 5.08)
					(hide yes)
					(name "MGTAVTT"
						(effects
							(font
								(size 1.27 1.27)
							)
						)
					)
					(number "G5"
						(effects
							(font
								(size 1.27 1.27)
							)
						)
					)
				)
				(pin passive line
					(at 0 -8.89 0)
					(length 5.08)
					(hide yes)
					(name "MGTAVTT"
						(effects
							(font
								(size 1.27 1.27)
							)
						)
					)
					(number "H3"
						(effects
							(font
								(size 1.27 1.27)
							)
						)
					)
				)
				(pin passive line
					(at 0 -8.89 0)
					(length 5.08)
					(hide yes)
					(name "MGTAVTT"
						(effects
							(font
								(size 1.27 1.27)
							)
						)
					)
					(number "J5"
						(effects
							(font
								(size 1.27 1.27)
							)
						)
					)
				)
				(pin passive line
					(at 0 -8.89 0)
					(length 5.08)
					(hide yes)
					(name "MGTAVTT"
						(effects
							(font
								(size 1.27 1.27)
							)
						)
					)
					(number "K3"
						(effects
							(font
								(size 1.27 1.27)
							)
						)
					)
				)
				(pin passive line
					(at 0 -8.89 0)
					(length 5.08)
					(hide yes)
					(name "MGTAVTT"
						(effects
							(font
								(size 1.27 1.27)
							)
						)
					)
					(number "L5"
						(effects
							(font
								(size 1.27 1.27)
							)
						)
					)
				)
				(pin passive line
					(at 0 -8.89 0)
					(length 5.08)
					(hide yes)
					(name "MGTAVTT"
						(effects
							(font
								(size 1.27 1.27)
							)
						)
					)
					(number "M3"
						(effects
							(font
								(size 1.27 1.27)
							)
						)
					)
				)
				(pin passive line
					(at 0 -8.89 0)
					(length 5.08)
					(hide yes)
					(name "MGTAVTT"
						(effects
							(font
								(size 1.27 1.27)
							)
						)
					)
					(number "N5"
						(effects
							(font
								(size 1.27 1.27)
							)
						)
					)
				)
				(pin passive line
					(at 0 -8.89 0)
					(length 5.08)
					(hide yes)
					(name "MGTAVTT"
						(effects
							(font
								(size 1.27 1.27)
							)
						)
					)
					(number "P3"
						(effects
							(font
								(size 1.27 1.27)
							)
						)
					)
				)
				(pin passive line
					(at 0 -8.89 0)
					(length 5.08)
					(hide yes)
					(name "MGTAVTT"
						(effects
							(font
								(size 1.27 1.27)
							)
						)
					)
					(number "R5"
						(effects
							(font
								(size 1.27 1.27)
							)
						)
					)
				)
				(pin passive line
					(at 0 -8.89 0)
					(length 5.08)
					(hide yes)
					(name "MGTAVTT"
						(effects
							(font
								(size 1.27 1.27)
							)
						)
					)
					(number "T3"
						(effects
							(font
								(size 1.27 1.27)
							)
						)
					)
				)
				(pin passive line
					(at 0 -8.89 0)
					(length 5.08)
					(hide yes)
					(name "MGTAVTT"
						(effects
							(font
								(size 1.27 1.27)
							)
						)
					)
					(number "U5"
						(effects
							(font
								(size 1.27 1.27)
							)
						)
					)
				)
				(pin passive line
					(at 0 -8.89 0)
					(length 5.08)
					(hide yes)
					(name "MGTAVTT"
						(effects
							(font
								(size 1.27 1.27)
							)
						)
					)
					(number "V3"
						(effects
							(font
								(size 1.27 1.27)
							)
						)
					)
				)
				(pin passive line
					(at 0 -8.89 0)
					(length 5.08)
					(hide yes)
					(name "MGTAVTT"
						(effects
							(font
								(size 1.27 1.27)
							)
						)
					)
					(number "W5"
						(effects
							(font
								(size 1.27 1.27)
							)
						)
					)
				)
				(pin bidirectional line
					(at 0 -11.43 0)
					(length 5.08)
					(name "MGTRREF_115"
						(effects
							(font
								(size 1.27 1.27)
							)
						)
					)
					(number "W8"
						(effects
							(font
								(size 1.27 1.27)
							)
						)
					)
				)
			)
			(symbol "XC7K410T-2FFG900I_1_9_1"
				(rectangle
					(start 5.08 2.54)
					(end 27.94 -29.21)
					(stroke
						(width 0.254)
						(type default)
					)
					(fill
						(type background)
					)
				)
				(pin bidirectional line
					(at 0 0 0)
					(length 5.08)
					(name "VCCO_0"
						(effects
							(font
								(size 1.27 1.27)
							)
						)
					)
					(number "AB6"
						(effects
							(font
								(size 1.27 1.27)
							)
						)
					)
				)
				(pin passive line
					(at 0 0 0)
					(length 5.08)
					(hide yes)
					(name "VCCO_0"
						(effects
							(font
								(size 1.27 1.27)
							)
						)
					)
					(number "T9"
						(effects
							(font
								(size 1.27 1.27)
							)
						)
					)
				)
				(pin bidirectional line
					(at 0 -3.81 0)
					(length 5.08)
					(name "CCLK_0"
						(effects
							(font
								(size 1.27 1.27)
							)
						)
					)
					(number "B10"
						(effects
							(font
								(size 1.27 1.27)
							)
						)
					)
				)
				(pin bidirectional line
					(at 0 -6.35 0)
					(length 5.08)
					(name "M0_0"
						(effects
							(font
								(size 1.27 1.27)
							)
						)
					)
					(number "AB5"
						(effects
							(font
								(size 1.27 1.27)
							)
						)
					)
				)
				(pin bidirectional line
					(at 0 -8.89 0)
					(length 5.08)
					(name "M1_0"
						(effects
							(font
								(size 1.27 1.27)
							)
						)
					)
					(number "AB2"
						(effects
							(font
								(size 1.27 1.27)
							)
						)
					)
				)
				(pin bidirectional line
					(at 0 -11.43 0)
					(length 5.08)
					(name "M2_0"
						(effects
							(font
								(size 1.27 1.27)
							)
						)
					)
					(number "AB1"
						(effects
							(font
								(size 1.27 1.27)
							)
						)
					)
				)
				(pin bidirectional line
					(at 0 -15.24 0)
					(length 5.08)
					(name "TDI_0"
						(effects
							(font
								(size 1.27 1.27)
							)
						)
					)
					(number "H10"
						(effects
							(font
								(size 1.27 1.27)
							)
						)
					)
				)
				(pin bidirectional line
					(at 0 -17.78 0)
					(length 5.08)
					(name "TDO_0"
						(effects
							(font
								(size 1.27 1.27)
							)
						)
					)
					(number "G10"
						(effects
							(font
								(size 1.27 1.27)
							)
						)
					)
				)
				(pin bidirectional line
					(at 0 -20.32 0)
					(length 5.08)
					(name "TMS_0"
						(effects
							(font
								(size 1.27 1.27)
							)
						)
					)
					(number "F10"
						(effects
							(font
								(size 1.27 1.27)
							)
						)
					)
				)
				(pin bidirectional line
					(at 0 -22.86 0)
					(length 5.08)
					(name "TCK_0"
						(effects
							(font
								(size 1.27 1.27)
							)
						)
					)
					(number "E10"
						(effects
							(font
								(size 1.27 1.27)
							)
						)
					)
				)
				(pin bidirectional line
					(at 0 -26.67 0)
					(length 5.08)
					(name "CFGBVS_0"
						(effects
							(font
								(size 1.27 1.27)
							)
						)
					)
					(number "L10"
						(effects
							(font
								(size 1.27 1.27)
							)
						)
					)
				)
				(pin bidirectional line
					(at 33.02 0 180)
					(length 5.08)
					(name "DONE_0"
						(effects
							(font
								(size 1.27 1.27)
							)
						)
					)
					(number "M10"
						(effects
							(font
								(size 1.27 1.27)
							)
						)
					)
				)
				(pin bidirectional line
					(at 33.02 -2.54 180)
					(length 5.08)
					(name "INIT_B_0"
						(effects
							(font
								(size 1.27 1.27)
							)
						)
					)
					(number "A10"
						(effects
							(font
								(size 1.27 1.27)
							)
						)
					)
				)
				(pin bidirectional line
					(at 33.02 -5.08 180)
					(length 5.08)
					(name "PROGRAM_B_0"
						(effects
							(font
								(size 1.27 1.27)
							)
						)
					)
					(number "K10"
						(effects
							(font
								(size 1.27 1.27)
							)
						)
					)
				)
				(pin bidirectional line
					(at 33.02 -8.89 180)
					(length 5.08)
					(name "VP_0"
						(effects
							(font
								(size 1.27 1.27)
							)
						)
					)
					(number "R15"
						(effects
							(font
								(size 1.27 1.27)
							)
						)
					)
				)
				(pin bidirectional line
					(at 33.02 -11.43 180)
					(length 5.08)
					(name "VN_0"
						(effects
							(font
								(size 1.27 1.27)
							)
						)
					)
					(number "T14"
						(effects
							(font
								(size 1.27 1.27)
							)
						)
					)
				)
				(pin bidirectional line
					(at 33.02 -15.24 180)
					(length 5.08)
					(name "VREFP_0"
						(effects
							(font
								(size 1.27 1.27)
							)
						)
					)
					(number "T15"
						(effects
							(font
								(size 1.27 1.27)
							)
						)
					)
				)
				(pin bidirectional line
					(at 33.02 -17.78 180)
					(length 5.08)
					(name "VREFN_0"
						(effects
							(font
								(size 1.27 1.27)
							)
						)
					)
					(number "R14"
						(effects
							(font
								(size 1.27 1.27)
							)
						)
					)
				)
				(pin bidirectional line
					(at 33.02 -21.59 180)
					(length 5.08)
					(name "DXP_0"
						(effects
							(font
								(size 1.27 1.27)
							)
						)
					)
					(number "U15"
						(effects
							(font
								(size 1.27 1.27)
							)
						)
					)
				)
				(pin bidirectional line
					(at 33.02 -24.13 180)
					(length 5.08)
					(name "DXN_0"
						(effects
							(font
								(size 1.27 1.27)
							)
						)
					)
					(number "U14"
						(effects
							(font
								(size 1.27 1.27)
							)
						)
					)
				)
			)
			(symbol "XC7K410T-2FFG900I_1_10_1"
				(rectangle
					(start 5.08 2.54)
					(end 20.32 -21.59)
					(stroke
						(width 0.254)
						(type default)
					)
					(fill
						(type background)
					)
				)
				(pin bidirectional line
					(at 0 0 0)
					(length 5.08)
					(name "VCCAUX"
						(effects
							(font
								(size 1.27 1.27)
							)
						)
					)
					(number "P13"
						(effects
							(font
								(size 1.27 1.27)
							)
						)
					)
				)
				(pin passive line
					(at 0 0 0)
					(length 5.08)
					(hide yes)
					(name "VCCAUX"
						(effects
							(font
								(size 1.27 1.27)
							)
						)
					)
					(number "T13"
						(effects
							(font
								(size 1.27 1.27)
							)
						)
					)
				)
				(pin passive line
					(at 0 0 0)
					(length 5.08)
					(hide yes)
					(name "VCCAUX"
						(effects
							(font
								(size 1.27 1.27)
							)
						)
					)
					(number "V13"
						(effects
							(font
								(size 1.27 1.27)
							)
						)
					)
				)
				(pin passive line
					(at 0 0 0)
					(length 5.08)
					(hide yes)
					(name "VCCAUX"
						(effects
							(font
								(size 1.27 1.27)
							)
						)
					)
					(number "V15"
						(effects
							(font
								(size 1.27 1.27)
							)
						)
					)
				)
				(pin passive line
					(at 0 0 0)
					(length 5.08)
					(hide yes)
					(name "VCCAUX"
						(effects
							(font
								(size 1.27 1.27)
							)
						)
					)
					(number "W14"
						(effects
							(font
								(size 1.27 1.27)
							)
						)
					)
				)
				(pin bidirectional line
					(at 0 -2.54 0)
					(length 5.08)
					(name "VCCAUX_IO_G0"
						(effects
							(font
								(size 1.27 1.27)
							)
						)
					)
					(number "V11"
						(effects
							(font
								(size 1.27 1.27)
							)
						)
					)
				)
				(pin passive line
					(at 0 -2.54 0)
					(length 5.08)
					(hide yes)
					(name "VCCAUX_IO_G0"
						(effects
							(font
								(size 1.27 1.27)
							)
						)
					)
					(number "W10"
						(effects
							(font
								(size 1.27 1.27)
							)
						)
					)
				)
				(pin passive line
					(at 0 -2.54 0)
					(length 5.08)
					(hide yes)
					(name "VCCAUX_IO_G0"
						(effects
							(font
								(size 1.27 1.27)
							)
						)
					)
					(number "W12"
						(effects
							(font
								(size 1.27 1.27)
							)
						)
					)
				)
				(pin bidirectional line
					(at 0 -5.08 0)
					(length 5.08)
					(name "VCCADC_0"
						(effects
							(font
								(size 1.27 1.27)
							)
						)
					)
					(number "P15"
						(effects
							(font
								(size 1.27 1.27)
							)
						)
					)
				)
				(pin bidirectional line
					(at 0 -7.62 0)
					(length 5.08)
					(name "VCCBRAM"
						(effects
							(font
								(size 1.27 1.27)
							)
						)
					)
					(number "N16"
						(effects
							(font
								(size 1.27 1.27)
							)
						)
					)
				)
				(pin passive line
					(at 0 -7.62 0)
					(length 5.08)
					(hide yes)
					(name "VCCBRAM"
						(effects
							(font
								(size 1.27 1.27)
							)
						)
					)
					(number "R16"
						(effects
							(font
								(size 1.27 1.27)
							)
						)
					)
				)
				(pin passive line
					(at 0 -7.62 0)
					(length 5.08)
					(hide yes)
					(name "VCCBRAM"
						(effects
							(font
								(size 1.27 1.27)
							)
						)
					)
					(number "U16"
						(effects
							(font
								(size 1.27 1.27)
							)
						)
					)
				)
				(pin passive line
					(at 0 -7.62 0)
					(length 5.08)
					(hide yes)
					(name "VCCBRAM"
						(effects
							(font
								(size 1.27 1.27)
							)
						)
					)
					(number "W16"
						(effects
							(font
								(size 1.27 1.27)
							)
						)
					)
				)
				(pin bidirectional line
					(at 0 -10.16 0)
					(length 5.08)
					(name "VCCINT"
						(effects
							(font
								(size 1.27 1.27)
							)
						)
					)
					(number "M11"
						(effects
							(font
								(size 1.27 1.27)
							)
						)
					)
				)
				(pin passive line
					(at 0 -10.16 0)
					(length 5.08)
					(hide yes)
					(name "VCCINT"
						(effects
							(font
								(size 1.27 1.27)
							)
						)
					)
					(number "M13"
						(effects
							(font
								(size 1.27 1.27)
							)
						)
					)
				)
				(pin passive line
					(at 0 -10.16 0)
					(length 5.08)
					(hide yes)
					(name "VCCINT"
						(effects
							(font
								(size 1.27 1.27)
							)
						)
					)
					(number "M15"
						(effects
							(font
								(size 1.27 1.27)
							)
						)
					)
				)
				(pin passive line
					(at 0 -10.16 0)
					(length 5.08)
					(hide yes)
					(name "VCCINT"
						(effects
							(font
								(size 1.27 1.27)
							)
						)
					)
					(number "M17"
						(effects
							(font
								(size 1.27 1.27)
							)
						)
					)
				)
				(pin passive line
					(at 0 -10.16 0)
					(length 5.08)
					(hide yes)
					(name "VCCINT"
						(effects
							(font
								(size 1.27 1.27)
							)
						)
					)
					(number "N10"
						(effects
							(font
								(size 1.27 1.27)
							)
						)
					)
				)
				(pin passive line
					(at 0 -10.16 0)
					(length 5.08)
					(hide yes)
					(name "VCCINT"
						(effects
							(font
								(size 1.27 1.27)
							)
						)
					)
					(number "N12"
						(effects
							(font
								(size 1.27 1.27)
							)
						)
					)
				)
				(pin passive line
					(at 0 -10.16 0)
					(length 5.08)
					(hide yes)
					(name "VCCINT"
						(effects
							(font
								(size 1.27 1.27)
							)
						)
					)
					(number "N14"
						(effects
							(font
								(size 1.27 1.27)
							)
						)
					)
				)
				(pin passive line
					(at 0 -10.16 0)
					(length 5.08)
					(hide yes)
					(name "VCCINT"
						(effects
							(font
								(size 1.27 1.27)
							)
						)
					)
					(number "N18"
						(effects
							(font
								(size 1.27 1.27)
							)
						)
					)
				)
				(pin passive line
					(at 0 -10.16 0)
					(length 5.08)
					(hide yes)
					(name "VCCINT"
						(effects
							(font
								(size 1.27 1.27)
							)
						)
					)
					(number "P11"
						(effects
							(font
								(size 1.27 1.27)
							)
						)
					)
				)
				(pin passive line
					(at 0 -10.16 0)
					(length 5.08)
					(hide yes)
					(name "VCCINT"
						(effects
							(font
								(size 1.27 1.27)
							)
						)
					)
					(number "P17"
						(effects
							(font
								(size 1.27 1.27)
							)
						)
					)
				)
				(pin passive line
					(at 0 -10.16 0)
					(length 5.08)
					(hide yes)
					(name "VCCINT"
						(effects
							(font
								(size 1.27 1.27)
							)
						)
					)
					(number "R10"
						(effects
							(font
								(size 1.27 1.27)
							)
						)
					)
				)
				(pin passive line
					(at 0 -10.16 0)
					(length 5.08)
					(hide yes)
					(name "VCCINT"
						(effects
							(font
								(size 1.27 1.27)
							)
						)
					)
					(number "R12"
						(effects
							(font
								(size 1.27 1.27)
							)
						)
					)
				)
				(pin passive line
					(at 0 -10.16 0)
					(length 5.08)
					(hide yes)
					(name "VCCINT"
						(effects
							(font
								(size 1.27 1.27)
							)
						)
					)
					(number "R18"
						(effects
							(font
								(size 1.27 1.27)
							)
						)
					)
				)
				(pin passive line
					(at 0 -10.16 0)
					(length 5.08)
					(hide yes)
					(name "VCCINT"
						(effects
							(font
								(size 1.27 1.27)
							)
						)
					)
					(number "T11"
						(effects
							(font
								(size 1.27 1.27)
							)
						)
					)
				)
				(pin passive line
					(at 0 -10.16 0)
					(length 5.08)
					(hide yes)
					(name "VCCINT"
						(effects
							(font
								(size 1.27 1.27)
							)
						)
					)
					(number "T17"
						(effects
							(font
								(size 1.27 1.27)
							)
						)
					)
				)
				(pin passive line
					(at 0 -10.16 0)
					(length 5.08)
					(hide yes)
					(name "VCCINT"
						(effects
							(font
								(size 1.27 1.27)
							)
						)
					)
					(number "U10"
						(effects
							(font
								(size 1.27 1.27)
							)
						)
					)
				)
				(pin passive line
					(at 0 -10.16 0)
					(length 5.08)
					(hide yes)
					(name "VCCINT"
						(effects
							(font
								(size 1.27 1.27)
							)
						)
					)
					(number "U12"
						(effects
							(font
								(size 1.27 1.27)
							)
						)
					)
				)
				(pin passive line
					(at 0 -10.16 0)
					(length 5.08)
					(hide yes)
					(name "VCCINT"
						(effects
							(font
								(size 1.27 1.27)
							)
						)
					)
					(number "U18"
						(effects
							(font
								(size 1.27 1.27)
							)
						)
					)
				)
				(pin passive line
					(at 0 -10.16 0)
					(length 5.08)
					(hide yes)
					(name "VCCINT"
						(effects
							(font
								(size 1.27 1.27)
							)
						)
					)
					(number "V17"
						(effects
							(font
								(size 1.27 1.27)
							)
						)
					)
				)
				(pin passive line
					(at 0 -10.16 0)
					(length 5.08)
					(hide yes)
					(name "VCCINT"
						(effects
							(font
								(size 1.27 1.27)
							)
						)
					)
					(number "W18"
						(effects
							(font
								(size 1.27 1.27)
							)
						)
					)
				)
				(pin bidirectional line
					(at 0 -12.7 0)
					(length 5.08)
					(name "VCCBATT_0"
						(effects
							(font
								(size 1.27 1.27)
							)
						)
					)
					(number "C10"
						(effects
							(font
								(size 1.27 1.27)
							)
						)
					)
				)
				(pin bidirectional line
					(at 0 -16.51 0)
					(length 5.08)
					(name "GNDADC_0"
						(effects
							(font
								(size 1.27 1.27)
							)
						)
					)
					(number "P14"
						(effects
							(font
								(size 1.27 1.27)
							)
						)
					)
				)
				(pin bidirectional line
					(at 0 -19.05 0)
					(length 5.08)
					(name "GND"
						(effects
							(font
								(size 1.27 1.27)
							)
						)
					)
					(number "A1"
						(effects
							(font
								(size 1.27 1.27)
							)
						)
					)
				)
				(pin passive line
					(at 0 -19.05 0)
					(length 5.08)
					(hide yes)
					(name "GND"
						(effects
							(font
								(size 1.27 1.27)
							)
						)
					)
					(number "A14"
						(effects
							(font
								(size 1.27 1.27)
							)
						)
					)
				)
				(pin passive line
					(at 0 -19.05 0)
					(length 5.08)
					(hide yes)
					(name "GND"
						(effects
							(font
								(size 1.27 1.27)
							)
						)
					)
					(number "A2"
						(effects
							(font
								(size 1.27 1.27)
							)
						)
					)
				)
				(pin passive line
					(at 0 -19.05 0)
					(length 5.08)
					(hide yes)
					(name "GND"
						(effects
							(font
								(size 1.27 1.27)
							)
						)
					)
					(number "A24"
						(effects
							(font
								(size 1.27 1.27)
							)
						)
					)
				)
				(pin passive line
					(at 0 -19.05 0)
					(length 5.08)
					(hide yes)
					(name "GND"
						(effects
							(font
								(size 1.27 1.27)
							)
						)
					)
					(number "A5"
						(effects
							(font
								(size 1.27 1.27)
							)
						)
					)
				)
				(pin passive line
					(at 0 -19.05 0)
					(length 5.08)
					(hide yes)
					(name "GND"
						(effects
							(font
								(size 1.27 1.27)
							)
						)
					)
					(number "A6"
						(effects
							(font
								(size 1.27 1.27)
							)
						)
					)
				)
				(pin passive line
					(at 0 -19.05 0)
					(length 5.08)
					(hide yes)
					(name "GND"
						(effects
							(font
								(size 1.27 1.27)
							)
						)
					)
					(number "A9"
						(effects
							(font
								(size 1.27 1.27)
							)
						)
					)
				)
				(pin passive line
					(at 0 -19.05 0)
					(length 5.08)
					(hide yes)
					(name "GND"
						(effects
							(font
								(size 1.27 1.27)
							)
						)
					)
					(number "AA1"
						(effects
							(font
								(size 1.27 1.27)
							)
						)
					)
				)
				(pin passive line
					(at 0 -19.05 0)
					(length 5.08)
					(hide yes)
					(name "GND"
						(effects
							(font
								(size 1.27 1.27)
							)
						)
					)
					(number "AA14"
						(effects
							(font
								(size 1.27 1.27)
							)
						)
					)
				)
				(pin passive line
					(at 0 -19.05 0)
					(length 5.08)
					(hide yes)
					(name "GND"
						(effects
							(font
								(size 1.27 1.27)
							)
						)
					)
					(number "AA2"
						(effects
							(font
								(size 1.27 1.27)
							)
						)
					)
				)
				(pin passive line
					(at 0 -19.05 0)
					(length 5.08)
					(hide yes)
					(name "GND"
						(effects
							(font
								(size 1.27 1.27)
							)
						)
					)
					(number "AA24"
						(effects
							(font
								(size 1.27 1.27)
							)
						)
					)
				)
				(pin passive line
					(at 0 -19.05 0)
					(length 5.08)
					(hide yes)
					(name "GND"
						(effects
							(font
								(size 1.27 1.27)
							)
						)
					)
					(number "AA5"
						(effects
							(font
								(size 1.27 1.27)
							)
						)
					)
				)
				(pin passive line
					(at 0 -19.05 0)
					(length 5.08)
					(hide yes)
					(name "GND"
						(effects
							(font
								(size 1.27 1.27)
							)
						)
					)
					(number "AA6"
						(effects
							(font
								(size 1.27 1.27)
							)
						)
					)
				)
				(pin passive line
					(at 0 -19.05 0)
					(length 5.08)
					(hide yes)
					(name "GND"
						(effects
							(font
								(size 1.27 1.27)
							)
						)
					)
					(number "AA7"
						(effects
							(font
								(size 1.27 1.27)
							)
						)
					)
				)
				(pin passive line
					(at 0 -19.05 0)
					(length 5.08)
					(hide yes)
					(name "GND"
						(effects
							(font
								(size 1.27 1.27)
							)
						)
					)
					(number "AB11"
						(effects
							(font
								(size 1.27 1.27)
							)
						)
					)
				)
				(pin passive line
					(at 0 -19.05 0)
					(length 5.08)
					(hide yes)
					(name "GND"
						(effects
							(font
								(size 1.27 1.27)
							)
						)
					)
					(number "AB21"
						(effects
							(font
								(size 1.27 1.27)
							)
						)
					)
				)
				(pin passive line
					(at 0 -19.05 0)
					(length 5.08)
					(hide yes)
					(name "GND"
						(effects
							(font
								(size 1.27 1.27)
							)
						)
					)
					(number "AB3"
						(effects
							(font
								(size 1.27 1.27)
							)
						)
					)
				)
				(pin passive line
					(at 0 -19.05 0)
					(length 5.08)
					(hide yes)
					(name "GND"
						(effects
							(font
								(size 1.27 1.27)
							)
						)
					)
					(number "AB4"
						(effects
							(font
								(size 1.27 1.27)
							)
						)
					)
				)
				(pin passive line
					(at 0 -19.05 0)
					(length 5.08)
					(hide yes)
					(name "GND"
						(effects
							(font
								(size 1.27 1.27)
							)
						)
					)
					(number "AC18"
						(effects
							(font
								(size 1.27 1.27)
							)
						)
					)
				)
				(pin passive line
					(at 0 -19.05 0)
					(length 5.08)
					(hide yes)
					(name "GND"
						(effects
							(font
								(size 1.27 1.27)
							)
						)
					)
					(number "AC28"
						(effects
							(font
								(size 1.27 1.27)
							)
						)
					)
				)
				(pin passive line
					(at 0 -19.05 0)
					(length 5.08)
					(hide yes)
					(name "GND"
						(effects
							(font
								(size 1.27 1.27)
							)
						)
					)
					(number "AC8"
						(effects
							(font
								(size 1.27 1.27)
							)
						)
					)
				)
				(pin passive line
					(at 0 -19.05 0)
					(length 5.08)
					(hide yes)
					(name "GND"
						(effects
							(font
								(size 1.27 1.27)
							)
						)
					)
					(number "AD15"
						(effects
							(font
								(size 1.27 1.27)
							)
						)
					)
				)
				(pin passive line
					(at 0 -19.05 0)
					(length 5.08)
					(hide yes)
					(name "GND"
						(effects
							(font
								(size 1.27 1.27)
							)
						)
					)
					(number "AD25"
						(effects
							(font
								(size 1.27 1.27)
							)
						)
					)
				)
				(pin passive line
					(at 0 -19.05 0)
					(length 5.08)
					(hide yes)
					(name "GND"
						(effects
							(font
								(size 1.27 1.27)
							)
						)
					)
					(number "AD5"
						(effects
							(font
								(size 1.27 1.27)
							)
						)
					)
				)
				(pin passive line
					(at 0 -19.05 0)
					(length 5.08)
					(hide yes)
					(name "GND"
						(effects
							(font
								(size 1.27 1.27)
							)
						)
					)
					(number "AE12"
						(effects
							(font
								(size 1.27 1.27)
							)
						)
					)
				)
				(pin passive line
					(at 0 -19.05 0)
					(length 5.08)
					(hide yes)
					(name "GND"
						(effects
							(font
								(size 1.27 1.27)
							)
						)
					)
					(number "AE2"
						(effects
							(font
								(size 1.27 1.27)
							)
						)
					)
				)
				(pin passive line
					(at 0 -19.05 0)
					(length 5.08)
					(hide yes)
					(name "GND"
						(effects
							(font
								(size 1.27 1.27)
							)
						)
					)
					(number "AE22"
						(effects
							(font
								(size 1.27 1.27)
							)
						)
					)
				)
				(pin passive line
					(at 0 -19.05 0)
					(length 5.08)
					(hide yes)
					(name "GND"
						(effects
							(font
								(size 1.27 1.27)
							)
						)
					)
					(number "AF19"
						(effects
							(font
								(size 1.27 1.27)
							)
						)
					)
				)
				(pin passive line
					(at 0 -19.05 0)
					(length 5.08)
					(hide yes)
					(name "GND"
						(effects
							(font
								(size 1.27 1.27)
							)
						)
					)
					(number "AF29"
						(effects
							(font
								(size 1.27 1.27)
							)
						)
					)
				)
				(pin passive line
					(at 0 -19.05 0)
					(length 5.08)
					(hide yes)
					(name "GND"
						(effects
							(font
								(size 1.27 1.27)
							)
						)
					)
					(number "AF9"
						(effects
							(font
								(size 1.27 1.27)
							)
						)
					)
				)
				(pin passive line
					(at 0 -19.05 0)
					(length 5.08)
					(hide yes)
					(name "GND"
						(effects
							(font
								(size 1.27 1.27)
							)
						)
					)
					(number "AG16"
						(effects
							(font
								(size 1.27 1.27)
							)
						)
					)
				)
				(pin passive line
					(at 0 -19.05 0)
					(length 5.08)
					(hide yes)
					(name "GND"
						(effects
							(font
								(size 1.27 1.27)
							)
						)
					)
					(number "AG26"
						(effects
							(font
								(size 1.27 1.27)
							)
						)
					)
				)
				(pin passive line
					(at 0 -19.05 0)
					(length 5.08)
					(hide yes)
					(name "GND"
						(effects
							(font
								(size 1.27 1.27)
							)
						)
					)
					(number "AG6"
						(effects
							(font
								(size 1.27 1.27)
							)
						)
					)
				)
				(pin passive line
					(at 0 -19.05 0)
					(length 5.08)
					(hide yes)
					(name "GND"
						(effects
							(font
								(size 1.27 1.27)
							)
						)
					)
					(number "AH13"
						(effects
							(font
								(size 1.27 1.27)
							)
						)
					)
				)
				(pin passive line
					(at 0 -19.05 0)
					(length 5.08)
					(hide yes)
					(name "GND"
						(effects
							(font
								(size 1.27 1.27)
							)
						)
					)
					(number "AH23"
						(effects
							(font
								(size 1.27 1.27)
							)
						)
					)
				)
				(pin passive line
					(at 0 -19.05 0)
					(length 5.08)
					(hide yes)
					(name "GND"
						(effects
							(font
								(size 1.27 1.27)
							)
						)
					)
					(number "AH3"
						(effects
							(font
								(size 1.27 1.27)
							)
						)
					)
				)
				(pin passive line
					(at 0 -19.05 0)
					(length 5.08)
					(hide yes)
					(name "GND"
						(effects
							(font
								(size 1.27 1.27)
							)
						)
					)
					(number "AJ10"
						(effects
							(font
								(size 1.27 1.27)
							)
						)
					)
				)
				(pin passive line
					(at 0 -19.05 0)
					(length 5.08)
					(hide yes)
					(name "GND"
						(effects
							(font
								(size 1.27 1.27)
							)
						)
					)
					(number "AJ20"
						(effects
							(font
								(size 1.27 1.27)
							)
						)
					)
				)
				(pin passive line
					(at 0 -19.05 0)
					(length 5.08)
					(hide yes)
					(name "GND"
						(effects
							(font
								(size 1.27 1.27)
							)
						)
					)
					(number "AJ30"
						(effects
							(font
								(size 1.27 1.27)
							)
						)
					)
				)
				(pin passive line
					(at 0 -19.05 0)
					(length 5.08)
					(hide yes)
					(name "GND"
						(effects
							(font
								(size 1.27 1.27)
							)
						)
					)
					(number "AK17"
						(effects
							(font
								(size 1.27 1.27)
							)
						)
					)
				)
				(pin passive line
					(at 0 -19.05 0)
					(length 5.08)
					(hide yes)
					(name "GND"
						(effects
							(font
								(size 1.27 1.27)
							)
						)
					)
					(number "AK27"
						(effects
							(font
								(size 1.27 1.27)
							)
						)
					)
				)
				(pin passive line
					(at 0 -19.05 0)
					(length 5.08)
					(hide yes)
					(name "GND"
						(effects
							(font
								(size 1.27 1.27)
							)
						)
					)
					(number "AK7"
						(effects
							(font
								(size 1.27 1.27)
							)
						)
					)
				)
				(pin passive line
					(at 0 -19.05 0)
					(length 5.08)
					(hide yes)
					(name "GND"
						(effects
							(font
								(size 1.27 1.27)
							)
						)
					)
					(number "B11"
						(effects
							(font
								(size 1.27 1.27)
							)
						)
					)
				)
				(pin passive line
					(at 0 -19.05 0)
					(length 5.08)
					(hide yes)
					(name "GND"
						(effects
							(font
								(size 1.27 1.27)
							)
						)
					)
					(number "B21"
						(effects
							(font
								(size 1.27 1.27)
							)
						)
					)
				)
				(pin passive line
					(at 0 -19.05 0)
					(length 5.08)
					(hide yes)
					(name "GND"
						(effects
							(font
								(size 1.27 1.27)
							)
						)
					)
					(number "B4"
						(effects
							(font
								(size 1.27 1.27)
							)
						)
					)
				)
				(pin passive line
					(at 0 -19.05 0)
					(length 5.08)
					(hide yes)
					(name "GND"
						(effects
							(font
								(size 1.27 1.27)
							)
						)
					)
					(number "B8"
						(effects
							(font
								(size 1.27 1.27)
							)
						)
					)
				)
				(pin passive line
					(at 0 -19.05 0)
					(length 5.08)
					(hide yes)
					(name "GND"
						(effects
							(font
								(size 1.27 1.27)
							)
						)
					)
					(number "B9"
						(effects
							(font
								(size 1.27 1.27)
							)
						)
					)
				)
				(pin passive line
					(at 0 -19.05 0)
					(length 5.08)
					(hide yes)
					(name "GND"
						(effects
							(font
								(size 1.27 1.27)
							)
						)
					)
					(number "C1"
						(effects
							(font
								(size 1.27 1.27)
							)
						)
					)
				)
				(pin passive line
					(at 0 -19.05 0)
					(length 5.08)
					(hide yes)
					(name "GND"
						(effects
							(font
								(size 1.27 1.27)
							)
						)
					)
					(number "C18"
						(effects
							(font
								(size 1.27 1.27)
							)
						)
					)
				)
				(pin passive line
					(at 0 -19.05 0)
					(length 5.08)
					(hide yes)
					(name "GND"
						(effects
							(font
								(size 1.27 1.27)
							)
						)
					)
					(number "C2"
						(effects
							(font
								(size 1.27 1.27)
							)
						)
					)
				)
				(pin passive line
					(at 0 -19.05 0)
					(length 5.08)
					(hide yes)
					(name "GND"
						(effects
							(font
								(size 1.27 1.27)
							)
						)
					)
					(number "C28"
						(effects
							(font
								(size 1.27 1.27)
							)
						)
					)
				)
				(pin passive line
					(at 0 -19.05 0)
					(length 5.08)
					(hide yes)
					(name "GND"
						(effects
							(font
								(size 1.27 1.27)
							)
						)
					)
					(number "C6"
						(effects
							(font
								(size 1.27 1.27)
							)
						)
					)
				)
				(pin passive line
					(at 0 -19.05 0)
					(length 5.08)
					(hide yes)
					(name "GND"
						(effects
							(font
								(size 1.27 1.27)
							)
						)
					)
					(number "C9"
						(effects
							(font
								(size 1.27 1.27)
							)
						)
					)
				)
				(pin passive line
					(at 0 -19.05 0)
					(length 5.08)
					(hide yes)
					(name "GND"
						(effects
							(font
								(size 1.27 1.27)
							)
						)
					)
					(number "D15"
						(effects
							(font
								(size 1.27 1.27)
							)
						)
					)
				)
				(pin passive line
					(at 0 -19.05 0)
					(length 5.08)
					(hide yes)
					(name "GND"
						(effects
							(font
								(size 1.27 1.27)
							)
						)
					)
					(number "D25"
						(effects
							(font
								(size 1.27 1.27)
							)
						)
					)
				)
				(pin passive line
					(at 0 -19.05 0)
					(length 5.08)
					(hide yes)
					(name "GND"
						(effects
							(font
								(size 1.27 1.27)
							)
						)
					)
					(number "D4"
						(effects
							(font
								(size 1.27 1.27)
							)
						)
					)
				)
				(pin passive line
					(at 0 -19.05 0)
					(length 5.08)
					(hide yes)
					(name "GND"
						(effects
							(font
								(size 1.27 1.27)
							)
						)
					)
					(number "D8"
						(effects
							(font
								(size 1.27 1.27)
							)
						)
					)
				)
				(pin passive line
					(at 0 -19.05 0)
					(length 5.08)
					(hide yes)
					(name "GND"
						(effects
							(font
								(size 1.27 1.27)
							)
						)
					)
					(number "D9"
						(effects
							(font
								(size 1.27 1.27)
							)
						)
					)
				)
				(pin passive line
					(at 0 -19.05 0)
					(length 5.08)
					(hide yes)
					(name "GND"
						(effects
							(font
								(size 1.27 1.27)
							)
						)
					)
					(number "E1"
						(effects
							(font
								(size 1.27 1.27)
							)
						)
					)
				)
				(pin passive line
					(at 0 -19.05 0)
					(length 5.08)
					(hide yes)
					(name "GND"
						(effects
							(font
								(size 1.27 1.27)
							)
						)
					)
					(number "E12"
						(effects
							(font
								(size 1.27 1.27)
							)
						)
					)
				)
				(pin passive line
					(at 0 -19.05 0)
					(length 5.08)
					(hide yes)
					(name "GND"
						(effects
							(font
								(size 1.27 1.27)
							)
						)
					)
					(number "E2"
						(effects
							(font
								(size 1.27 1.27)
							)
						)
					)
				)
				(pin passive line
					(at 0 -19.05 0)
					(length 5.08)
					(hide yes)
					(name "GND"
						(effects
							(font
								(size 1.27 1.27)
							)
						)
					)
					(number "E22"
						(effects
							(font
								(size 1.27 1.27)
							)
						)
					)
				)
				(pin passive line
					(at 0 -19.05 0)
					(length 5.08)
					(hide yes)
					(name "GND"
						(effects
							(font
								(size 1.27 1.27)
							)
						)
					)
					(number "E6"
						(effects
							(font
								(size 1.27 1.27)
							)
						)
					)
				)
				(pin passive line
					(at 0 -19.05 0)
					(length 5.08)
					(hide yes)
					(name "GND"
						(effects
							(font
								(size 1.27 1.27)
							)
						)
					)
					(number "E9"
						(effects
							(font
								(size 1.27 1.27)
							)
						)
					)
				)
				(pin passive line
					(at 0 -19.05 0)
					(length 5.08)
					(hide yes)
					(name "GND"
						(effects
							(font
								(size 1.27 1.27)
							)
						)
					)
					(number "F19"
						(effects
							(font
								(size 1.27 1.27)
							)
						)
					)
				)
				(pin passive line
					(at 0 -19.05 0)
					(length 5.08)
					(hide yes)
					(name "GND"
						(effects
							(font
								(size 1.27 1.27)
							)
						)
					)
					(number "F29"
						(effects
							(font
								(size 1.27 1.27)
							)
						)
					)
				)
				(pin passive line
					(at 0 -19.05 0)
					(length 5.08)
					(hide yes)
					(name "GND"
						(effects
							(font
								(size 1.27 1.27)
							)
						)
					)
					(number "F4"
						(effects
							(font
								(size 1.27 1.27)
							)
						)
					)
				)
				(pin passive line
					(at 0 -19.05 0)
					(length 5.08)
					(hide yes)
					(name "GND"
						(effects
							(font
								(size 1.27 1.27)
							)
						)
					)
					(number "F8"
						(effects
							(font
								(size 1.27 1.27)
							)
						)
					)
				)
				(pin passive line
					(at 0 -19.05 0)
					(length 5.08)
					(hide yes)
					(name "GND"
						(effects
							(font
								(size 1.27 1.27)
							)
						)
					)
					(number "F9"
						(effects
							(font
								(size 1.27 1.27)
							)
						)
					)
				)
				(pin passive line
					(at 0 -19.05 0)
					(length 5.08)
					(hide yes)
					(name "GND"
						(effects
							(font
								(size 1.27 1.27)
							)
						)
					)
					(number "G1"
						(effects
							(font
								(size 1.27 1.27)
							)
						)
					)
				)
				(pin passive line
					(at 0 -19.05 0)
					(length 5.08)
					(hide yes)
					(name "GND"
						(effects
							(font
								(size 1.27 1.27)
							)
						)
					)
					(number "G16"
						(effects
							(font
								(size 1.27 1.27)
							)
						)
					)
				)
				(pin passive line
					(at 0 -19.05 0)
					(length 5.08)
					(hide yes)
					(name "GND"
						(effects
							(font
								(size 1.27 1.27)
							)
						)
					)
					(number "G2"
						(effects
							(font
								(size 1.27 1.27)
							)
						)
					)
				)
				(pin passive line
					(at 0 -19.05 0)
					(length 5.08)
					(hide yes)
					(name "GND"
						(effects
							(font
								(size 1.27 1.27)
							)
						)
					)
					(number "G26"
						(effects
							(font
								(size 1.27 1.27)
							)
						)
					)
				)
				(pin passive line
					(at 0 -19.05 0)
					(length 5.08)
					(hide yes)
					(name "GND"
						(effects
							(font
								(size 1.27 1.27)
							)
						)
					)
					(number "G6"
						(effects
							(font
								(size 1.27 1.27)
							)
						)
					)
				)
				(pin passive line
					(at 0 -19.05 0)
					(length 5.08)
					(hide yes)
					(name "GND"
						(effects
							(font
								(size 1.27 1.27)
							)
						)
					)
					(number "G9"
						(effects
							(font
								(size 1.27 1.27)
							)
						)
					)
				)
				(pin passive line
					(at 0 -19.05 0)
					(length 5.08)
					(hide yes)
					(name "GND"
						(effects
							(font
								(size 1.27 1.27)
							)
						)
					)
					(number "H13"
						(effects
							(font
								(size 1.27 1.27)
							)
						)
					)
				)
				(pin passive line
					(at 0 -19.05 0)
					(length 5.08)
					(hide yes)
					(name "GND"
						(effects
							(font
								(size 1.27 1.27)
							)
						)
					)
					(number "H23"
						(effects
							(font
								(size 1.27 1.27)
							)
						)
					)
				)
				(pin passive line
					(at 0 -19.05 0)
					(length 5.08)
					(hide yes)
					(name "GND"
						(effects
							(font
								(size 1.27 1.27)
							)
						)
					)
					(number "H4"
						(effects
							(font
								(size 1.27 1.27)
							)
						)
					)
				)
				(pin passive line
					(at 0 -19.05 0)
					(length 5.08)
					(hide yes)
					(name "GND"
						(effects
							(font
								(size 1.27 1.27)
							)
						)
					)
					(number "H8"
						(effects
							(font
								(size 1.27 1.27)
							)
						)
					)
				)
				(pin passive line
					(at 0 -19.05 0)
					(length 5.08)
					(hide yes)
					(name "GND"
						(effects
							(font
								(size 1.27 1.27)
							)
						)
					)
					(number "H9"
						(effects
							(font
								(size 1.27 1.27)
							)
						)
					)
				)
				(pin passive line
					(at 0 -19.05 0)
					(length 5.08)
					(hide yes)
					(name "GND"
						(effects
							(font
								(size 1.27 1.27)
							)
						)
					)
					(number "J1"
						(effects
							(font
								(size 1.27 1.27)
							)
						)
					)
				)
				(pin passive line
					(at 0 -19.05 0)
					(length 5.08)
					(hide yes)
					(name "GND"
						(effects
							(font
								(size 1.27 1.27)
							)
						)
					)
					(number "J10"
						(effects
							(font
								(size 1.27 1.27)
							)
						)
					)
				)
				(pin passive line
					(at 0 -19.05 0)
					(length 5.08)
					(hide yes)
					(name "GND"
						(effects
							(font
								(size 1.27 1.27)
							)
						)
					)
					(number "J2"
						(effects
							(font
								(size 1.27 1.27)
							)
						)
					)
				)
				(pin passive line
					(at 0 -19.05 0)
					(length 5.08)
					(hide yes)
					(name "GND"
						(effects
							(font
								(size 1.27 1.27)
							)
						)
					)
					(number "J20"
						(effects
							(font
								(size 1.27 1.27)
							)
						)
					)
				)
				(pin passive line
					(at 0 -19.05 0)
					(length 5.08)
					(hide yes)
					(name "GND"
						(effects
							(font
								(size 1.27 1.27)
							)
						)
					)
					(number "J30"
						(effects
							(font
								(size 1.27 1.27)
							)
						)
					)
				)
				(pin passive line
					(at 0 -19.05 0)
					(length 5.08)
					(hide yes)
					(name "GND"
						(effects
							(font
								(size 1.27 1.27)
							)
						)
					)
					(number "J6"
						(effects
							(font
								(size 1.27 1.27)
							)
						)
					)
				)
				(pin passive line
					(at 0 -19.05 0)
					(length 5.08)
					(hide yes)
					(name "GND"
						(effects
							(font
								(size 1.27 1.27)
							)
						)
					)
					(number "J9"
						(effects
							(font
								(size 1.27 1.27)
							)
						)
					)
				)
				(pin passive line
					(at 0 -19.05 0)
					(length 5.08)
					(hide yes)
					(name "GND"
						(effects
							(font
								(size 1.27 1.27)
							)
						)
					)
					(number "K17"
						(effects
							(font
								(size 1.27 1.27)
							)
						)
					)
				)
				(pin passive line
					(at 0 -19.05 0)
					(length 5.08)
					(hide yes)
					(name "GND"
						(effects
							(font
								(size 1.27 1.27)
							)
						)
					)
					(number "K27"
						(effects
							(font
								(size 1.27 1.27)
							)
						)
					)
				)
				(pin passive line
					(at 0 -19.05 0)
					(length 5.08)
					(hide yes)
					(name "GND"
						(effects
							(font
								(size 1.27 1.27)
							)
						)
					)
					(number "K4"
						(effects
							(font
								(size 1.27 1.27)
							)
						)
					)
				)
				(pin passive line
					(at 0 -19.05 0)
					(length 5.08)
					(hide yes)
					(name "GND"
						(effects
							(font
								(size 1.27 1.27)
							)
						)
					)
					(number "K8"
						(effects
							(font
								(size 1.27 1.27)
							)
						)
					)
				)
				(pin passive line
					(at 0 -19.05 0)
					(length 5.08)
					(hide yes)
					(name "GND"
						(effects
							(font
								(size 1.27 1.27)
							)
						)
					)
					(number "K9"
						(effects
							(font
								(size 1.27 1.27)
							)
						)
					)
				)
				(pin passive line
					(at 0 -19.05 0)
					(length 5.08)
					(hide yes)
					(name "GND"
						(effects
							(font
								(size 1.27 1.27)
							)
						)
					)
					(number "L1"
						(effects
							(font
								(size 1.27 1.27)
							)
						)
					)
				)
				(pin passive line
					(at 0 -19.05 0)
					(length 5.08)
					(hide yes)
					(name "GND"
						(effects
							(font
								(size 1.27 1.27)
							)
						)
					)
					(number "L14"
						(effects
							(font
								(size 1.27 1.27)
							)
						)
					)
				)
				(pin passive line
					(at 0 -19.05 0)
					(length 5.08)
					(hide yes)
					(name "GND"
						(effects
							(font
								(size 1.27 1.27)
							)
						)
					)
					(number "L2"
						(effects
							(font
								(size 1.27 1.27)
							)
						)
					)
				)
				(pin passive line
					(at 0 -19.05 0)
					(length 5.08)
					(hide yes)
					(name "GND"
						(effects
							(font
								(size 1.27 1.27)
							)
						)
					)
					(number "L24"
						(effects
							(font
								(size 1.27 1.27)
							)
						)
					)
				)
				(pin passive line
					(at 0 -19.05 0)
					(length 5.08)
					(hide yes)
					(name "GND"
						(effects
							(font
								(size 1.27 1.27)
							)
						)
					)
					(number "L6"
						(effects
							(font
								(size 1.27 1.27)
							)
						)
					)
				)
				(pin passive line
					(at 0 -19.05 0)
					(length 5.08)
					(hide yes)
					(name "GND"
						(effects
							(font
								(size 1.27 1.27)
							)
						)
					)
					(number "L9"
						(effects
							(font
								(size 1.27 1.27)
							)
						)
					)
				)
				(pin passive line
					(at 0 -19.05 0)
					(length 5.08)
					(hide yes)
					(name "GND"
						(effects
							(font
								(size 1.27 1.27)
							)
						)
					)
					(number "M12"
						(effects
							(font
								(size 1.27 1.27)
							)
						)
					)
				)
				(pin passive line
					(at 0 -19.05 0)
					(length 5.08)
					(hide yes)
					(name "GND"
						(effects
							(font
								(size 1.27 1.27)
							)
						)
					)
					(number "M14"
						(effects
							(font
								(size 1.27 1.27)
							)
						)
					)
				)
				(pin passive line
					(at 0 -19.05 0)
					(length 5.08)
					(hide yes)
					(name "GND"
						(effects
							(font
								(size 1.27 1.27)
							)
						)
					)
					(number "M16"
						(effects
							(font
								(size 1.27 1.27)
							)
						)
					)
				)
				(pin passive line
					(at 0 -19.05 0)
					(length 5.08)
					(hide yes)
					(name "GND"
						(effects
							(font
								(size 1.27 1.27)
							)
						)
					)
					(number "M18"
						(effects
							(font
								(size 1.27 1.27)
							)
						)
					)
				)
				(pin passive line
					(at 0 -19.05 0)
					(length 5.08)
					(hide yes)
					(name "GND"
						(effects
							(font
								(size 1.27 1.27)
							)
						)
					)
					(number "M21"
						(effects
							(font
								(size 1.27 1.27)
							)
						)
					)
				)
				(pin passive line
					(at 0 -19.05 0)
					(length 5.08)
					(hide yes)
					(name "GND"
						(effects
							(font
								(size 1.27 1.27)
							)
						)
					)
					(number "M4"
						(effects
							(font
								(size 1.27 1.27)
							)
						)
					)
				)
				(pin passive line
					(at 0 -19.05 0)
					(length 5.08)
					(hide yes)
					(name "GND"
						(effects
							(font
								(size 1.27 1.27)
							)
						)
					)
					(number "M8"
						(effects
							(font
								(size 1.27 1.27)
							)
						)
					)
				)
				(pin passive line
					(at 0 -19.05 0)
					(length 5.08)
					(hide yes)
					(name "GND"
						(effects
							(font
								(size 1.27 1.27)
							)
						)
					)
					(number "M9"
						(effects
							(font
								(size 1.27 1.27)
							)
						)
					)
				)
				(pin passive line
					(at 0 -19.05 0)
					(length 5.08)
					(hide yes)
					(name "GND"
						(effects
							(font
								(size 1.27 1.27)
							)
						)
					)
					(number "N1"
						(effects
							(font
								(size 1.27 1.27)
							)
						)
					)
				)
				(pin passive line
					(at 0 -19.05 0)
					(length 5.08)
					(hide yes)
					(name "GND"
						(effects
							(font
								(size 1.27 1.27)
							)
						)
					)
					(number "N11"
						(effects
							(font
								(size 1.27 1.27)
							)
						)
					)
				)
				(pin passive line
					(at 0 -19.05 0)
					(length 5.08)
					(hide yes)
					(name "GND"
						(effects
							(font
								(size 1.27 1.27)
							)
						)
					)
					(number "N13"
						(effects
							(font
								(size 1.27 1.27)
							)
						)
					)
				)
				(pin passive line
					(at 0 -19.05 0)
					(length 5.08)
					(hide yes)
					(name "GND"
						(effects
							(font
								(size 1.27 1.27)
							)
						)
					)
					(number "N15"
						(effects
							(font
								(size 1.27 1.27)
							)
						)
					)
				)
				(pin passive line
					(at 0 -19.05 0)
					(length 5.08)
					(hide yes)
					(name "GND"
						(effects
							(font
								(size 1.27 1.27)
							)
						)
					)
					(number "N17"
						(effects
							(font
								(size 1.27 1.27)
							)
						)
					)
				)
				(pin passive line
					(at 0 -19.05 0)
					(length 5.08)
					(hide yes)
					(name "GND"
						(effects
							(font
								(size 1.27 1.27)
							)
						)
					)
					(number "N2"
						(effects
							(font
								(size 1.27 1.27)
							)
						)
					)
				)
				(pin passive line
					(at 0 -19.05 0)
					(length 5.08)
					(hide yes)
					(name "GND"
						(effects
							(font
								(size 1.27 1.27)
							)
						)
					)
					(number "N28"
						(effects
							(font
								(size 1.27 1.27)
							)
						)
					)
				)
				(pin passive line
					(at 0 -19.05 0)
					(length 5.08)
					(hide yes)
					(name "GND"
						(effects
							(font
								(size 1.27 1.27)
							)
						)
					)
					(number "N6"
						(effects
							(font
								(size 1.27 1.27)
							)
						)
					)
				)
				(pin passive line
					(at 0 -19.05 0)
					(length 5.08)
					(hide yes)
					(name "GND"
						(effects
							(font
								(size 1.27 1.27)
							)
						)
					)
					(number "N9"
						(effects
							(font
								(size 1.27 1.27)
							)
						)
					)
				)
				(pin passive line
					(at 0 -19.05 0)
					(length 5.08)
					(hide yes)
					(name "GND"
						(effects
							(font
								(size 1.27 1.27)
							)
						)
					)
					(number "P10"
						(effects
							(font
								(size 1.27 1.27)
							)
						)
					)
				)
				(pin passive line
					(at 0 -19.05 0)
					(length 5.08)
					(hide yes)
					(name "GND"
						(effects
							(font
								(size 1.27 1.27)
							)
						)
					)
					(number "P12"
						(effects
							(font
								(size 1.27 1.27)
							)
						)
					)
				)
				(pin passive line
					(at 0 -19.05 0)
					(length 5.08)
					(hide yes)
					(name "GND"
						(effects
							(font
								(size 1.27 1.27)
							)
						)
					)
					(number "P16"
						(effects
							(font
								(size 1.27 1.27)
							)
						)
					)
				)
				(pin passive line
					(at 0 -19.05 0)
					(length 5.08)
					(hide yes)
					(name "GND"
						(effects
							(font
								(size 1.27 1.27)
							)
						)
					)
					(number "P18"
						(effects
							(font
								(size 1.27 1.27)
							)
						)
					)
				)
				(pin passive line
					(at 0 -19.05 0)
					(length 5.08)
					(hide yes)
					(name "GND"
						(effects
							(font
								(size 1.27 1.27)
							)
						)
					)
					(number "P25"
						(effects
							(font
								(size 1.27 1.27)
							)
						)
					)
				)
				(pin passive line
					(at 0 -19.05 0)
					(length 5.08)
					(hide yes)
					(name "GND"
						(effects
							(font
								(size 1.27 1.27)
							)
						)
					)
					(number "P4"
						(effects
							(font
								(size 1.27 1.27)
							)
						)
					)
				)
				(pin passive line
					(at 0 -19.05 0)
					(length 5.08)
					(hide yes)
					(name "GND"
						(effects
							(font
								(size 1.27 1.27)
							)
						)
					)
					(number "P8"
						(effects
							(font
								(size 1.27 1.27)
							)
						)
					)
				)
				(pin passive line
					(at 0 -19.05 0)
					(length 5.08)
					(hide yes)
					(name "GND"
						(effects
							(font
								(size 1.27 1.27)
							)
						)
					)
					(number "P9"
						(effects
							(font
								(size 1.27 1.27)
							)
						)
					)
				)
				(pin passive line
					(at 0 -19.05 0)
					(length 5.08)
					(hide yes)
					(name "GND"
						(effects
							(font
								(size 1.27 1.27)
							)
						)
					)
					(number "R1"
						(effects
							(font
								(size 1.27 1.27)
							)
						)
					)
				)
				(pin passive line
					(at 0 -19.05 0)
					(length 5.08)
					(hide yes)
					(name "GND"
						(effects
							(font
								(size 1.27 1.27)
							)
						)
					)
					(number "R11"
						(effects
							(font
								(size 1.27 1.27)
							)
						)
					)
				)
				(pin passive line
					(at 0 -19.05 0)
					(length 5.08)
					(hide yes)
					(name "GND"
						(effects
							(font
								(size 1.27 1.27)
							)
						)
					)
					(number "R13"
						(effects
							(font
								(size 1.27 1.27)
							)
						)
					)
				)
				(pin passive line
					(at 0 -19.05 0)
					(length 5.08)
					(hide yes)
					(name "GND"
						(effects
							(font
								(size 1.27 1.27)
							)
						)
					)
					(number "R17"
						(effects
							(font
								(size 1.27 1.27)
							)
						)
					)
				)
				(pin passive line
					(at 0 -19.05 0)
					(length 5.08)
					(hide yes)
					(name "GND"
						(effects
							(font
								(size 1.27 1.27)
							)
						)
					)
					(number "R2"
						(effects
							(font
								(size 1.27 1.27)
							)
						)
					)
				)
				(pin passive line
					(at 0 -19.05 0)
					(length 5.08)
					(hide yes)
					(name "GND"
						(effects
							(font
								(size 1.27 1.27)
							)
						)
					)
					(number "R22"
						(effects
							(font
								(size 1.27 1.27)
							)
						)
					)
				)
				(pin passive line
					(at 0 -19.05 0)
					(length 5.08)
					(hide yes)
					(name "GND"
						(effects
							(font
								(size 1.27 1.27)
							)
						)
					)
					(number "R6"
						(effects
							(font
								(size 1.27 1.27)
							)
						)
					)
				)
				(pin passive line
					(at 0 -19.05 0)
					(length 5.08)
					(hide yes)
					(name "GND"
						(effects
							(font
								(size 1.27 1.27)
							)
						)
					)
					(number "R9"
						(effects
							(font
								(size 1.27 1.27)
							)
						)
					)
				)
				(pin passive line
					(at 0 -19.05 0)
					(length 5.08)
					(hide yes)
					(name "GND"
						(effects
							(font
								(size 1.27 1.27)
							)
						)
					)
					(number "T10"
						(effects
							(font
								(size 1.27 1.27)
							)
						)
					)
				)
				(pin passive line
					(at 0 -19.05 0)
					(length 5.08)
					(hide yes)
					(name "GND"
						(effects
							(font
								(size 1.27 1.27)
							)
						)
					)
					(number "T12"
						(effects
							(font
								(size 1.27 1.27)
							)
						)
					)
				)
				(pin passive line
					(at 0 -19.05 0)
					(length 5.08)
					(hide yes)
					(name "GND"
						(effects
							(font
								(size 1.27 1.27)
							)
						)
					)
					(number "T16"
						(effects
							(font
								(size 1.27 1.27)
							)
						)
					)
				)
				(pin passive line
					(at 0 -19.05 0)
					(length 5.08)
					(hide yes)
					(name "GND"
						(effects
							(font
								(size 1.27 1.27)
							)
						)
					)
					(number "T18"
						(effects
							(font
								(size 1.27 1.27)
							)
						)
					)
				)
				(pin passive line
					(at 0 -19.05 0)
					(length 5.08)
					(hide yes)
					(name "GND"
						(effects
							(font
								(size 1.27 1.27)
							)
						)
					)
					(number "T19"
						(effects
							(font
								(size 1.27 1.27)
							)
						)
					)
				)
				(pin passive line
					(at 0 -19.05 0)
					(length 5.08)
					(hide yes)
					(name "GND"
						(effects
							(font
								(size 1.27 1.27)
							)
						)
					)
					(number "T29"
						(effects
							(font
								(size 1.27 1.27)
							)
						)
					)
				)
				(pin passive line
					(at 0 -19.05 0)
					(length 5.08)
					(hide yes)
					(name "GND"
						(effects
							(font
								(size 1.27 1.27)
							)
						)
					)
					(number "T4"
						(effects
							(font
								(size 1.27 1.27)
							)
						)
					)
				)
				(pin passive line
					(at 0 -19.05 0)
					(length 5.08)
					(hide yes)
					(name "GND"
						(effects
							(font
								(size 1.27 1.27)
							)
						)
					)
					(number "T8"
						(effects
							(font
								(size 1.27 1.27)
							)
						)
					)
				)
				(pin passive line
					(at 0 -19.05 0)
					(length 5.08)
					(hide yes)
					(name "GND"
						(effects
							(font
								(size 1.27 1.27)
							)
						)
					)
					(number "U1"
						(effects
							(font
								(size 1.27 1.27)
							)
						)
					)
				)
				(pin passive line
					(at 0 -19.05 0)
					(length 5.08)
					(hide yes)
					(name "GND"
						(effects
							(font
								(size 1.27 1.27)
							)
						)
					)
					(number "U11"
						(effects
							(font
								(size 1.27 1.27)
							)
						)
					)
				)
				(pin passive line
					(at 0 -19.05 0)
					(length 5.08)
					(hide yes)
					(name "GND"
						(effects
							(font
								(size 1.27 1.27)
							)
						)
					)
					(number "U13"
						(effects
							(font
								(size 1.27 1.27)
							)
						)
					)
				)
				(pin passive line
					(at 0 -19.05 0)
					(length 5.08)
					(hide yes)
					(name "GND"
						(effects
							(font
								(size 1.27 1.27)
							)
						)
					)
					(number "U17"
						(effects
							(font
								(size 1.27 1.27)
							)
						)
					)
				)
				(pin passive line
					(at 0 -19.05 0)
					(length 5.08)
					(hide yes)
					(name "GND"
						(effects
							(font
								(size 1.27 1.27)
							)
						)
					)
					(number "U2"
						(effects
							(font
								(size 1.27 1.27)
							)
						)
					)
				)
				(pin passive line
					(at 0 -19.05 0)
					(length 5.08)
					(hide yes)
					(name "GND"
						(effects
							(font
								(size 1.27 1.27)
							)
						)
					)
					(number "U26"
						(effects
							(font
								(size 1.27 1.27)
							)
						)
					)
				)
				(pin passive line
					(at 0 -19.05 0)
					(length 5.08)
					(hide yes)
					(name "GND"
						(effects
							(font
								(size 1.27 1.27)
							)
						)
					)
					(number "U6"
						(effects
							(font
								(size 1.27 1.27)
							)
						)
					)
				)
				(pin passive line
					(at 0 -19.05 0)
					(length 5.08)
					(hide yes)
					(name "GND"
						(effects
							(font
								(size 1.27 1.27)
							)
						)
					)
					(number "U9"
						(effects
							(font
								(size 1.27 1.27)
							)
						)
					)
				)
				(pin passive line
					(at 0 -19.05 0)
					(length 5.08)
					(hide yes)
					(name "GND"
						(effects
							(font
								(size 1.27 1.27)
							)
						)
					)
					(number "V10"
						(effects
							(font
								(size 1.27 1.27)
							)
						)
					)
				)
				(pin passive line
					(at 0 -19.05 0)
					(length 5.08)
					(hide yes)
					(name "GND"
						(effects
							(font
								(size 1.27 1.27)
							)
						)
					)
					(number "V12"
						(effects
							(font
								(size 1.27 1.27)
							)
						)
					)
				)
				(pin passive line
					(at 0 -19.05 0)
					(length 5.08)
					(hide yes)
					(name "GND"
						(effects
							(font
								(size 1.27 1.27)
							)
						)
					)
					(number "V14"
						(effects
							(font
								(size 1.27 1.27)
							)
						)
					)
				)
				(pin passive line
					(at 0 -19.05 0)
					(length 5.08)
					(hide yes)
					(name "GND"
						(effects
							(font
								(size 1.27 1.27)
							)
						)
					)
					(number "V16"
						(effects
							(font
								(size 1.27 1.27)
							)
						)
					)
				)
				(pin passive line
					(at 0 -19.05 0)
					(length 5.08)
					(hide yes)
					(name "GND"
						(effects
							(font
								(size 1.27 1.27)
							)
						)
					)
					(number "V18"
						(effects
							(font
								(size 1.27 1.27)
							)
						)
					)
				)
				(pin passive line
					(at 0 -19.05 0)
					(length 5.08)
					(hide yes)
					(name "GND"
						(effects
							(font
								(size 1.27 1.27)
							)
						)
					)
					(number "V23"
						(effects
							(font
								(size 1.27 1.27)
							)
						)
					)
				)
				(pin passive line
					(at 0 -19.05 0)
					(length 5.08)
					(hide yes)
					(name "GND"
						(effects
							(font
								(size 1.27 1.27)
							)
						)
					)
					(number "V4"
						(effects
							(font
								(size 1.27 1.27)
							)
						)
					)
				)
				(pin passive line
					(at 0 -19.05 0)
					(length 5.08)
					(hide yes)
					(name "GND"
						(effects
							(font
								(size 1.27 1.27)
							)
						)
					)
					(number "V8"
						(effects
							(font
								(size 1.27 1.27)
							)
						)
					)
				)
				(pin passive line
					(at 0 -19.05 0)
					(length 5.08)
					(hide yes)
					(name "GND"
						(effects
							(font
								(size 1.27 1.27)
							)
						)
					)
					(number "V9"
						(effects
							(font
								(size 1.27 1.27)
							)
						)
					)
				)
				(pin passive line
					(at 0 -19.05 0)
					(length 5.08)
					(hide yes)
					(name "GND"
						(effects
							(font
								(size 1.27 1.27)
							)
						)
					)
					(number "W1"
						(effects
							(font
								(size 1.27 1.27)
							)
						)
					)
				)
				(pin passive line
					(at 0 -19.05 0)
					(length 5.08)
					(hide yes)
					(name "GND"
						(effects
							(font
								(size 1.27 1.27)
							)
						)
					)
					(number "W11"
						(effects
							(font
								(size 1.27 1.27)
							)
						)
					)
				)
				(pin passive line
					(at 0 -19.05 0)
					(length 5.08)
					(hide yes)
					(name "GND"
						(effects
							(font
								(size 1.27 1.27)
							)
						)
					)
					(number "W13"
						(effects
							(font
								(size 1.27 1.27)
							)
						)
					)
				)
				(pin passive line
					(at 0 -19.05 0)
					(length 5.08)
					(hide yes)
					(name "GND"
						(effects
							(font
								(size 1.27 1.27)
							)
						)
					)
					(number "W15"
						(effects
							(font
								(size 1.27 1.27)
							)
						)
					)
				)
				(pin passive line
					(at 0 -19.05 0)
					(length 5.08)
					(hide yes)
					(name "GND"
						(effects
							(font
								(size 1.27 1.27)
							)
						)
					)
					(number "W17"
						(effects
							(font
								(size 1.27 1.27)
							)
						)
					)
				)
				(pin passive line
					(at 0 -19.05 0)
					(length 5.08)
					(hide yes)
					(name "GND"
						(effects
							(font
								(size 1.27 1.27)
							)
						)
					)
					(number "W2"
						(effects
							(font
								(size 1.27 1.27)
							)
						)
					)
				)
				(pin passive line
					(at 0 -19.05 0)
					(length 5.08)
					(hide yes)
					(name "GND"
						(effects
							(font
								(size 1.27 1.27)
							)
						)
					)
					(number "W20"
						(effects
							(font
								(size 1.27 1.27)
							)
						)
					)
				)
				(pin passive line
					(at 0 -19.05 0)
					(length 5.08)
					(hide yes)
					(name "GND"
						(effects
							(font
								(size 1.27 1.27)
							)
						)
					)
					(number "W30"
						(effects
							(font
								(size 1.27 1.27)
							)
						)
					)
				)
				(pin passive line
					(at 0 -19.05 0)
					(length 5.08)
					(hide yes)
					(name "GND"
						(effects
							(font
								(size 1.27 1.27)
							)
						)
					)
					(number "W6"
						(effects
							(font
								(size 1.27 1.27)
							)
						)
					)
				)
				(pin passive line
					(at 0 -19.05 0)
					(length 5.08)
					(hide yes)
					(name "GND"
						(effects
							(font
								(size 1.27 1.27)
							)
						)
					)
					(number "W9"
						(effects
							(font
								(size 1.27 1.27)
							)
						)
					)
				)
				(pin passive line
					(at 0 -19.05 0)
					(length 5.08)
					(hide yes)
					(name "GND"
						(effects
							(font
								(size 1.27 1.27)
							)
						)
					)
					(number "Y17"
						(effects
							(font
								(size 1.27 1.27)
							)
						)
					)
				)
				(pin passive line
					(at 0 -19.05 0)
					(length 5.08)
					(hide yes)
					(name "GND"
						(effects
							(font
								(size 1.27 1.27)
							)
						)
					)
					(number "Y27"
						(effects
							(font
								(size 1.27 1.27)
							)
						)
					)
				)
				(pin passive line
					(at 0 -19.05 0)
					(length 5.08)
					(hide yes)
					(name "GND"
						(effects
							(font
								(size 1.27 1.27)
							)
						)
					)
					(number "Y3"
						(effects
							(font
								(size 1.27 1.27)
							)
						)
					)
				)
				(pin passive line
					(at 0 -19.05 0)
					(length 5.08)
					(hide yes)
					(name "GND"
						(effects
							(font
								(size 1.27 1.27)
							)
						)
					)
					(number "Y4"
						(effects
							(font
								(size 1.27 1.27)
							)
						)
					)
				)
				(pin passive line
					(at 0 -19.05 0)
					(length 5.08)
					(hide yes)
					(name "GND"
						(effects
							(font
								(size 1.27 1.27)
							)
						)
					)
					(number "Y7"
						(effects
							(font
								(size 1.27 1.27)
							)
						)
					)
				)
				(pin passive line
					(at 0 -19.05 0)
					(length 5.08)
					(hide yes)
					(name "GND"
						(effects
							(font
								(size 1.27 1.27)
							)
						)
					)
					(number "Y8"
						(effects
							(font
								(size 1.27 1.27)
							)
						)
					)
				)
				(pin passive line
					(at 0 -19.05 0)
					(length 5.08)
					(hide yes)
					(name "GND"
						(effects
							(font
								(size 1.27 1.27)
							)
						)
					)
					(number "Y9"
						(effects
							(font
								(size 1.27 1.27)
							)
						)
					)
				)
			)
		)
	(symbol "XC7K410T-2FFG900I_2"
			(exclude_from_sim no)
			(in_bom yes)
			(on_board yes)
			(property "Reference" "U1"
				(at 17.145 6.985 0)
				(effects
					(font
						(size 1.27 1.27)
						(thickness 0.15)
					)
				)
			)
			(property "Value" "XC7K410T-2FFG900I"
				(at 17.145 4.445 0)
				(effects
					(font
						(size 1.27 1.27)
						(thickness 0.15)
					)
				)
			)
			(property "Footprint" "k410t-devboard-footprints:xc7k410t-2ffg900I"
				(at 0 26.67 0)
				(effects
					(font
						(size 1.27 1.27)
						(thickness 0.15)
					)
					(justify left bottom)
					(hide yes)
				)
			)
			(property "Datasheet" "https://eu.mouser.com/datasheet/2/903/ds180_7Series_Overview-1591537.pdf"
				(at 0 24.13 0)
				(effects
					(font
						(size 1.27 1.27)
						(thickness 0.15)
					)
					(justify left bottom)
					(hide yes)
				)
			)
			(property "Description" "Kintex 7 XC7K410T-2FFG900I"
				(at 0 0 0)
				(effects
					(font
						(size 1.27 1.27)
					)
					(hide yes)
				)
			)
			(property "Manufacturer" "AMD-Xilinx"
				(at 0 21.59 0)
				(effects
					(font
						(size 1.27 1.27)
						(thickness 0.15)
					)
					(justify left bottom)
					(hide yes)
				)
			)
			(property "MPN" "XC7K410T-2FFG900I"
				(at 0 19.05 0)
				(effects
					(font
						(size 1.27 1.27)
						(thickness 0.15)
					)
					(justify left bottom)
					(hide yes)
				)
			)
			(property "Author" "Antmicro"
				(at 0 16.51 0)
				(effects
					(font
						(size 1.27 1.27)
						(thickness 0.15)
					)
					(justify left bottom)
					(hide yes)
				)
			)
			(property "License" "Apache-2.0"
				(at 0 13.97 0)
				(effects
					(font
						(size 1.27 1.27)
						(thickness 0.15)
					)
					(justify left bottom)
					(hide yes)
				)
			)
			(property "ki_locked" ""
				(at 0 0 0)
				(effects
					(font
						(size 1.27 1.27)
					)
				)
			)
			(symbol "XC7K410T-2FFG900I_2_1_1"
				(rectangle
					(start -40.64 -129.54)
					(end -5.08 7.62)
					(stroke
						(width 0.254)
						(type default)
					)
					(fill
						(type background)
					)
				)
				(polyline
					(pts
						(xy -30.48 1.27) (xy -38.1 1.27) (xy -38.1 -125.73) (xy -30.48 -125.73)
					)
					(stroke
						(width 0.254)
						(type default)
					)
					(fill
						(type background)
					)
				)
				(text "BANK 12"
					(at -24.13 3.81 0)
					(effects
						(font
							(size 1.27 1.27)
							(thickness 0.15)
						)
						(justify left bottom)
					)
				)
				(pin bidirectional line
					(at 0 0 180)
					(length 5.08)
					(name "IO_0_12"
						(effects
							(font
								(size 1.27 1.27)
							)
						)
					)
					(number "Y20"
						(effects
							(font
								(size 1.27 1.27)
							)
						)
					)
				)
				(pin bidirectional line
					(at 0 -2.54 180)
					(length 5.08)
					(name "IO_L1P_T0_12"
						(effects
							(font
								(size 1.27 1.27)
							)
						)
					)
					(number "Y23"
						(effects
							(font
								(size 1.27 1.27)
							)
						)
					)
				)
				(pin bidirectional line
					(at 0 -5.08 180)
					(length 5.08)
					(name "IO_L1N_T0_12"
						(effects
							(font
								(size 1.27 1.27)
							)
						)
					)
					(number "Y24"
						(effects
							(font
								(size 1.27 1.27)
							)
						)
					)
				)
				(pin bidirectional line
					(at 0 -7.62 180)
					(length 5.08)
					(name "IO_L2P_T0_12"
						(effects
							(font
								(size 1.27 1.27)
							)
						)
					)
					(number "Y21"
						(effects
							(font
								(size 1.27 1.27)
							)
						)
					)
				)
				(pin bidirectional line
					(at 0 -10.16 180)
					(length 5.08)
					(name "IO_L2N_T0_12"
						(effects
							(font
								(size 1.27 1.27)
							)
						)
					)
					(number "AA21"
						(effects
							(font
								(size 1.27 1.27)
							)
						)
					)
				)
				(pin bidirectional line
					(at 0 -12.7 180)
					(length 5.08)
					(name "IO_L3P_T0_DQS_12"
						(effects
							(font
								(size 1.27 1.27)
							)
						)
					)
					(number "AB22"
						(effects
							(font
								(size 1.27 1.27)
							)
						)
					)
				)
				(pin bidirectional line
					(at 0 -15.24 180)
					(length 5.08)
					(name "IO_L3N_T0_DQS_12"
						(effects
							(font
								(size 1.27 1.27)
							)
						)
					)
					(number "AB23"
						(effects
							(font
								(size 1.27 1.27)
							)
						)
					)
				)
				(pin bidirectional line
					(at 0 -17.78 180)
					(length 5.08)
					(name "IO_L4P_T0_12"
						(effects
							(font
								(size 1.27 1.27)
							)
						)
					)
					(number "AA22"
						(effects
							(font
								(size 1.27 1.27)
							)
						)
					)
				)
				(pin bidirectional line
					(at 0 -20.32 180)
					(length 5.08)
					(name "IO_L4N_T0_12"
						(effects
							(font
								(size 1.27 1.27)
							)
						)
					)
					(number "AA23"
						(effects
							(font
								(size 1.27 1.27)
							)
						)
					)
				)
				(pin bidirectional line
					(at 0 -22.86 180)
					(length 5.08)
					(name "IO_L5P_T0_12"
						(effects
							(font
								(size 1.27 1.27)
							)
						)
					)
					(number "AC20"
						(effects
							(font
								(size 1.27 1.27)
							)
						)
					)
				)
				(pin bidirectional line
					(at 0 -25.4 180)
					(length 5.08)
					(name "IO_L5N_T0_12"
						(effects
							(font
								(size 1.27 1.27)
							)
						)
					)
					(number "AC21"
						(effects
							(font
								(size 1.27 1.27)
							)
						)
					)
				)
				(pin bidirectional line
					(at 0 -27.94 180)
					(length 5.08)
					(name "IO_L6P_T0_12"
						(effects
							(font
								(size 1.27 1.27)
							)
						)
					)
					(number "AA20"
						(effects
							(font
								(size 1.27 1.27)
							)
						)
					)
				)
				(pin bidirectional line
					(at 0 -30.48 180)
					(length 5.08)
					(name "IO_L6N_T0_VREF_12"
						(effects
							(font
								(size 1.27 1.27)
							)
						)
					)
					(number "AB20"
						(effects
							(font
								(size 1.27 1.27)
							)
						)
					)
				)
				(pin bidirectional line
					(at 0 -33.02 180)
					(length 5.08)
					(name "IO_L7P_T1_12"
						(effects
							(font
								(size 1.27 1.27)
							)
						)
					)
					(number "AB24"
						(effects
							(font
								(size 1.27 1.27)
							)
						)
					)
				)
				(pin bidirectional line
					(at 0 -35.56 180)
					(length 5.08)
					(name "IO_L7N_T1_12"
						(effects
							(font
								(size 1.27 1.27)
							)
						)
					)
					(number "AC25"
						(effects
							(font
								(size 1.27 1.27)
							)
						)
					)
				)
				(pin bidirectional line
					(at 0 -38.1 180)
					(length 5.08)
					(name "IO_L8P_T1_12"
						(effects
							(font
								(size 1.27 1.27)
							)
						)
					)
					(number "AC22"
						(effects
							(font
								(size 1.27 1.27)
							)
						)
					)
				)
				(pin bidirectional line
					(at 0 -40.64 180)
					(length 5.08)
					(name "IO_L8N_T1_12"
						(effects
							(font
								(size 1.27 1.27)
							)
						)
					)
					(number "AD22"
						(effects
							(font
								(size 1.27 1.27)
							)
						)
					)
				)
				(pin bidirectional line
					(at 0 -43.18 180)
					(length 5.08)
					(name "IO_L9P_T1_DQS_12"
						(effects
							(font
								(size 1.27 1.27)
							)
						)
					)
					(number "AC24"
						(effects
							(font
								(size 1.27 1.27)
							)
						)
					)
				)
				(pin bidirectional line
					(at 0 -45.72 180)
					(length 5.08)
					(name "IO_L9N_T1_DQS_12"
						(effects
							(font
								(size 1.27 1.27)
							)
						)
					)
					(number "AD24"
						(effects
							(font
								(size 1.27 1.27)
							)
						)
					)
				)
				(pin bidirectional line
					(at 0 -48.26 180)
					(length 5.08)
					(name "IO_L10P_T1_12"
						(effects
							(font
								(size 1.27 1.27)
							)
						)
					)
					(number "AD21"
						(effects
							(font
								(size 1.27 1.27)
							)
						)
					)
				)
				(pin bidirectional line
					(at 0 -50.8 180)
					(length 5.08)
					(name "IO_L10N_T1_12"
						(effects
							(font
								(size 1.27 1.27)
							)
						)
					)
					(number "AE21"
						(effects
							(font
								(size 1.27 1.27)
							)
						)
					)
				)
				(pin bidirectional line
					(at 0 -53.34 180)
					(length 5.08)
					(name "IO_L11P_T1_SRCC_12"
						(effects
							(font
								(size 1.27 1.27)
							)
						)
					)
					(number "AE23"
						(effects
							(font
								(size 1.27 1.27)
							)
						)
					)
				)
				(pin bidirectional line
					(at 0 -55.88 180)
					(length 5.08)
					(name "IO_L11N_T1_SRCC_12"
						(effects
							(font
								(size 1.27 1.27)
							)
						)
					)
					(number "AF23"
						(effects
							(font
								(size 1.27 1.27)
							)
						)
					)
				)
				(pin bidirectional line
					(at 0 -58.42 180)
					(length 5.08)
					(name "IO_L12P_T1_MRCC_12"
						(effects
							(font
								(size 1.27 1.27)
							)
						)
					)
					(number "AD23"
						(effects
							(font
								(size 1.27 1.27)
							)
						)
					)
				)
				(pin bidirectional line
					(at 0 -60.96 180)
					(length 5.08)
					(name "IO_L12N_T1_MRCC_12"
						(effects
							(font
								(size 1.27 1.27)
							)
						)
					)
					(number "AE24"
						(effects
							(font
								(size 1.27 1.27)
							)
						)
					)
				)
				(pin bidirectional line
					(at 0 -63.5 180)
					(length 5.08)
					(name "IO_L13P_T2_MRCC_12"
						(effects
							(font
								(size 1.27 1.27)
							)
						)
					)
					(number "AF22"
						(effects
							(font
								(size 1.27 1.27)
							)
						)
					)
				)
				(pin bidirectional line
					(at 0 -66.04 180)
					(length 5.08)
					(name "IO_L13N_T2_MRCC_12"
						(effects
							(font
								(size 1.27 1.27)
							)
						)
					)
					(number "AG23"
						(effects
							(font
								(size 1.27 1.27)
							)
						)
					)
				)
				(pin bidirectional line
					(at 0 -68.58 180)
					(length 5.08)
					(name "IO_L14P_T2_SRCC_12"
						(effects
							(font
								(size 1.27 1.27)
							)
						)
					)
					(number "AG24"
						(effects
							(font
								(size 1.27 1.27)
							)
						)
					)
				)
				(pin bidirectional line
					(at 0 -71.12 180)
					(length 5.08)
					(name "IO_L14N_T2_SRCC_12"
						(effects
							(font
								(size 1.27 1.27)
							)
						)
					)
					(number "AH24"
						(effects
							(font
								(size 1.27 1.27)
							)
						)
					)
				)
				(pin bidirectional line
					(at 0 -73.66 180)
					(length 5.08)
					(name "IO_L15P_T2_DQS_12"
						(effects
							(font
								(size 1.27 1.27)
							)
						)
					)
					(number "AJ24"
						(effects
							(font
								(size 1.27 1.27)
							)
						)
					)
				)
				(pin bidirectional line
					(at 0 -76.2 180)
					(length 5.08)
					(name "IO_L15N_T2_DQS_12"
						(effects
							(font
								(size 1.27 1.27)
							)
						)
					)
					(number "AK25"
						(effects
							(font
								(size 1.27 1.27)
							)
						)
					)
				)
				(pin bidirectional line
					(at 0 -78.74 180)
					(length 5.08)
					(name "IO_L16P_T2_12"
						(effects
							(font
								(size 1.27 1.27)
							)
						)
					)
					(number "AE25"
						(effects
							(font
								(size 1.27 1.27)
							)
						)
					)
				)
				(pin bidirectional line
					(at 0 -81.28 180)
					(length 5.08)
					(name "IO_L16N_T2_12"
						(effects
							(font
								(size 1.27 1.27)
							)
						)
					)
					(number "AF25"
						(effects
							(font
								(size 1.27 1.27)
							)
						)
					)
				)
				(pin bidirectional line
					(at 0 -83.82 180)
					(length 5.08)
					(name "IO_L17P_T2_12"
						(effects
							(font
								(size 1.27 1.27)
							)
						)
					)
					(number "AK23"
						(effects
							(font
								(size 1.27 1.27)
							)
						)
					)
				)
				(pin bidirectional line
					(at 0 -86.36 180)
					(length 5.08)
					(name "IO_L17N_T2_12"
						(effects
							(font
								(size 1.27 1.27)
							)
						)
					)
					(number "AK24"
						(effects
							(font
								(size 1.27 1.27)
							)
						)
					)
				)
				(pin bidirectional line
					(at 0 -88.9 180)
					(length 5.08)
					(name "IO_L18P_T2_12"
						(effects
							(font
								(size 1.27 1.27)
							)
						)
					)
					(number "AG25"
						(effects
							(font
								(size 1.27 1.27)
							)
						)
					)
				)
				(pin bidirectional line
					(at 0 -91.44 180)
					(length 5.08)
					(name "IO_L18N_T2_12"
						(effects
							(font
								(size 1.27 1.27)
							)
						)
					)
					(number "AH25"
						(effects
							(font
								(size 1.27 1.27)
							)
						)
					)
				)
				(pin bidirectional line
					(at 0 -93.98 180)
					(length 5.08)
					(name "IO_L19P_T3_12"
						(effects
							(font
								(size 1.27 1.27)
							)
						)
					)
					(number "AF20"
						(effects
							(font
								(size 1.27 1.27)
							)
						)
					)
				)
				(pin bidirectional line
					(at 0 -96.52 180)
					(length 5.08)
					(name "IO_L19N_T3_VREF_12"
						(effects
							(font
								(size 1.27 1.27)
							)
						)
					)
					(number "AF21"
						(effects
							(font
								(size 1.27 1.27)
							)
						)
					)
				)
				(pin bidirectional line
					(at 0 -99.06 180)
					(length 5.08)
					(name "IO_L20P_T3_12"
						(effects
							(font
								(size 1.27 1.27)
							)
						)
					)
					(number "AG22"
						(effects
							(font
								(size 1.27 1.27)
							)
						)
					)
				)
				(pin bidirectional line
					(at 0 -101.6 180)
					(length 5.08)
					(name "IO_L20N_T3_12"
						(effects
							(font
								(size 1.27 1.27)
							)
						)
					)
					(number "AH22"
						(effects
							(font
								(size 1.27 1.27)
							)
						)
					)
				)
				(pin bidirectional line
					(at 0 -104.14 180)
					(length 5.08)
					(name "IO_L21P_T3_DQS_12"
						(effects
							(font
								(size 1.27 1.27)
							)
						)
					)
					(number "AJ22"
						(effects
							(font
								(size 1.27 1.27)
							)
						)
					)
				)
				(pin bidirectional line
					(at 0 -106.68 180)
					(length 5.08)
					(name "IO_L21N_T3_DQS_12"
						(effects
							(font
								(size 1.27 1.27)
							)
						)
					)
					(number "AJ23"
						(effects
							(font
								(size 1.27 1.27)
							)
						)
					)
				)
				(pin bidirectional line
					(at 0 -109.22 180)
					(length 5.08)
					(name "IO_L22P_T3_12"
						(effects
							(font
								(size 1.27 1.27)
							)
						)
					)
					(number "AG20"
						(effects
							(font
								(size 1.27 1.27)
							)
						)
					)
				)
				(pin bidirectional line
					(at 0 -111.76 180)
					(length 5.08)
					(name "IO_L22N_T3_12"
						(effects
							(font
								(size 1.27 1.27)
							)
						)
					)
					(number "AH20"
						(effects
							(font
								(size 1.27 1.27)
							)
						)
					)
				)
				(pin bidirectional line
					(at 0 -114.3 180)
					(length 5.08)
					(name "IO_L23P_T3_12"
						(effects
							(font
								(size 1.27 1.27)
							)
						)
					)
					(number "AH21"
						(effects
							(font
								(size 1.27 1.27)
							)
						)
					)
				)
				(pin bidirectional line
					(at 0 -116.84 180)
					(length 5.08)
					(name "IO_L23N_T3_12"
						(effects
							(font
								(size 1.27 1.27)
							)
						)
					)
					(number "AJ21"
						(effects
							(font
								(size 1.27 1.27)
							)
						)
					)
				)
				(pin bidirectional line
					(at 0 -119.38 180)
					(length 5.08)
					(name "IO_L24P_T3_12"
						(effects
							(font
								(size 1.27 1.27)
							)
						)
					)
					(number "AK20"
						(effects
							(font
								(size 1.27 1.27)
							)
						)
					)
				)
				(pin bidirectional line
					(at 0 -121.92 180)
					(length 5.08)
					(name "IO_L24N_T3_12"
						(effects
							(font
								(size 1.27 1.27)
							)
						)
					)
					(number "AK21"
						(effects
							(font
								(size 1.27 1.27)
							)
						)
					)
				)
				(pin bidirectional line
					(at 0 -124.46 180)
					(length 5.08)
					(name "IO_25_12"
						(effects
							(font
								(size 1.27 1.27)
							)
						)
					)
					(number "AE20"
						(effects
							(font
								(size 1.27 1.27)
							)
						)
					)
				)
			)
			(symbol "XC7K410T-2FFG900I_2_2_1"
				(rectangle
					(start -40.64 7.62)
					(end -5.08 -129.54)
					(stroke
						(width 0.254)
						(type default)
					)
					(fill
						(type background)
					)
				)
				(polyline
					(pts
						(xy -30.48 1.27) (xy -38.1 1.27) (xy -38.1 -125.73) (xy -30.48 -125.73)
					)
					(stroke
						(width 0.254)
						(type default)
					)
					(fill
						(type background)
					)
				)
				(text "BANK 14"
					(at -24.13 3.81 0)
					(effects
						(font
							(size 1.27 1.27)
							(thickness 0.15)
						)
						(justify left bottom)
					)
				)
				(pin bidirectional line
					(at 0 0 180)
					(length 5.08)
					(name "IO_0_14"
						(effects
							(font
								(size 1.27 1.27)
							)
						)
					)
					(number "R19"
						(effects
							(font
								(size 1.27 1.27)
							)
						)
					)
				)
				(pin bidirectional line
					(at 0 -2.54 180)
					(length 5.08)
					(name "IO_L1P_T0_D00_MOSI_14"
						(effects
							(font
								(size 1.27 1.27)
							)
						)
					)
					(number "P24"
						(effects
							(font
								(size 1.27 1.27)
							)
						)
					)
				)
				(pin bidirectional line
					(at 0 -5.08 180)
					(length 5.08)
					(name "IO_L1N_T0_D01_DIN_14"
						(effects
							(font
								(size 1.27 1.27)
							)
						)
					)
					(number "R25"
						(effects
							(font
								(size 1.27 1.27)
							)
						)
					)
				)
				(pin bidirectional line
					(at 0 -7.62 180)
					(length 5.08)
					(name "IO_L2P_T0_D02_14"
						(effects
							(font
								(size 1.27 1.27)
							)
						)
					)
					(number "R20"
						(effects
							(font
								(size 1.27 1.27)
							)
						)
					)
				)
				(pin bidirectional line
					(at 0 -10.16 180)
					(length 5.08)
					(name "IO_L2N_T0_D03_14"
						(effects
							(font
								(size 1.27 1.27)
							)
						)
					)
					(number "R21"
						(effects
							(font
								(size 1.27 1.27)
							)
						)
					)
				)
				(pin bidirectional line
					(at 0 -12.7 180)
					(length 5.08)
					(name "IO_L3P_T0_DQS_PUDC_B_14"
						(effects
							(font
								(size 1.27 1.27)
							)
						)
					)
					(number "R23"
						(effects
							(font
								(size 1.27 1.27)
							)
						)
					)
				)
				(pin bidirectional line
					(at 0 -15.24 180)
					(length 5.08)
					(name "IO_L3N_T0_DQS_EMCCLK_14"
						(effects
							(font
								(size 1.27 1.27)
							)
						)
					)
					(number "R24"
						(effects
							(font
								(size 1.27 1.27)
							)
						)
					)
				)
				(pin bidirectional line
					(at 0 -17.78 180)
					(length 5.08)
					(name "IO_L4P_T0_D04_14"
						(effects
							(font
								(size 1.27 1.27)
							)
						)
					)
					(number "T20"
						(effects
							(font
								(size 1.27 1.27)
							)
						)
					)
				)
				(pin bidirectional line
					(at 0 -20.32 180)
					(length 5.08)
					(name "IO_L4N_T0_D05_14"
						(effects
							(font
								(size 1.27 1.27)
							)
						)
					)
					(number "T21"
						(effects
							(font
								(size 1.27 1.27)
							)
						)
					)
				)
				(pin bidirectional line
					(at 0 -22.86 180)
					(length 5.08)
					(name "IO_L5P_T0_D06_14"
						(effects
							(font
								(size 1.27 1.27)
							)
						)
					)
					(number "T22"
						(effects
							(font
								(size 1.27 1.27)
							)
						)
					)
				)
				(pin bidirectional line
					(at 0 -25.4 180)
					(length 5.08)
					(name "IO_L5N_T0_D07_14"
						(effects
							(font
								(size 1.27 1.27)
							)
						)
					)
					(number "T23"
						(effects
							(font
								(size 1.27 1.27)
							)
						)
					)
				)
				(pin bidirectional line
					(at 0 -27.94 180)
					(length 5.08)
					(name "IO_L6P_T0_FCS_B_14"
						(effects
							(font
								(size 1.27 1.27)
							)
						)
					)
					(number "U19"
						(effects
							(font
								(size 1.27 1.27)
							)
						)
					)
				)
				(pin bidirectional line
					(at 0 -30.48 180)
					(length 5.08)
					(name "IO_L6N_T0_D08_VREF_14"
						(effects
							(font
								(size 1.27 1.27)
							)
						)
					)
					(number "U20"
						(effects
							(font
								(size 1.27 1.27)
							)
						)
					)
				)
				(pin bidirectional line
					(at 0 -33.02 180)
					(length 5.08)
					(name "IO_L7P_T1_D09_14"
						(effects
							(font
								(size 1.27 1.27)
							)
						)
					)
					(number "P29"
						(effects
							(font
								(size 1.27 1.27)
							)
						)
					)
				)
				(pin bidirectional line
					(at 0 -35.56 180)
					(length 5.08)
					(name "IO_L7N_T1_D10_14"
						(effects
							(font
								(size 1.27 1.27)
							)
						)
					)
					(number "R29"
						(effects
							(font
								(size 1.27 1.27)
							)
						)
					)
				)
				(pin bidirectional line
					(at 0 -38.1 180)
					(length 5.08)
					(name "IO_L8P_T1_D11_14"
						(effects
							(font
								(size 1.27 1.27)
							)
						)
					)
					(number "P27"
						(effects
							(font
								(size 1.27 1.27)
							)
						)
					)
				)
				(pin bidirectional line
					(at 0 -40.64 180)
					(length 5.08)
					(name "IO_L8N_T1_D12_14"
						(effects
							(font
								(size 1.27 1.27)
							)
						)
					)
					(number "P28"
						(effects
							(font
								(size 1.27 1.27)
							)
						)
					)
				)
				(pin bidirectional line
					(at 0 -43.18 180)
					(length 5.08)
					(name "IO_L9P_T1_DQS_14"
						(effects
							(font
								(size 1.27 1.27)
							)
						)
					)
					(number "R30"
						(effects
							(font
								(size 1.27 1.27)
							)
						)
					)
				)
				(pin bidirectional line
					(at 0 -45.72 180)
					(length 5.08)
					(name "IO_L9N_T1_DQS_D13_14"
						(effects
							(font
								(size 1.27 1.27)
							)
						)
					)
					(number "T30"
						(effects
							(font
								(size 1.27 1.27)
							)
						)
					)
				)
				(pin bidirectional line
					(at 0 -48.26 180)
					(length 5.08)
					(name "IO_L10P_T1_D14_14"
						(effects
							(font
								(size 1.27 1.27)
							)
						)
					)
					(number "P26"
						(effects
							(font
								(size 1.27 1.27)
							)
						)
					)
				)
				(pin bidirectional line
					(at 0 -50.8 180)
					(length 5.08)
					(name "IO_L10N_T1_D15_14"
						(effects
							(font
								(size 1.27 1.27)
							)
						)
					)
					(number "R26"
						(effects
							(font
								(size 1.27 1.27)
							)
						)
					)
				)
				(pin bidirectional line
					(at 0 -53.34 180)
					(length 5.08)
					(name "IO_L11P_T1_SRCC_14"
						(effects
							(font
								(size 1.27 1.27)
							)
						)
					)
					(number "R28"
						(effects
							(font
								(size 1.27 1.27)
							)
						)
					)
				)
				(pin bidirectional line
					(at 0 -55.88 180)
					(length 5.08)
					(name "IO_L11N_T1_SRCC_14"
						(effects
							(font
								(size 1.27 1.27)
							)
						)
					)
					(number "T28"
						(effects
							(font
								(size 1.27 1.27)
							)
						)
					)
				)
				(pin bidirectional line
					(at 0 -58.42 180)
					(length 5.08)
					(name "IO_L12P_T1_MRCC_14"
						(effects
							(font
								(size 1.27 1.27)
							)
						)
					)
					(number "T26"
						(effects
							(font
								(size 1.27 1.27)
							)
						)
					)
				)
				(pin bidirectional line
					(at 0 -60.96 180)
					(length 5.08)
					(name "IO_L12N_T1_MRCC_14"
						(effects
							(font
								(size 1.27 1.27)
							)
						)
					)
					(number "T27"
						(effects
							(font
								(size 1.27 1.27)
							)
						)
					)
				)
				(pin bidirectional line
					(at 0 -63.5 180)
					(length 5.08)
					(name "IO_L13P_T2_MRCC_14"
						(effects
							(font
								(size 1.27 1.27)
							)
						)
					)
					(number "U27"
						(effects
							(font
								(size 1.27 1.27)
							)
						)
					)
				)
				(pin bidirectional line
					(at 0 -66.04 180)
					(length 5.08)
					(name "IO_L13N_T2_MRCC_14"
						(effects
							(font
								(size 1.27 1.27)
							)
						)
					)
					(number "U28"
						(effects
							(font
								(size 1.27 1.27)
							)
						)
					)
				)
				(pin bidirectional line
					(at 0 -68.58 180)
					(length 5.08)
					(name "IO_L14P_T2_SRCC_14"
						(effects
							(font
								(size 1.27 1.27)
							)
						)
					)
					(number "T25"
						(effects
							(font
								(size 1.27 1.27)
							)
						)
					)
				)
				(pin bidirectional line
					(at 0 -71.12 180)
					(length 5.08)
					(name "IO_L14N_T2_SRCC_14"
						(effects
							(font
								(size 1.27 1.27)
							)
						)
					)
					(number "U25"
						(effects
							(font
								(size 1.27 1.27)
							)
						)
					)
				)
				(pin bidirectional line
					(at 0 -73.66 180)
					(length 5.08)
					(name "IO_L15P_T2_DQS_RDWR_B_14"
						(effects
							(font
								(size 1.27 1.27)
							)
						)
					)
					(number "U29"
						(effects
							(font
								(size 1.27 1.27)
							)
						)
					)
				)
				(pin bidirectional line
					(at 0 -76.2 180)
					(length 5.08)
					(name "IO_L15N_T2_DQS_DOUT_CSO_B_14"
						(effects
							(font
								(size 1.27 1.27)
							)
						)
					)
					(number "U30"
						(effects
							(font
								(size 1.27 1.27)
							)
						)
					)
				)
				(pin bidirectional line
					(at 0 -78.74 180)
					(length 5.08)
					(name "IO_L16P_T2_CSI_B_14"
						(effects
							(font
								(size 1.27 1.27)
							)
						)
					)
					(number "V26"
						(effects
							(font
								(size 1.27 1.27)
							)
						)
					)
				)
				(pin bidirectional line
					(at 0 -81.28 180)
					(length 5.08)
					(name "IO_L16N_T2_A15_D31_14"
						(effects
							(font
								(size 1.27 1.27)
							)
						)
					)
					(number "V27"
						(effects
							(font
								(size 1.27 1.27)
							)
						)
					)
				)
				(pin bidirectional line
					(at 0 -83.82 180)
					(length 5.08)
					(name "IO_L17P_T2_A14_D30_14"
						(effects
							(font
								(size 1.27 1.27)
							)
						)
					)
					(number "V29"
						(effects
							(font
								(size 1.27 1.27)
							)
						)
					)
				)
				(pin bidirectional line
					(at 0 -86.36 180)
					(length 5.08)
					(name "IO_L17N_T2_A13_D29_14"
						(effects
							(font
								(size 1.27 1.27)
							)
						)
					)
					(number "V30"
						(effects
							(font
								(size 1.27 1.27)
							)
						)
					)
				)
				(pin bidirectional line
					(at 0 -88.9 180)
					(length 5.08)
					(name "IO_L18P_T2_A12_D28_14"
						(effects
							(font
								(size 1.27 1.27)
							)
						)
					)
					(number "V25"
						(effects
							(font
								(size 1.27 1.27)
							)
						)
					)
				)
				(pin bidirectional line
					(at 0 -91.44 180)
					(length 5.08)
					(name "IO_L18N_T2_A11_D27_14"
						(effects
							(font
								(size 1.27 1.27)
							)
						)
					)
					(number "W26"
						(effects
							(font
								(size 1.27 1.27)
							)
						)
					)
				)
				(pin bidirectional line
					(at 0 -93.98 180)
					(length 5.08)
					(name "IO_L19P_T3_A10_D26_14"
						(effects
							(font
								(size 1.27 1.27)
							)
						)
					)
					(number "V19"
						(effects
							(font
								(size 1.27 1.27)
							)
						)
					)
				)
				(pin bidirectional line
					(at 0 -96.52 180)
					(length 5.08)
					(name "IO_L19N_T3_A09_D25_VREF_14"
						(effects
							(font
								(size 1.27 1.27)
							)
						)
					)
					(number "V20"
						(effects
							(font
								(size 1.27 1.27)
							)
						)
					)
				)
				(pin bidirectional line
					(at 0 -99.06 180)
					(length 5.08)
					(name "IO_L20P_T3_A08_D24_14"
						(effects
							(font
								(size 1.27 1.27)
							)
						)
					)
					(number "W23"
						(effects
							(font
								(size 1.27 1.27)
							)
						)
					)
				)
				(pin bidirectional line
					(at 0 -101.6 180)
					(length 5.08)
					(name "IO_L20N_T3_A07_D23_14"
						(effects
							(font
								(size 1.27 1.27)
							)
						)
					)
					(number "W24"
						(effects
							(font
								(size 1.27 1.27)
							)
						)
					)
				)
				(pin bidirectional line
					(at 0 -104.14 180)
					(length 5.08)
					(name "IO_L21P_T3_DQS_14"
						(effects
							(font
								(size 1.27 1.27)
							)
						)
					)
					(number "U22"
						(effects
							(font
								(size 1.27 1.27)
							)
						)
					)
				)
				(pin bidirectional line
					(at 0 -106.68 180)
					(length 5.08)
					(name "IO_L21N_T3_DQS_A06_D22_14"
						(effects
							(font
								(size 1.27 1.27)
							)
						)
					)
					(number "U23"
						(effects
							(font
								(size 1.27 1.27)
							)
						)
					)
				)
				(pin bidirectional line
					(at 0 -109.22 180)
					(length 5.08)
					(name "IO_L22P_T3_A05_D21_14"
						(effects
							(font
								(size 1.27 1.27)
							)
						)
					)
					(number "V21"
						(effects
							(font
								(size 1.27 1.27)
							)
						)
					)
				)
				(pin bidirectional line
					(at 0 -111.76 180)
					(length 5.08)
					(name "IO_L22N_T3_A04_D20_14"
						(effects
							(font
								(size 1.27 1.27)
							)
						)
					)
					(number "V22"
						(effects
							(font
								(size 1.27 1.27)
							)
						)
					)
				)
				(pin bidirectional line
					(at 0 -114.3 180)
					(length 5.08)
					(name "IO_L23P_T3_A03_D19_14"
						(effects
							(font
								(size 1.27 1.27)
							)
						)
					)
					(number "U24"
						(effects
							(font
								(size 1.27 1.27)
							)
						)
					)
				)
				(pin bidirectional line
					(at 0 -116.84 180)
					(length 5.08)
					(name "IO_L23N_T3_A02_D18_14"
						(effects
							(font
								(size 1.27 1.27)
							)
						)
					)
					(number "V24"
						(effects
							(font
								(size 1.27 1.27)
							)
						)
					)
				)
				(pin bidirectional line
					(at 0 -119.38 180)
					(length 5.08)
					(name "IO_L24P_T3_A01_D17_14"
						(effects
							(font
								(size 1.27 1.27)
							)
						)
					)
					(number "W21"
						(effects
							(font
								(size 1.27 1.27)
							)
						)
					)
				)
				(pin bidirectional line
					(at 0 -121.92 180)
					(length 5.08)
					(name "IO_L24N_T3_A00_D16_14"
						(effects
							(font
								(size 1.27 1.27)
							)
						)
					)
					(number "W22"
						(effects
							(font
								(size 1.27 1.27)
							)
						)
					)
				)
				(pin bidirectional line
					(at 0 -124.46 180)
					(length 5.08)
					(name "IO_25_14"
						(effects
							(font
								(size 1.27 1.27)
							)
						)
					)
					(number "W19"
						(effects
							(font
								(size 1.27 1.27)
							)
						)
					)
				)
			)
			(symbol "XC7K410T-2FFG900I_2_3_1"
				(rectangle
					(start -40.64 -129.54)
					(end -5.08 7.62)
					(stroke
						(width 0.254)
						(type default)
					)
					(fill
						(type background)
					)
				)
				(polyline
					(pts
						(xy -30.48 1.27) (xy -38.1 1.27) (xy -38.1 -125.73) (xy -30.48 -125.73)
					)
					(stroke
						(width 0.254)
						(type default)
					)
					(fill
						(type background)
					)
				)
				(text "BANK 16"
					(at -24.13 3.81 0)
					(effects
						(font
							(size 1.27 1.27)
							(thickness 0.15)
						)
						(justify left bottom)
					)
				)
				(pin bidirectional line
					(at 0 0 180)
					(length 5.08)
					(name "IO_0_16"
						(effects
							(font
								(size 1.27 1.27)
							)
						)
					)
					(number "F23"
						(effects
							(font
								(size 1.27 1.27)
							)
						)
					)
				)
				(pin bidirectional line
					(at 0 -2.54 180)
					(length 5.08)
					(name "IO_L1P_T0_16"
						(effects
							(font
								(size 1.27 1.27)
							)
						)
					)
					(number "B23"
						(effects
							(font
								(size 1.27 1.27)
							)
						)
					)
				)
				(pin bidirectional line
					(at 0 -5.08 180)
					(length 5.08)
					(name "IO_L1N_T0_16"
						(effects
							(font
								(size 1.27 1.27)
							)
						)
					)
					(number "A23"
						(effects
							(font
								(size 1.27 1.27)
							)
						)
					)
				)
				(pin bidirectional line
					(at 0 -7.62 180)
					(length 5.08)
					(name "IO_L2P_T0_16"
						(effects
							(font
								(size 1.27 1.27)
							)
						)
					)
					(number "E23"
						(effects
							(font
								(size 1.27 1.27)
							)
						)
					)
				)
				(pin bidirectional line
					(at 0 -10.16 180)
					(length 5.08)
					(name "IO_L2N_T0_16"
						(effects
							(font
								(size 1.27 1.27)
							)
						)
					)
					(number "D23"
						(effects
							(font
								(size 1.27 1.27)
							)
						)
					)
				)
				(pin bidirectional line
					(at 0 -12.7 180)
					(length 5.08)
					(name "IO_L3P_T0_DQS_16"
						(effects
							(font
								(size 1.27 1.27)
							)
						)
					)
					(number "F25"
						(effects
							(font
								(size 1.27 1.27)
							)
						)
					)
				)
				(pin bidirectional line
					(at 0 -15.24 180)
					(length 5.08)
					(name "IO_L3N_T0_DQS_16"
						(effects
							(font
								(size 1.27 1.27)
							)
						)
					)
					(number "E25"
						(effects
							(font
								(size 1.27 1.27)
							)
						)
					)
				)
				(pin bidirectional line
					(at 0 -17.78 180)
					(length 5.08)
					(name "IO_L4P_T0_16"
						(effects
							(font
								(size 1.27 1.27)
							)
						)
					)
					(number "E24"
						(effects
							(font
								(size 1.27 1.27)
							)
						)
					)
				)
				(pin bidirectional line
					(at 0 -20.32 180)
					(length 5.08)
					(name "IO_L4N_T0_16"
						(effects
							(font
								(size 1.27 1.27)
							)
						)
					)
					(number "D24"
						(effects
							(font
								(size 1.27 1.27)
							)
						)
					)
				)
				(pin bidirectional line
					(at 0 -22.86 180)
					(length 5.08)
					(name "IO_L5P_T0_16"
						(effects
							(font
								(size 1.27 1.27)
							)
						)
					)
					(number "F26"
						(effects
							(font
								(size 1.27 1.27)
							)
						)
					)
				)
				(pin bidirectional line
					(at 0 -25.4 180)
					(length 5.08)
					(name "IO_L5N_T0_16"
						(effects
							(font
								(size 1.27 1.27)
							)
						)
					)
					(number "E26"
						(effects
							(font
								(size 1.27 1.27)
							)
						)
					)
				)
				(pin bidirectional line
					(at 0 -27.94 180)
					(length 5.08)
					(name "IO_L6P_T0_16"
						(effects
							(font
								(size 1.27 1.27)
							)
						)
					)
					(number "G23"
						(effects
							(font
								(size 1.27 1.27)
							)
						)
					)
				)
				(pin bidirectional line
					(at 0 -30.48 180)
					(length 5.08)
					(name "IO_L6N_T0_VREF_16"
						(effects
							(font
								(size 1.27 1.27)
							)
						)
					)
					(number "G24"
						(effects
							(font
								(size 1.27 1.27)
							)
						)
					)
				)
				(pin bidirectional line
					(at 0 -33.02 180)
					(length 5.08)
					(name "IO_L7P_T1_16"
						(effects
							(font
								(size 1.27 1.27)
							)
						)
					)
					(number "B27"
						(effects
							(font
								(size 1.27 1.27)
							)
						)
					)
				)
				(pin bidirectional line
					(at 0 -35.56 180)
					(length 5.08)
					(name "IO_L7N_T1_16"
						(effects
							(font
								(size 1.27 1.27)
							)
						)
					)
					(number "A27"
						(effects
							(font
								(size 1.27 1.27)
							)
						)
					)
				)
				(pin bidirectional line
					(at 0 -38.1 180)
					(length 5.08)
					(name "IO_L8P_T1_16"
						(effects
							(font
								(size 1.27 1.27)
							)
						)
					)
					(number "C24"
						(effects
							(font
								(size 1.27 1.27)
							)
						)
					)
				)
				(pin bidirectional line
					(at 0 -40.64 180)
					(length 5.08)
					(name "IO_L8N_T1_16"
						(effects
							(font
								(size 1.27 1.27)
							)
						)
					)
					(number "B24"
						(effects
							(font
								(size 1.27 1.27)
							)
						)
					)
				)
				(pin bidirectional line
					(at 0 -43.18 180)
					(length 5.08)
					(name "IO_L9P_T1_DQS_16"
						(effects
							(font
								(size 1.27 1.27)
							)
						)
					)
					(number "B28"
						(effects
							(font
								(size 1.27 1.27)
							)
						)
					)
				)
				(pin bidirectional line
					(at 0 -45.72 180)
					(length 5.08)
					(name "IO_L9N_T1_DQS_16"
						(effects
							(font
								(size 1.27 1.27)
							)
						)
					)
					(number "A28"
						(effects
							(font
								(size 1.27 1.27)
							)
						)
					)
				)
				(pin bidirectional line
					(at 0 -48.26 180)
					(length 5.08)
					(name "IO_L10P_T1_16"
						(effects
							(font
								(size 1.27 1.27)
							)
						)
					)
					(number "A25"
						(effects
							(font
								(size 1.27 1.27)
							)
						)
					)
				)
				(pin bidirectional line
					(at 0 -50.8 180)
					(length 5.08)
					(name "IO_L10N_T1_16"
						(effects
							(font
								(size 1.27 1.27)
							)
						)
					)
					(number "A26"
						(effects
							(font
								(size 1.27 1.27)
							)
						)
					)
				)
				(pin bidirectional line
					(at 0 -53.34 180)
					(length 5.08)
					(name "IO_L11P_T1_SRCC_16"
						(effects
							(font
								(size 1.27 1.27)
							)
						)
					)
					(number "D26"
						(effects
							(font
								(size 1.27 1.27)
							)
						)
					)
				)
				(pin bidirectional line
					(at 0 -55.88 180)
					(length 5.08)
					(name "IO_L11N_T1_SRCC_16"
						(effects
							(font
								(size 1.27 1.27)
							)
						)
					)
					(number "C26"
						(effects
							(font
								(size 1.27 1.27)
							)
						)
					)
				)
				(pin bidirectional line
					(at 0 -58.42 180)
					(length 5.08)
					(name "IO_L12P_T1_MRCC_16"
						(effects
							(font
								(size 1.27 1.27)
							)
						)
					)
					(number "C25"
						(effects
							(font
								(size 1.27 1.27)
							)
						)
					)
				)
				(pin bidirectional line
					(at 0 -60.96 180)
					(length 5.08)
					(name "IO_L12N_T1_MRCC_16"
						(effects
							(font
								(size 1.27 1.27)
							)
						)
					)
					(number "B25"
						(effects
							(font
								(size 1.27 1.27)
							)
						)
					)
				)
				(pin bidirectional line
					(at 0 -63.5 180)
					(length 5.08)
					(name "IO_L13P_T2_MRCC_16"
						(effects
							(font
								(size 1.27 1.27)
							)
						)
					)
					(number "D27"
						(effects
							(font
								(size 1.27 1.27)
							)
						)
					)
				)
				(pin bidirectional line
					(at 0 -66.04 180)
					(length 5.08)
					(name "IO_L13N_T2_MRCC_16"
						(effects
							(font
								(size 1.27 1.27)
							)
						)
					)
					(number "C27"
						(effects
							(font
								(size 1.27 1.27)
							)
						)
					)
				)
				(pin bidirectional line
					(at 0 -68.58 180)
					(length 5.08)
					(name "IO_L14P_T2_SRCC_16"
						(effects
							(font
								(size 1.27 1.27)
							)
						)
					)
					(number "E28"
						(effects
							(font
								(size 1.27 1.27)
							)
						)
					)
				)
				(pin bidirectional line
					(at 0 -71.12 180)
					(length 5.08)
					(name "IO_L14N_T2_SRCC_16"
						(effects
							(font
								(size 1.27 1.27)
							)
						)
					)
					(number "D28"
						(effects
							(font
								(size 1.27 1.27)
							)
						)
					)
				)
				(pin bidirectional line
					(at 0 -73.66 180)
					(length 5.08)
					(name "IO_L15P_T2_DQS_16"
						(effects
							(font
								(size 1.27 1.27)
							)
						)
					)
					(number "C29"
						(effects
							(font
								(size 1.27 1.27)
							)
						)
					)
				)
				(pin bidirectional line
					(at 0 -76.2 180)
					(length 5.08)
					(name "IO_L15N_T2_DQS_16"
						(effects
							(font
								(size 1.27 1.27)
							)
						)
					)
					(number "B29"
						(effects
							(font
								(size 1.27 1.27)
							)
						)
					)
				)
				(pin bidirectional line
					(at 0 -78.74 180)
					(length 5.08)
					(name "IO_L16P_T2_16"
						(effects
							(font
								(size 1.27 1.27)
							)
						)
					)
					(number "D29"
						(effects
							(font
								(size 1.27 1.27)
							)
						)
					)
				)
				(pin bidirectional line
					(at 0 -81.28 180)
					(length 5.08)
					(name "IO_L16N_T2_16"
						(effects
							(font
								(size 1.27 1.27)
							)
						)
					)
					(number "C30"
						(effects
							(font
								(size 1.27 1.27)
							)
						)
					)
				)
				(pin bidirectional line
					(at 0 -83.82 180)
					(length 5.08)
					(name "IO_L17P_T2_16"
						(effects
							(font
								(size 1.27 1.27)
							)
						)
					)
					(number "B30"
						(effects
							(font
								(size 1.27 1.27)
							)
						)
					)
				)
				(pin bidirectional line
					(at 0 -86.36 180)
					(length 5.08)
					(name "IO_L17N_T2_16"
						(effects
							(font
								(size 1.27 1.27)
							)
						)
					)
					(number "A30"
						(effects
							(font
								(size 1.27 1.27)
							)
						)
					)
				)
				(pin bidirectional line
					(at 0 -88.9 180)
					(length 5.08)
					(name "IO_L18P_T2_16"
						(effects
							(font
								(size 1.27 1.27)
							)
						)
					)
					(number "E29"
						(effects
							(font
								(size 1.27 1.27)
							)
						)
					)
				)
				(pin bidirectional line
					(at 0 -91.44 180)
					(length 5.08)
					(name "IO_L18N_T2_16"
						(effects
							(font
								(size 1.27 1.27)
							)
						)
					)
					(number "E30"
						(effects
							(font
								(size 1.27 1.27)
							)
						)
					)
				)
				(pin bidirectional line
					(at 0 -93.98 180)
					(length 5.08)
					(name "IO_L19P_T3_16"
						(effects
							(font
								(size 1.27 1.27)
							)
						)
					)
					(number "H24"
						(effects
							(font
								(size 1.27 1.27)
							)
						)
					)
				)
				(pin bidirectional line
					(at 0 -96.52 180)
					(length 5.08)
					(name "IO_L19N_T3_VREF_16"
						(effects
							(font
								(size 1.27 1.27)
							)
						)
					)
					(number "H25"
						(effects
							(font
								(size 1.27 1.27)
							)
						)
					)
				)
				(pin bidirectional line
					(at 0 -99.06 180)
					(length 5.08)
					(name "IO_L20P_T3_16"
						(effects
							(font
								(size 1.27 1.27)
							)
						)
					)
					(number "G28"
						(effects
							(font
								(size 1.27 1.27)
							)
						)
					)
				)
				(pin bidirectional line
					(at 0 -101.6 180)
					(length 5.08)
					(name "IO_L20N_T3_16"
						(effects
							(font
								(size 1.27 1.27)
							)
						)
					)
					(number "F28"
						(effects
							(font
								(size 1.27 1.27)
							)
						)
					)
				)
				(pin bidirectional line
					(at 0 -104.14 180)
					(length 5.08)
					(name "IO_L21P_T3_DQS_16"
						(effects
							(font
								(size 1.27 1.27)
							)
						)
					)
					(number "G27"
						(effects
							(font
								(size 1.27 1.27)
							)
						)
					)
				)
				(pin bidirectional line
					(at 0 -106.68 180)
					(length 5.08)
					(name "IO_L21N_T3_DQS_16"
						(effects
							(font
								(size 1.27 1.27)
							)
						)
					)
					(number "F27"
						(effects
							(font
								(size 1.27 1.27)
							)
						)
					)
				)
				(pin bidirectional line
					(at 0 -109.22 180)
					(length 5.08)
					(name "IO_L22P_T3_16"
						(effects
							(font
								(size 1.27 1.27)
							)
						)
					)
					(number "G29"
						(effects
							(font
								(size 1.27 1.27)
							)
						)
					)
				)
				(pin bidirectional line
					(at 0 -111.76 180)
					(length 5.08)
					(name "IO_L22N_T3_16"
						(effects
							(font
								(size 1.27 1.27)
							)
						)
					)
					(number "F30"
						(effects
							(font
								(size 1.27 1.27)
							)
						)
					)
				)
				(pin bidirectional line
					(at 0 -114.3 180)
					(length 5.08)
					(name "IO_L23P_T3_16"
						(effects
							(font
								(size 1.27 1.27)
							)
						)
					)
					(number "H26"
						(effects
							(font
								(size 1.27 1.27)
							)
						)
					)
				)
				(pin bidirectional line
					(at 0 -116.84 180)
					(length 5.08)
					(name "IO_L23N_T3_16"
						(effects
							(font
								(size 1.27 1.27)
							)
						)
					)
					(number "H27"
						(effects
							(font
								(size 1.27 1.27)
							)
						)
					)
				)
				(pin bidirectional line
					(at 0 -119.38 180)
					(length 5.08)
					(name "IO_L24P_T3_16"
						(effects
							(font
								(size 1.27 1.27)
							)
						)
					)
					(number "H30"
						(effects
							(font
								(size 1.27 1.27)
							)
						)
					)
				)
				(pin bidirectional line
					(at 0 -121.92 180)
					(length 5.08)
					(name "IO_L24N_T3_16"
						(effects
							(font
								(size 1.27 1.27)
							)
						)
					)
					(number "G30"
						(effects
							(font
								(size 1.27 1.27)
							)
						)
					)
				)
				(pin bidirectional line
					(at 0 -124.46 180)
					(length 5.08)
					(name "IO_25_16"
						(effects
							(font
								(size 1.27 1.27)
							)
						)
					)
					(number "G25"
						(effects
							(font
								(size 1.27 1.27)
							)
						)
					)
				)
			)
			(symbol "XC7K410T-2FFG900I_2_4_1"
				(rectangle
					(start -40.64 -129.54)
					(end -5.08 7.62)
					(stroke
						(width 0.254)
						(type default)
					)
					(fill
						(type background)
					)
				)
				(polyline
					(pts
						(xy -30.48 1.27) (xy -38.1 1.27) (xy -38.1 -125.73) (xy -30.48 -125.73)
					)
					(stroke
						(width 0.254)
						(type default)
					)
					(fill
						(type background)
					)
				)
				(text "BANK 18"
					(at -24.13 3.81 0)
					(effects
						(font
							(size 1.27 1.27)
							(thickness 0.15)
						)
						(justify left bottom)
					)
				)
				(pin bidirectional line
					(at 0 0 180)
					(length 5.08)
					(name "IO_0_18"
						(effects
							(font
								(size 1.27 1.27)
							)
						)
					)
					(number "G12"
						(effects
							(font
								(size 1.27 1.27)
							)
						)
					)
				)
				(pin bidirectional line
					(at 0 -2.54 180)
					(length 5.08)
					(name "IO_L1P_T0_18"
						(effects
							(font
								(size 1.27 1.27)
							)
						)
					)
					(number "L16"
						(effects
							(font
								(size 1.27 1.27)
							)
						)
					)
				)
				(pin bidirectional line
					(at 0 -5.08 180)
					(length 5.08)
					(name "IO_L1N_T0_18"
						(effects
							(font
								(size 1.27 1.27)
							)
						)
					)
					(number "K16"
						(effects
							(font
								(size 1.27 1.27)
							)
						)
					)
				)
				(pin bidirectional line
					(at 0 -7.62 180)
					(length 5.08)
					(name "IO_L2P_T0_18"
						(effects
							(font
								(size 1.27 1.27)
							)
						)
					)
					(number "L15"
						(effects
							(font
								(size 1.27 1.27)
							)
						)
					)
				)
				(pin bidirectional line
					(at 0 -10.16 180)
					(length 5.08)
					(name "IO_L2N_T0_18"
						(effects
							(font
								(size 1.27 1.27)
							)
						)
					)
					(number "K15"
						(effects
							(font
								(size 1.27 1.27)
							)
						)
					)
				)
				(pin bidirectional line
					(at 0 -12.7 180)
					(length 5.08)
					(name "IO_L3P_T0_DQS_18"
						(effects
							(font
								(size 1.27 1.27)
							)
						)
					)
					(number "L12"
						(effects
							(font
								(size 1.27 1.27)
							)
						)
					)
				)
				(pin bidirectional line
					(at 0 -15.24 180)
					(length 5.08)
					(name "IO_L3N_T0_DQS_18"
						(effects
							(font
								(size 1.27 1.27)
							)
						)
					)
					(number "L13"
						(effects
							(font
								(size 1.27 1.27)
							)
						)
					)
				)
				(pin bidirectional line
					(at 0 -17.78 180)
					(length 5.08)
					(name "IO_L4P_T0_18"
						(effects
							(font
								(size 1.27 1.27)
							)
						)
					)
					(number "K13"
						(effects
							(font
								(size 1.27 1.27)
							)
						)
					)
				)
				(pin bidirectional line
					(at 0 -20.32 180)
					(length 5.08)
					(name "IO_L4N_T0_18"
						(effects
							(font
								(size 1.27 1.27)
							)
						)
					)
					(number "J13"
						(effects
							(font
								(size 1.27 1.27)
							)
						)
					)
				)
				(pin bidirectional line
					(at 0 -22.86 180)
					(length 5.08)
					(name "IO_L5P_T0_18"
						(effects
							(font
								(size 1.27 1.27)
							)
						)
					)
					(number "K14"
						(effects
							(font
								(size 1.27 1.27)
							)
						)
					)
				)
				(pin bidirectional line
					(at 0 -25.4 180)
					(length 5.08)
					(name "IO_L5N_T0_18"
						(effects
							(font
								(size 1.27 1.27)
							)
						)
					)
					(number "J14"
						(effects
							(font
								(size 1.27 1.27)
							)
						)
					)
				)
				(pin bidirectional line
					(at 0 -27.94 180)
					(length 5.08)
					(name "IO_L6P_T0_18"
						(effects
							(font
								(size 1.27 1.27)
							)
						)
					)
					(number "L11"
						(effects
							(font
								(size 1.27 1.27)
							)
						)
					)
				)
				(pin bidirectional line
					(at 0 -30.48 180)
					(length 5.08)
					(name "IO_L6N_T0_VREF_18"
						(effects
							(font
								(size 1.27 1.27)
							)
						)
					)
					(number "K11"
						(effects
							(font
								(size 1.27 1.27)
							)
						)
					)
				)
				(pin bidirectional line
					(at 0 -33.02 180)
					(length 5.08)
					(name "IO_L7P_T1_18"
						(effects
							(font
								(size 1.27 1.27)
							)
						)
					)
					(number "H15"
						(effects
							(font
								(size 1.27 1.27)
							)
						)
					)
				)
				(pin bidirectional line
					(at 0 -35.56 180)
					(length 5.08)
					(name "IO_L7N_T1_18"
						(effects
							(font
								(size 1.27 1.27)
							)
						)
					)
					(number "G15"
						(effects
							(font
								(size 1.27 1.27)
							)
						)
					)
				)
				(pin bidirectional line
					(at 0 -38.1 180)
					(length 5.08)
					(name "IO_L8P_T1_18"
						(effects
							(font
								(size 1.27 1.27)
							)
						)
					)
					(number "J11"
						(effects
							(font
								(size 1.27 1.27)
							)
						)
					)
				)
				(pin bidirectional line
					(at 0 -40.64 180)
					(length 5.08)
					(name "IO_L8N_T1_18"
						(effects
							(font
								(size 1.27 1.27)
							)
						)
					)
					(number "J12"
						(effects
							(font
								(size 1.27 1.27)
							)
						)
					)
				)
				(pin bidirectional line
					(at 0 -43.18 180)
					(length 5.08)
					(name "IO_L9P_T1_DQS_18"
						(effects
							(font
								(size 1.27 1.27)
							)
						)
					)
					(number "J16"
						(effects
							(font
								(size 1.27 1.27)
							)
						)
					)
				)
				(pin bidirectional line
					(at 0 -45.72 180)
					(length 5.08)
					(name "IO_L9N_T1_DQS_18"
						(effects
							(font
								(size 1.27 1.27)
							)
						)
					)
					(number "H16"
						(effects
							(font
								(size 1.27 1.27)
							)
						)
					)
				)
				(pin bidirectional line
					(at 0 -48.26 180)
					(length 5.08)
					(name "IO_L10P_T1_18"
						(effects
							(font
								(size 1.27 1.27)
							)
						)
					)
					(number "H11"
						(effects
							(font
								(size 1.27 1.27)
							)
						)
					)
				)
				(pin bidirectional line
					(at 0 -50.8 180)
					(length 5.08)
					(name "IO_L10N_T1_18"
						(effects
							(font
								(size 1.27 1.27)
							)
						)
					)
					(number "H12"
						(effects
							(font
								(size 1.27 1.27)
							)
						)
					)
				)
				(pin bidirectional line
					(at 0 -53.34 180)
					(length 5.08)
					(name "IO_L11P_T1_SRCC_18"
						(effects
							(font
								(size 1.27 1.27)
							)
						)
					)
					(number "H14"
						(effects
							(font
								(size 1.27 1.27)
							)
						)
					)
				)
				(pin bidirectional line
					(at 0 -55.88 180)
					(length 5.08)
					(name "IO_L11N_T1_SRCC_18"
						(effects
							(font
								(size 1.27 1.27)
							)
						)
					)
					(number "G14"
						(effects
							(font
								(size 1.27 1.27)
							)
						)
					)
				)
				(pin bidirectional line
					(at 0 -58.42 180)
					(length 5.08)
					(name "IO_L12P_T1_MRCC_18"
						(effects
							(font
								(size 1.27 1.27)
							)
						)
					)
					(number "G13"
						(effects
							(font
								(size 1.27 1.27)
							)
						)
					)
				)
				(pin bidirectional line
					(at 0 -60.96 180)
					(length 5.08)
					(name "IO_L12N_T1_MRCC_18"
						(effects
							(font
								(size 1.27 1.27)
							)
						)
					)
					(number "F13"
						(effects
							(font
								(size 1.27 1.27)
							)
						)
					)
				)
				(pin bidirectional line
					(at 0 -63.5 180)
					(length 5.08)
					(name "IO_L13P_T2_MRCC_18"
						(effects
							(font
								(size 1.27 1.27)
							)
						)
					)
					(number "D12"
						(effects
							(font
								(size 1.27 1.27)
							)
						)
					)
				)
				(pin bidirectional line
					(at 0 -66.04 180)
					(length 5.08)
					(name "IO_L13N_T2_MRCC_18"
						(effects
							(font
								(size 1.27 1.27)
							)
						)
					)
					(number "D13"
						(effects
							(font
								(size 1.27 1.27)
							)
						)
					)
				)
				(pin bidirectional line
					(at 0 -68.58 180)
					(length 5.08)
					(name "IO_L14P_T2_SRCC_18"
						(effects
							(font
								(size 1.27 1.27)
							)
						)
					)
					(number "F12"
						(effects
							(font
								(size 1.27 1.27)
							)
						)
					)
				)
				(pin bidirectional line
					(at 0 -71.12 180)
					(length 5.08)
					(name "IO_L14N_T2_SRCC_18"
						(effects
							(font
								(size 1.27 1.27)
							)
						)
					)
					(number "E13"
						(effects
							(font
								(size 1.27 1.27)
							)
						)
					)
				)
				(pin bidirectional line
					(at 0 -73.66 180)
					(length 5.08)
					(name "IO_L15P_T2_DQS_18"
						(effects
							(font
								(size 1.27 1.27)
							)
						)
					)
					(number "C12"
						(effects
							(font
								(size 1.27 1.27)
							)
						)
					)
				)
				(pin bidirectional line
					(at 0 -76.2 180)
					(length 5.08)
					(name "IO_L15N_T2_DQS_18"
						(effects
							(font
								(size 1.27 1.27)
							)
						)
					)
					(number "B12"
						(effects
							(font
								(size 1.27 1.27)
							)
						)
					)
				)
				(pin bidirectional line
					(at 0 -78.74 180)
					(length 5.08)
					(name "IO_L16P_T2_18"
						(effects
							(font
								(size 1.27 1.27)
							)
						)
					)
					(number "F11"
						(effects
							(font
								(size 1.27 1.27)
							)
						)
					)
				)
				(pin bidirectional line
					(at 0 -81.28 180)
					(length 5.08)
					(name "IO_L16N_T2_18"
						(effects
							(font
								(size 1.27 1.27)
							)
						)
					)
					(number "E11"
						(effects
							(font
								(size 1.27 1.27)
							)
						)
					)
				)
				(pin bidirectional line
					(at 0 -83.82 180)
					(length 5.08)
					(name "IO_L17P_T2_18"
						(effects
							(font
								(size 1.27 1.27)
							)
						)
					)
					(number "A11"
						(effects
							(font
								(size 1.27 1.27)
							)
						)
					)
				)
				(pin bidirectional line
					(at 0 -86.36 180)
					(length 5.08)
					(name "IO_L17N_T2_18"
						(effects
							(font
								(size 1.27 1.27)
							)
						)
					)
					(number "A12"
						(effects
							(font
								(size 1.27 1.27)
							)
						)
					)
				)
				(pin bidirectional line
					(at 0 -88.9 180)
					(length 5.08)
					(name "IO_L18P_T2_18"
						(effects
							(font
								(size 1.27 1.27)
							)
						)
					)
					(number "D11"
						(effects
							(font
								(size 1.27 1.27)
							)
						)
					)
				)
				(pin bidirectional line
					(at 0 -91.44 180)
					(length 5.08)
					(name "IO_L18N_T2_18"
						(effects
							(font
								(size 1.27 1.27)
							)
						)
					)
					(number "C11"
						(effects
							(font
								(size 1.27 1.27)
							)
						)
					)
				)
				(pin bidirectional line
					(at 0 -93.98 180)
					(length 5.08)
					(name "IO_L19P_T3_18"
						(effects
							(font
								(size 1.27 1.27)
							)
						)
					)
					(number "F15"
						(effects
							(font
								(size 1.27 1.27)
							)
						)
					)
				)
				(pin bidirectional line
					(at 0 -96.52 180)
					(length 5.08)
					(name "IO_L19N_T3_VREF_18"
						(effects
							(font
								(size 1.27 1.27)
							)
						)
					)
					(number "E16"
						(effects
							(font
								(size 1.27 1.27)
							)
						)
					)
				)
				(pin bidirectional line
					(at 0 -99.06 180)
					(length 5.08)
					(name "IO_L20P_T3_18"
						(effects
							(font
								(size 1.27 1.27)
							)
						)
					)
					(number "E14"
						(effects
							(font
								(size 1.27 1.27)
							)
						)
					)
				)
				(pin bidirectional line
					(at 0 -101.6 180)
					(length 5.08)
					(name "IO_L20N_T3_18"
						(effects
							(font
								(size 1.27 1.27)
							)
						)
					)
					(number "E15"
						(effects
							(font
								(size 1.27 1.27)
							)
						)
					)
				)
				(pin bidirectional line
					(at 0 -104.14 180)
					(length 5.08)
					(name "IO_L21P_T3_DQS_18"
						(effects
							(font
								(size 1.27 1.27)
							)
						)
					)
					(number "D14"
						(effects
							(font
								(size 1.27 1.27)
							)
						)
					)
				)
				(pin bidirectional line
					(at 0 -106.68 180)
					(length 5.08)
					(name "IO_L21N_T3_DQS_18"
						(effects
							(font
								(size 1.27 1.27)
							)
						)
					)
					(number "C14"
						(effects
							(font
								(size 1.27 1.27)
							)
						)
					)
				)
				(pin bidirectional line
					(at 0 -109.22 180)
					(length 5.08)
					(name "IO_L22P_T3_18"
						(effects
							(font
								(size 1.27 1.27)
							)
						)
					)
					(number "B13"
						(effects
							(font
								(size 1.27 1.27)
							)
						)
					)
				)
				(pin bidirectional line
					(at 0 -111.76 180)
					(length 5.08)
					(name "IO_L22N_T3_18"
						(effects
							(font
								(size 1.27 1.27)
							)
						)
					)
					(number "A13"
						(effects
							(font
								(size 1.27 1.27)
							)
						)
					)
				)
				(pin bidirectional line
					(at 0 -114.3 180)
					(length 5.08)
					(name "IO_L23P_T3_18"
						(effects
							(font
								(size 1.27 1.27)
							)
						)
					)
					(number "C15"
						(effects
							(font
								(size 1.27 1.27)
							)
						)
					)
				)
				(pin bidirectional line
					(at 0 -116.84 180)
					(length 5.08)
					(name "IO_L23N_T3_18"
						(effects
							(font
								(size 1.27 1.27)
							)
						)
					)
					(number "B15"
						(effects
							(font
								(size 1.27 1.27)
							)
						)
					)
				)
				(pin bidirectional line
					(at 0 -119.38 180)
					(length 5.08)
					(name "IO_L24P_T3_18"
						(effects
							(font
								(size 1.27 1.27)
							)
						)
					)
					(number "B14"
						(effects
							(font
								(size 1.27 1.27)
							)
						)
					)
				)
				(pin bidirectional line
					(at 0 -121.92 180)
					(length 5.08)
					(name "IO_L24N_T3_18"
						(effects
							(font
								(size 1.27 1.27)
							)
						)
					)
					(number "A15"
						(effects
							(font
								(size 1.27 1.27)
							)
						)
					)
				)
				(pin bidirectional line
					(at 0 -124.46 180)
					(length 5.08)
					(name "IO_25_18"
						(effects
							(font
								(size 1.27 1.27)
							)
						)
					)
					(number "F16"
						(effects
							(font
								(size 1.27 1.27)
							)
						)
					)
				)
			)
			(symbol "XC7K410T-2FFG900I_2_5_1"
				(rectangle
					(start -40.64 -129.54)
					(end -5.08 7.62)
					(stroke
						(width 0.254)
						(type default)
					)
					(fill
						(type background)
					)
				)
				(polyline
					(pts
						(xy -30.48 1.27) (xy -38.1 1.27) (xy -38.1 -125.73) (xy -30.48 -125.73)
					)
					(stroke
						(width 0.254)
						(type default)
					)
					(fill
						(type background)
					)
				)
				(text "BANK 33"
					(at -24.13 3.81 0)
					(effects
						(font
							(size 1.27 1.27)
							(thickness 0.15)
						)
						(justify left bottom)
					)
				)
				(pin bidirectional line
					(at 0 0 180)
					(length 5.08)
					(name "IO_0_VRN_33"
						(effects
							(font
								(size 1.27 1.27)
							)
						)
					)
					(number "Y13"
						(effects
							(font
								(size 1.27 1.27)
							)
						)
					)
				)
				(pin bidirectional line
					(at 0 -2.54 180)
					(length 5.08)
					(name "IO_L1P_T0_33"
						(effects
							(font
								(size 1.27 1.27)
							)
						)
					)
					(number "AA12"
						(effects
							(font
								(size 1.27 1.27)
							)
						)
					)
				)
				(pin bidirectional line
					(at 0 -5.08 180)
					(length 5.08)
					(name "IO_L1N_T0_33"
						(effects
							(font
								(size 1.27 1.27)
							)
						)
					)
					(number "AB12"
						(effects
							(font
								(size 1.27 1.27)
							)
						)
					)
				)
				(pin bidirectional line
					(at 0 -7.62 180)
					(length 5.08)
					(name "IO_L2P_T0_33"
						(effects
							(font
								(size 1.27 1.27)
							)
						)
					)
					(number "AA8"
						(effects
							(font
								(size 1.27 1.27)
							)
						)
					)
				)
				(pin bidirectional line
					(at 0 -10.16 180)
					(length 5.08)
					(name "IO_L2N_T0_33"
						(effects
							(font
								(size 1.27 1.27)
							)
						)
					)
					(number "AB8"
						(effects
							(font
								(size 1.27 1.27)
							)
						)
					)
				)
				(pin bidirectional line
					(at 0 -12.7 180)
					(length 5.08)
					(name "IO_L3P_T0_DQS_33"
						(effects
							(font
								(size 1.27 1.27)
							)
						)
					)
					(number "AB9"
						(effects
							(font
								(size 1.27 1.27)
							)
						)
					)
				)
				(pin bidirectional line
					(at 0 -15.24 180)
					(length 5.08)
					(name "IO_L3N_T0_DQS_33"
						(effects
							(font
								(size 1.27 1.27)
							)
						)
					)
					(number "AC9"
						(effects
							(font
								(size 1.27 1.27)
							)
						)
					)
				)
				(pin bidirectional line
					(at 0 -17.78 180)
					(length 5.08)
					(name "IO_L4P_T0_33"
						(effects
							(font
								(size 1.27 1.27)
							)
						)
					)
					(number "Y11"
						(effects
							(font
								(size 1.27 1.27)
							)
						)
					)
				)
				(pin bidirectional line
					(at 0 -20.32 180)
					(length 5.08)
					(name "IO_L4N_T0_33"
						(effects
							(font
								(size 1.27 1.27)
							)
						)
					)
					(number "Y10"
						(effects
							(font
								(size 1.27 1.27)
							)
						)
					)
				)
				(pin bidirectional line
					(at 0 -22.86 180)
					(length 5.08)
					(name "IO_L5P_T0_33"
						(effects
							(font
								(size 1.27 1.27)
							)
						)
					)
					(number "AA11"
						(effects
							(font
								(size 1.27 1.27)
							)
						)
					)
				)
				(pin bidirectional line
					(at 0 -25.4 180)
					(length 5.08)
					(name "IO_L5N_T0_33"
						(effects
							(font
								(size 1.27 1.27)
							)
						)
					)
					(number "AA10"
						(effects
							(font
								(size 1.27 1.27)
							)
						)
					)
				)
				(pin bidirectional line
					(at 0 -27.94 180)
					(length 5.08)
					(name "IO_L6P_T0_33"
						(effects
							(font
								(size 1.27 1.27)
							)
						)
					)
					(number "AA13"
						(effects
							(font
								(size 1.27 1.27)
							)
						)
					)
				)
				(pin bidirectional line
					(at 0 -30.48 180)
					(length 5.08)
					(name "IO_L6N_T0_VREF_33"
						(effects
							(font
								(size 1.27 1.27)
							)
						)
					)
					(number "AB13"
						(effects
							(font
								(size 1.27 1.27)
							)
						)
					)
				)
				(pin bidirectional line
					(at 0 -33.02 180)
					(length 5.08)
					(name "IO_L7P_T1_33"
						(effects
							(font
								(size 1.27 1.27)
							)
						)
					)
					(number "AB10"
						(effects
							(font
								(size 1.27 1.27)
							)
						)
					)
				)
				(pin bidirectional line
					(at 0 -35.56 180)
					(length 5.08)
					(name "IO_L7N_T1_33"
						(effects
							(font
								(size 1.27 1.27)
							)
						)
					)
					(number "AC10"
						(effects
							(font
								(size 1.27 1.27)
							)
						)
					)
				)
				(pin bidirectional line
					(at 0 -38.1 180)
					(length 5.08)
					(name "IO_L8P_T1_33"
						(effects
							(font
								(size 1.27 1.27)
							)
						)
					)
					(number "AD8"
						(effects
							(font
								(size 1.27 1.27)
							)
						)
					)
				)
				(pin bidirectional line
					(at 0 -40.64 180)
					(length 5.08)
					(name "IO_L8N_T1_33"
						(effects
							(font
								(size 1.27 1.27)
							)
						)
					)
					(number "AE8"
						(effects
							(font
								(size 1.27 1.27)
							)
						)
					)
				)
				(pin bidirectional line
					(at 0 -43.18 180)
					(length 5.08)
					(name "IO_L9P_T1_DQS_33"
						(effects
							(font
								(size 1.27 1.27)
							)
						)
					)
					(number "AC12"
						(effects
							(font
								(size 1.27 1.27)
							)
						)
					)
				)
				(pin bidirectional line
					(at 0 -45.72 180)
					(length 5.08)
					(name "IO_L9N_T1_DQS_33"
						(effects
							(font
								(size 1.27 1.27)
							)
						)
					)
					(number "AC11"
						(effects
							(font
								(size 1.27 1.27)
							)
						)
					)
				)
				(pin bidirectional line
					(at 0 -48.26 180)
					(length 5.08)
					(name "IO_L10P_T1_33"
						(effects
							(font
								(size 1.27 1.27)
							)
						)
					)
					(number "AD9"
						(effects
							(font
								(size 1.27 1.27)
							)
						)
					)
				)
				(pin bidirectional line
					(at 0 -50.8 180)
					(length 5.08)
					(name "IO_L10N_T1_33"
						(effects
							(font
								(size 1.27 1.27)
							)
						)
					)
					(number "AE9"
						(effects
							(font
								(size 1.27 1.27)
							)
						)
					)
				)
				(pin bidirectional line
					(at 0 -53.34 180)
					(length 5.08)
					(name "IO_L11P_T1_SRCC_33"
						(effects
							(font
								(size 1.27 1.27)
							)
						)
					)
					(number "AE11"
						(effects
							(font
								(size 1.27 1.27)
							)
						)
					)
				)
				(pin bidirectional line
					(at 0 -55.88 180)
					(length 5.08)
					(name "IO_L11N_T1_SRCC_33"
						(effects
							(font
								(size 1.27 1.27)
							)
						)
					)
					(number "AF11"
						(effects
							(font
								(size 1.27 1.27)
							)
						)
					)
				)
				(pin bidirectional line
					(at 0 -58.42 180)
					(length 5.08)
					(name "IO_L12P_T1_MRCC_33"
						(effects
							(font
								(size 1.27 1.27)
							)
						)
					)
					(number "AD12"
						(effects
							(font
								(size 1.27 1.27)
							)
						)
					)
				)
				(pin bidirectional line
					(at 0 -60.96 180)
					(length 5.08)
					(name "IO_L12N_T1_MRCC_33"
						(effects
							(font
								(size 1.27 1.27)
							)
						)
					)
					(number "AD11"
						(effects
							(font
								(size 1.27 1.27)
							)
						)
					)
				)
				(pin bidirectional line
					(at 0 -63.5 180)
					(length 5.08)
					(name "IO_L13P_T2_MRCC_33"
						(effects
							(font
								(size 1.27 1.27)
							)
						)
					)
					(number "AG10"
						(effects
							(font
								(size 1.27 1.27)
							)
						)
					)
				)
				(pin bidirectional line
					(at 0 -66.04 180)
					(length 5.08)
					(name "IO_L13N_T2_MRCC_33"
						(effects
							(font
								(size 1.27 1.27)
							)
						)
					)
					(number "AH10"
						(effects
							(font
								(size 1.27 1.27)
							)
						)
					)
				)
				(pin bidirectional line
					(at 0 -68.58 180)
					(length 5.08)
					(name "IO_L14P_T2_SRCC_33"
						(effects
							(font
								(size 1.27 1.27)
							)
						)
					)
					(number "AE10"
						(effects
							(font
								(size 1.27 1.27)
							)
						)
					)
				)
				(pin bidirectional line
					(at 0 -71.12 180)
					(length 5.08)
					(name "IO_L14N_T2_SRCC_33"
						(effects
							(font
								(size 1.27 1.27)
							)
						)
					)
					(number "AF10"
						(effects
							(font
								(size 1.27 1.27)
							)
						)
					)
				)
				(pin bidirectional line
					(at 0 -73.66 180)
					(length 5.08)
					(name "IO_L15P_T2_DQS_33"
						(effects
							(font
								(size 1.27 1.27)
							)
						)
					)
					(number "AJ9"
						(effects
							(font
								(size 1.27 1.27)
							)
						)
					)
				)
				(pin bidirectional line
					(at 0 -76.2 180)
					(length 5.08)
					(name "IO_L15N_T2_DQS_33"
						(effects
							(font
								(size 1.27 1.27)
							)
						)
					)
					(number "AK9"
						(effects
							(font
								(size 1.27 1.27)
							)
						)
					)
				)
				(pin bidirectional line
					(at 0 -78.74 180)
					(length 5.08)
					(name "IO_L16P_T2_33"
						(effects
							(font
								(size 1.27 1.27)
							)
						)
					)
					(number "AG9"
						(effects
							(font
								(size 1.27 1.27)
							)
						)
					)
				)
				(pin bidirectional line
					(at 0 -81.28 180)
					(length 5.08)
					(name "IO_L16N_T2_33"
						(effects
							(font
								(size 1.27 1.27)
							)
						)
					)
					(number "AH9"
						(effects
							(font
								(size 1.27 1.27)
							)
						)
					)
				)
				(pin bidirectional line
					(at 0 -83.82 180)
					(length 5.08)
					(name "IO_L17P_T2_33"
						(effects
							(font
								(size 1.27 1.27)
							)
						)
					)
					(number "AK11"
						(effects
							(font
								(size 1.27 1.27)
							)
						)
					)
				)
				(pin bidirectional line
					(at 0 -86.36 180)
					(length 5.08)
					(name "IO_L17N_T2_33"
						(effects
							(font
								(size 1.27 1.27)
							)
						)
					)
					(number "AK10"
						(effects
							(font
								(size 1.27 1.27)
							)
						)
					)
				)
				(pin bidirectional line
					(at 0 -88.9 180)
					(length 5.08)
					(name "IO_L18P_T2_33"
						(effects
							(font
								(size 1.27 1.27)
							)
						)
					)
					(number "AH11"
						(effects
							(font
								(size 1.27 1.27)
							)
						)
					)
				)
				(pin bidirectional line
					(at 0 -91.44 180)
					(length 5.08)
					(name "IO_L18N_T2_33"
						(effects
							(font
								(size 1.27 1.27)
							)
						)
					)
					(number "AJ11"
						(effects
							(font
								(size 1.27 1.27)
							)
						)
					)
				)
				(pin bidirectional line
					(at 0 -93.98 180)
					(length 5.08)
					(name "IO_L19P_T3_33"
						(effects
							(font
								(size 1.27 1.27)
							)
						)
					)
					(number "AE13"
						(effects
							(font
								(size 1.27 1.27)
							)
						)
					)
				)
				(pin bidirectional line
					(at 0 -96.52 180)
					(length 5.08)
					(name "IO_L19N_T3_VREF_33"
						(effects
							(font
								(size 1.27 1.27)
							)
						)
					)
					(number "AF13"
						(effects
							(font
								(size 1.27 1.27)
							)
						)
					)
				)
				(pin bidirectional line
					(at 0 -99.06 180)
					(length 5.08)
					(name "IO_L20P_T3_33"
						(effects
							(font
								(size 1.27 1.27)
							)
						)
					)
					(number "AK14"
						(effects
							(font
								(size 1.27 1.27)
							)
						)
					)
				)
				(pin bidirectional line
					(at 0 -101.6 180)
					(length 5.08)
					(name "IO_L20N_T3_33"
						(effects
							(font
								(size 1.27 1.27)
							)
						)
					)
					(number "AK13"
						(effects
							(font
								(size 1.27 1.27)
							)
						)
					)
				)
				(pin bidirectional line
					(at 0 -104.14 180)
					(length 5.08)
					(name "IO_L21P_T3_DQS_33"
						(effects
							(font
								(size 1.27 1.27)
							)
						)
					)
					(number "AH14"
						(effects
							(font
								(size 1.27 1.27)
							)
						)
					)
				)
				(pin bidirectional line
					(at 0 -106.68 180)
					(length 5.08)
					(name "IO_L21N_T3_DQS_33"
						(effects
							(font
								(size 1.27 1.27)
							)
						)
					)
					(number "AJ14"
						(effects
							(font
								(size 1.27 1.27)
							)
						)
					)
				)
				(pin bidirectional line
					(at 0 -109.22 180)
					(length 5.08)
					(name "IO_L22P_T3_33"
						(effects
							(font
								(size 1.27 1.27)
							)
						)
					)
					(number "AJ13"
						(effects
							(font
								(size 1.27 1.27)
							)
						)
					)
				)
				(pin bidirectional line
					(at 0 -111.76 180)
					(length 5.08)
					(name "IO_L22N_T3_33"
						(effects
							(font
								(size 1.27 1.27)
							)
						)
					)
					(number "AJ12"
						(effects
							(font
								(size 1.27 1.27)
							)
						)
					)
				)
				(pin bidirectional line
					(at 0 -114.3 180)
					(length 5.08)
					(name "IO_L23P_T3_33"
						(effects
							(font
								(size 1.27 1.27)
							)
						)
					)
					(number "AF12"
						(effects
							(font
								(size 1.27 1.27)
							)
						)
					)
				)
				(pin bidirectional line
					(at 0 -116.84 180)
					(length 5.08)
					(name "IO_L23N_T3_33"
						(effects
							(font
								(size 1.27 1.27)
							)
						)
					)
					(number "AG12"
						(effects
							(font
								(size 1.27 1.27)
							)
						)
					)
				)
				(pin bidirectional line
					(at 0 -119.38 180)
					(length 5.08)
					(name "IO_L24P_T3_33"
						(effects
							(font
								(size 1.27 1.27)
							)
						)
					)
					(number "AG13"
						(effects
							(font
								(size 1.27 1.27)
							)
						)
					)
				)
				(pin bidirectional line
					(at 0 -121.92 180)
					(length 5.08)
					(name "IO_L24N_T3_33"
						(effects
							(font
								(size 1.27 1.27)
							)
						)
					)
					(number "AH12"
						(effects
							(font
								(size 1.27 1.27)
							)
						)
					)
				)
				(pin bidirectional line
					(at 0 -124.46 180)
					(length 5.08)
					(name "IO_25_VRP_33"
						(effects
							(font
								(size 1.27 1.27)
							)
						)
					)
					(number "AD13"
						(effects
							(font
								(size 1.27 1.27)
							)
						)
					)
				)
			)
			(symbol "XC7K410T-2FFG900I_2_6_1"
				(rectangle
					(start 5.08 7.62)
					(end 50.8 -124.46)
					(stroke
						(width 0.254)
						(type default)
					)
					(fill
						(type background)
					)
				)
				(polyline
					(pts
						(xy 16.51 2.54) (xy 24.13 2.54) (xy 24.13 -55.88) (xy 16.51 -55.88)
					)
					(stroke
						(width 0.254)
						(type default)
					)
					(fill
						(type background)
					)
				)
				(polyline
					(pts
						(xy 16.51 -63.5) (xy 24.13 -63.5) (xy 24.13 -121.92) (xy 16.51 -121.92)
					)
					(stroke
						(width 0.254)
						(type default)
					)
					(fill
						(type background)
					)
				)
				(polyline
					(pts
						(xy 39.37 2.54) (xy 31.75 2.54) (xy 31.75 -55.88) (xy 39.37 -55.88)
					)
					(stroke
						(width 0.254)
						(type default)
					)
					(fill
						(type background)
					)
				)
				(polyline
					(pts
						(xy 39.37 -63.5) (xy 31.75 -63.5) (xy 31.75 -121.92) (xy 39.37 -121.92)
					)
					(stroke
						(width 0.254)
						(type default)
					)
					(fill
						(type background)
					)
				)
				(text "GTX 115"
					(at 16.51 5.08 0)
					(effects
						(font
							(size 1.27 1.27)
							(thickness 0.15)
						)
						(justify left bottom)
					)
				)
				(text "GTX 116"
					(at 16.51 -60.96 0)
					(effects
						(font
							(size 1.27 1.27)
							(thickness 0.15)
						)
						(justify left bottom)
					)
				)
				(text "GTX 117"
					(at 39.37 5.08 0)
					(effects
						(font
							(size 1.27 1.27)
							(thickness 0.15)
						)
						(justify left bottom)
					)
				)
				(text "GTX 118"
					(at 39.37 -60.96 0)
					(effects
						(font
							(size 1.27 1.27)
							(thickness 0.15)
						)
						(justify left bottom)
					)
				)
				(pin bidirectional line
					(at 0 0 0)
					(length 5.08)
					(name "MGTXTXP0_115"
						(effects
							(font
								(size 1.27 1.27)
							)
						)
					)
					(number "Y2"
						(effects
							(font
								(size 1.27 1.27)
							)
						)
					)
				)
				(pin bidirectional line
					(at 0 -2.54 0)
					(length 5.08)
					(name "MGTXTXN0_115"
						(effects
							(font
								(size 1.27 1.27)
							)
						)
					)
					(number "Y1"
						(effects
							(font
								(size 1.27 1.27)
							)
						)
					)
				)
				(pin bidirectional line
					(at 0 -5.08 0)
					(length 5.08)
					(name "MGTXTXP1_115"
						(effects
							(font
								(size 1.27 1.27)
							)
						)
					)
					(number "V2"
						(effects
							(font
								(size 1.27 1.27)
							)
						)
					)
				)
				(pin bidirectional line
					(at 0 -7.62 0)
					(length 5.08)
					(name "MGTXTXN1_115"
						(effects
							(font
								(size 1.27 1.27)
							)
						)
					)
					(number "V1"
						(effects
							(font
								(size 1.27 1.27)
							)
						)
					)
				)
				(pin bidirectional line
					(at 0 -10.16 0)
					(length 5.08)
					(name "MGTXTXP2_115"
						(effects
							(font
								(size 1.27 1.27)
							)
						)
					)
					(number "U4"
						(effects
							(font
								(size 1.27 1.27)
							)
						)
					)
				)
				(pin bidirectional line
					(at 0 -12.7 0)
					(length 5.08)
					(name "MGTXTXN2_115"
						(effects
							(font
								(size 1.27 1.27)
							)
						)
					)
					(number "U3"
						(effects
							(font
								(size 1.27 1.27)
							)
						)
					)
				)
				(pin bidirectional line
					(at 0 -15.24 0)
					(length 5.08)
					(name "MGTXTXP3_115"
						(effects
							(font
								(size 1.27 1.27)
							)
						)
					)
					(number "T2"
						(effects
							(font
								(size 1.27 1.27)
							)
						)
					)
				)
				(pin bidirectional line
					(at 0 -17.78 0)
					(length 5.08)
					(name "MGTXTXN3_115"
						(effects
							(font
								(size 1.27 1.27)
							)
						)
					)
					(number "T1"
						(effects
							(font
								(size 1.27 1.27)
							)
						)
					)
				)
				(pin bidirectional line
					(at 0 -22.86 0)
					(length 5.08)
					(name "MGTXRXP0_115"
						(effects
							(font
								(size 1.27 1.27)
							)
						)
					)
					(number "AA4"
						(effects
							(font
								(size 1.27 1.27)
							)
						)
					)
				)
				(pin bidirectional line
					(at 0 -25.4 0)
					(length 5.08)
					(name "MGTXRXN0_115"
						(effects
							(font
								(size 1.27 1.27)
							)
						)
					)
					(number "AA3"
						(effects
							(font
								(size 1.27 1.27)
							)
						)
					)
				)
				(pin bidirectional line
					(at 0 -27.94 0)
					(length 5.08)
					(name "MGTXRXP1_115"
						(effects
							(font
								(size 1.27 1.27)
							)
						)
					)
					(number "Y6"
						(effects
							(font
								(size 1.27 1.27)
							)
						)
					)
				)
				(pin bidirectional line
					(at 0 -30.48 0)
					(length 5.08)
					(name "MGTXRXN1_115"
						(effects
							(font
								(size 1.27 1.27)
							)
						)
					)
					(number "Y5"
						(effects
							(font
								(size 1.27 1.27)
							)
						)
					)
				)
				(pin bidirectional line
					(at 0 -33.02 0)
					(length 5.08)
					(name "MGTXRXP2_115"
						(effects
							(font
								(size 1.27 1.27)
							)
						)
					)
					(number "W4"
						(effects
							(font
								(size 1.27 1.27)
							)
						)
					)
				)
				(pin bidirectional line
					(at 0 -35.56 0)
					(length 5.08)
					(name "MGTXRXN2_115"
						(effects
							(font
								(size 1.27 1.27)
							)
						)
					)
					(number "W3"
						(effects
							(font
								(size 1.27 1.27)
							)
						)
					)
				)
				(pin bidirectional line
					(at 0 -38.1 0)
					(length 5.08)
					(name "MGTXRXP3_115"
						(effects
							(font
								(size 1.27 1.27)
							)
						)
					)
					(number "V6"
						(effects
							(font
								(size 1.27 1.27)
							)
						)
					)
				)
				(pin bidirectional line
					(at 0 -40.64 0)
					(length 5.08)
					(name "MGTXRXN3_115"
						(effects
							(font
								(size 1.27 1.27)
							)
						)
					)
					(number "V5"
						(effects
							(font
								(size 1.27 1.27)
							)
						)
					)
				)
				(pin bidirectional line
					(at 0 -45.72 0)
					(length 5.08)
					(name "MGTREFCLK0P_115"
						(effects
							(font
								(size 1.27 1.27)
							)
						)
					)
					(number "R8"
						(effects
							(font
								(size 1.27 1.27)
							)
						)
					)
				)
				(pin bidirectional line
					(at 0 -48.26 0)
					(length 5.08)
					(name "MGTREFCLK0N_115"
						(effects
							(font
								(size 1.27 1.27)
							)
						)
					)
					(number "R7"
						(effects
							(font
								(size 1.27 1.27)
							)
						)
					)
				)
				(pin bidirectional line
					(at 0 -50.8 0)
					(length 5.08)
					(name "MGTREFCLK1P_115"
						(effects
							(font
								(size 1.27 1.27)
							)
						)
					)
					(number "U8"
						(effects
							(font
								(size 1.27 1.27)
							)
						)
					)
				)
				(pin bidirectional line
					(at 0 -53.34 0)
					(length 5.08)
					(name "MGTREFCLK1N_115"
						(effects
							(font
								(size 1.27 1.27)
							)
						)
					)
					(number "U7"
						(effects
							(font
								(size 1.27 1.27)
							)
						)
					)
				)
				(pin bidirectional line
					(at 0 -66.04 0)
					(length 5.08)
					(name "MGTXTXP0_116"
						(effects
							(font
								(size 1.27 1.27)
							)
						)
					)
					(number "P2"
						(effects
							(font
								(size 1.27 1.27)
							)
						)
					)
				)
				(pin bidirectional line
					(at 0 -68.58 0)
					(length 5.08)
					(name "MGTXTXN0_116"
						(effects
							(font
								(size 1.27 1.27)
							)
						)
					)
					(number "P1"
						(effects
							(font
								(size 1.27 1.27)
							)
						)
					)
				)
				(pin bidirectional line
					(at 0 -71.12 0)
					(length 5.08)
					(name "MGTXTXP1_116"
						(effects
							(font
								(size 1.27 1.27)
							)
						)
					)
					(number "N4"
						(effects
							(font
								(size 1.27 1.27)
							)
						)
					)
				)
				(pin bidirectional line
					(at 0 -73.66 0)
					(length 5.08)
					(name "MGTXTXN1_116"
						(effects
							(font
								(size 1.27 1.27)
							)
						)
					)
					(number "N3"
						(effects
							(font
								(size 1.27 1.27)
							)
						)
					)
				)
				(pin bidirectional line
					(at 0 -76.2 0)
					(length 5.08)
					(name "MGTXTXP2_116"
						(effects
							(font
								(size 1.27 1.27)
							)
						)
					)
					(number "M2"
						(effects
							(font
								(size 1.27 1.27)
							)
						)
					)
				)
				(pin bidirectional line
					(at 0 -78.74 0)
					(length 5.08)
					(name "MGTXTXN2_116"
						(effects
							(font
								(size 1.27 1.27)
							)
						)
					)
					(number "M1"
						(effects
							(font
								(size 1.27 1.27)
							)
						)
					)
				)
				(pin bidirectional line
					(at 0 -81.28 0)
					(length 5.08)
					(name "MGTXTXP3_116"
						(effects
							(font
								(size 1.27 1.27)
							)
						)
					)
					(number "L4"
						(effects
							(font
								(size 1.27 1.27)
							)
						)
					)
				)
				(pin bidirectional line
					(at 0 -83.82 0)
					(length 5.08)
					(name "MGTXTXN3_116"
						(effects
							(font
								(size 1.27 1.27)
							)
						)
					)
					(number "L3"
						(effects
							(font
								(size 1.27 1.27)
							)
						)
					)
				)
				(pin bidirectional line
					(at 0 -88.9 0)
					(length 5.08)
					(name "MGTXRXP0_116"
						(effects
							(font
								(size 1.27 1.27)
							)
						)
					)
					(number "T6"
						(effects
							(font
								(size 1.27 1.27)
							)
						)
					)
				)
				(pin bidirectional line
					(at 0 -91.44 0)
					(length 5.08)
					(name "MGTXRXN0_116"
						(effects
							(font
								(size 1.27 1.27)
							)
						)
					)
					(number "T5"
						(effects
							(font
								(size 1.27 1.27)
							)
						)
					)
				)
				(pin bidirectional line
					(at 0 -93.98 0)
					(length 5.08)
					(name "MGTXRXP1_116"
						(effects
							(font
								(size 1.27 1.27)
							)
						)
					)
					(number "R4"
						(effects
							(font
								(size 1.27 1.27)
							)
						)
					)
				)
				(pin bidirectional line
					(at 0 -96.52 0)
					(length 5.08)
					(name "MGTXRXN1_116"
						(effects
							(font
								(size 1.27 1.27)
							)
						)
					)
					(number "R3"
						(effects
							(font
								(size 1.27 1.27)
							)
						)
					)
				)
				(pin bidirectional line
					(at 0 -99.06 0)
					(length 5.08)
					(name "MGTXRXP2_116"
						(effects
							(font
								(size 1.27 1.27)
							)
						)
					)
					(number "P6"
						(effects
							(font
								(size 1.27 1.27)
							)
						)
					)
				)
				(pin bidirectional line
					(at 0 -101.6 0)
					(length 5.08)
					(name "MGTXRXN2_116"
						(effects
							(font
								(size 1.27 1.27)
							)
						)
					)
					(number "P5"
						(effects
							(font
								(size 1.27 1.27)
							)
						)
					)
				)
				(pin bidirectional line
					(at 0 -104.14 0)
					(length 5.08)
					(name "MGTXRXP3_116"
						(effects
							(font
								(size 1.27 1.27)
							)
						)
					)
					(number "M6"
						(effects
							(font
								(size 1.27 1.27)
							)
						)
					)
				)
				(pin bidirectional line
					(at 0 -106.68 0)
					(length 5.08)
					(name "MGTXRXN3_116"
						(effects
							(font
								(size 1.27 1.27)
							)
						)
					)
					(number "M5"
						(effects
							(font
								(size 1.27 1.27)
							)
						)
					)
				)
				(pin bidirectional line
					(at 0 -111.76 0)
					(length 5.08)
					(name "MGTREFCLK0P_116"
						(effects
							(font
								(size 1.27 1.27)
							)
						)
					)
					(number "L8"
						(effects
							(font
								(size 1.27 1.27)
							)
						)
					)
				)
				(pin bidirectional line
					(at 0 -114.3 0)
					(length 5.08)
					(name "MGTREFCLK0N_116"
						(effects
							(font
								(size 1.27 1.27)
							)
						)
					)
					(number "L7"
						(effects
							(font
								(size 1.27 1.27)
							)
						)
					)
				)
				(pin bidirectional line
					(at 0 -116.84 0)
					(length 5.08)
					(name "MGTREFCLK1P_116"
						(effects
							(font
								(size 1.27 1.27)
							)
						)
					)
					(number "N8"
						(effects
							(font
								(size 1.27 1.27)
							)
						)
					)
				)
				(pin bidirectional line
					(at 0 -119.38 0)
					(length 5.08)
					(name "MGTREFCLK1N_116"
						(effects
							(font
								(size 1.27 1.27)
							)
						)
					)
					(number "N7"
						(effects
							(font
								(size 1.27 1.27)
							)
						)
					)
				)
				(pin bidirectional line
					(at 55.88 0 180)
					(length 5.08)
					(name "MGTXTXP0_117"
						(effects
							(font
								(size 1.27 1.27)
							)
						)
					)
					(number "K2"
						(effects
							(font
								(size 1.27 1.27)
							)
						)
					)
				)
				(pin bidirectional line
					(at 55.88 -2.54 180)
					(length 5.08)
					(name "MGTXTXN0_117"
						(effects
							(font
								(size 1.27 1.27)
							)
						)
					)
					(number "K1"
						(effects
							(font
								(size 1.27 1.27)
							)
						)
					)
				)
				(pin bidirectional line
					(at 55.88 -5.08 180)
					(length 5.08)
					(name "MGTXTXP1_117"
						(effects
							(font
								(size 1.27 1.27)
							)
						)
					)
					(number "J4"
						(effects
							(font
								(size 1.27 1.27)
							)
						)
					)
				)
				(pin bidirectional line
					(at 55.88 -7.62 180)
					(length 5.08)
					(name "MGTXTXN1_117"
						(effects
							(font
								(size 1.27 1.27)
							)
						)
					)
					(number "J3"
						(effects
							(font
								(size 1.27 1.27)
							)
						)
					)
				)
				(pin bidirectional line
					(at 55.88 -10.16 180)
					(length 5.08)
					(name "MGTXTXP2_117"
						(effects
							(font
								(size 1.27 1.27)
							)
						)
					)
					(number "H2"
						(effects
							(font
								(size 1.27 1.27)
							)
						)
					)
				)
				(pin bidirectional line
					(at 55.88 -12.7 180)
					(length 5.08)
					(name "MGTXTXN2_117"
						(effects
							(font
								(size 1.27 1.27)
							)
						)
					)
					(number "H1"
						(effects
							(font
								(size 1.27 1.27)
							)
						)
					)
				)
				(pin bidirectional line
					(at 55.88 -15.24 180)
					(length 5.08)
					(name "MGTXTXP3_117"
						(effects
							(font
								(size 1.27 1.27)
							)
						)
					)
					(number "F2"
						(effects
							(font
								(size 1.27 1.27)
							)
						)
					)
				)
				(pin bidirectional line
					(at 55.88 -17.78 180)
					(length 5.08)
					(name "MGTXTXN3_117"
						(effects
							(font
								(size 1.27 1.27)
							)
						)
					)
					(number "F1"
						(effects
							(font
								(size 1.27 1.27)
							)
						)
					)
				)
				(pin bidirectional line
					(at 55.88 -22.86 180)
					(length 5.08)
					(name "MGTXRXP0_117"
						(effects
							(font
								(size 1.27 1.27)
							)
						)
					)
					(number "K6"
						(effects
							(font
								(size 1.27 1.27)
							)
						)
					)
				)
				(pin bidirectional line
					(at 55.88 -25.4 180)
					(length 5.08)
					(name "MGTXRXN0_117"
						(effects
							(font
								(size 1.27 1.27)
							)
						)
					)
					(number "K5"
						(effects
							(font
								(size 1.27 1.27)
							)
						)
					)
				)
				(pin bidirectional line
					(at 55.88 -27.94 180)
					(length 5.08)
					(name "MGTXRXP1_117"
						(effects
							(font
								(size 1.27 1.27)
							)
						)
					)
					(number "H6"
						(effects
							(font
								(size 1.27 1.27)
							)
						)
					)
				)
				(pin bidirectional line
					(at 55.88 -30.48 180)
					(length 5.08)
					(name "MGTXRXN1_117"
						(effects
							(font
								(size 1.27 1.27)
							)
						)
					)
					(number "H5"
						(effects
							(font
								(size 1.27 1.27)
							)
						)
					)
				)
				(pin bidirectional line
					(at 55.88 -33.02 180)
					(length 5.08)
					(name "MGTXRXP2_117"
						(effects
							(font
								(size 1.27 1.27)
							)
						)
					)
					(number "G4"
						(effects
							(font
								(size 1.27 1.27)
							)
						)
					)
				)
				(pin bidirectional line
					(at 55.88 -35.56 180)
					(length 5.08)
					(name "MGTXRXN2_117"
						(effects
							(font
								(size 1.27 1.27)
							)
						)
					)
					(number "G3"
						(effects
							(font
								(size 1.27 1.27)
							)
						)
					)
				)
				(pin bidirectional line
					(at 55.88 -38.1 180)
					(length 5.08)
					(name "MGTXRXP3_117"
						(effects
							(font
								(size 1.27 1.27)
							)
						)
					)
					(number "F6"
						(effects
							(font
								(size 1.27 1.27)
							)
						)
					)
				)
				(pin bidirectional line
					(at 55.88 -40.64 180)
					(length 5.08)
					(name "MGTXRXN3_117"
						(effects
							(font
								(size 1.27 1.27)
							)
						)
					)
					(number "F5"
						(effects
							(font
								(size 1.27 1.27)
							)
						)
					)
				)
				(pin bidirectional line
					(at 55.88 -45.72 180)
					(length 5.08)
					(name "MGTREFCLK0P_117"
						(effects
							(font
								(size 1.27 1.27)
							)
						)
					)
					(number "G8"
						(effects
							(font
								(size 1.27 1.27)
							)
						)
					)
				)
				(pin bidirectional line
					(at 55.88 -48.26 180)
					(length 5.08)
					(name "MGTREFCLK0N_117"
						(effects
							(font
								(size 1.27 1.27)
							)
						)
					)
					(number "G7"
						(effects
							(font
								(size 1.27 1.27)
							)
						)
					)
				)
				(pin bidirectional line
					(at 55.88 -50.8 180)
					(length 5.08)
					(name "MGTREFCLK1P_117"
						(effects
							(font
								(size 1.27 1.27)
							)
						)
					)
					(number "J8"
						(effects
							(font
								(size 1.27 1.27)
							)
						)
					)
				)
				(pin bidirectional line
					(at 55.88 -53.34 180)
					(length 5.08)
					(name "MGTREFCLK1N_117"
						(effects
							(font
								(size 1.27 1.27)
							)
						)
					)
					(number "J7"
						(effects
							(font
								(size 1.27 1.27)
							)
						)
					)
				)
				(pin bidirectional line
					(at 55.88 -66.04 180)
					(length 5.08)
					(name "MGTXTXP0_118"
						(effects
							(font
								(size 1.27 1.27)
							)
						)
					)
					(number "D2"
						(effects
							(font
								(size 1.27 1.27)
							)
						)
					)
				)
				(pin bidirectional line
					(at 55.88 -68.58 180)
					(length 5.08)
					(name "MGTXTXN0_118"
						(effects
							(font
								(size 1.27 1.27)
							)
						)
					)
					(number "D1"
						(effects
							(font
								(size 1.27 1.27)
							)
						)
					)
				)
				(pin bidirectional line
					(at 55.88 -71.12 180)
					(length 5.08)
					(name "MGTXTXP1_118"
						(effects
							(font
								(size 1.27 1.27)
							)
						)
					)
					(number "C4"
						(effects
							(font
								(size 1.27 1.27)
							)
						)
					)
				)
				(pin bidirectional line
					(at 55.88 -73.66 180)
					(length 5.08)
					(name "MGTXTXN1_118"
						(effects
							(font
								(size 1.27 1.27)
							)
						)
					)
					(number "C3"
						(effects
							(font
								(size 1.27 1.27)
							)
						)
					)
				)
				(pin bidirectional line
					(at 55.88 -76.2 180)
					(length 5.08)
					(name "MGTXTXP2_118"
						(effects
							(font
								(size 1.27 1.27)
							)
						)
					)
					(number "B2"
						(effects
							(font
								(size 1.27 1.27)
							)
						)
					)
				)
				(pin bidirectional line
					(at 55.88 -78.74 180)
					(length 5.08)
					(name "MGTXTXN2_118"
						(effects
							(font
								(size 1.27 1.27)
							)
						)
					)
					(number "B1"
						(effects
							(font
								(size 1.27 1.27)
							)
						)
					)
				)
				(pin bidirectional line
					(at 55.88 -81.28 180)
					(length 5.08)
					(name "MGTXTXP3_118"
						(effects
							(font
								(size 1.27 1.27)
							)
						)
					)
					(number "A4"
						(effects
							(font
								(size 1.27 1.27)
							)
						)
					)
				)
				(pin bidirectional line
					(at 55.88 -83.82 180)
					(length 5.08)
					(name "MGTXTXN3_118"
						(effects
							(font
								(size 1.27 1.27)
							)
						)
					)
					(number "A3"
						(effects
							(font
								(size 1.27 1.27)
							)
						)
					)
				)
				(pin bidirectional line
					(at 55.88 -88.9 180)
					(length 5.08)
					(name "MGTXRXP0_118"
						(effects
							(font
								(size 1.27 1.27)
							)
						)
					)
					(number "E4"
						(effects
							(font
								(size 1.27 1.27)
							)
						)
					)
				)
				(pin bidirectional line
					(at 55.88 -91.44 180)
					(length 5.08)
					(name "MGTXRXN0_118"
						(effects
							(font
								(size 1.27 1.27)
							)
						)
					)
					(number "E3"
						(effects
							(font
								(size 1.27 1.27)
							)
						)
					)
				)
				(pin bidirectional line
					(at 55.88 -93.98 180)
					(length 5.08)
					(name "MGTXRXP1_118"
						(effects
							(font
								(size 1.27 1.27)
							)
						)
					)
					(number "D6"
						(effects
							(font
								(size 1.27 1.27)
							)
						)
					)
				)
				(pin bidirectional line
					(at 55.88 -96.52 180)
					(length 5.08)
					(name "MGTXRXN1_118"
						(effects
							(font
								(size 1.27 1.27)
							)
						)
					)
					(number "D5"
						(effects
							(font
								(size 1.27 1.27)
							)
						)
					)
				)
				(pin bidirectional line
					(at 55.88 -99.06 180)
					(length 5.08)
					(name "MGTXRXP2_118"
						(effects
							(font
								(size 1.27 1.27)
							)
						)
					)
					(number "B6"
						(effects
							(font
								(size 1.27 1.27)
							)
						)
					)
				)
				(pin bidirectional line
					(at 55.88 -101.6 180)
					(length 5.08)
					(name "MGTXRXN2_118"
						(effects
							(font
								(size 1.27 1.27)
							)
						)
					)
					(number "B5"
						(effects
							(font
								(size 1.27 1.27)
							)
						)
					)
				)
				(pin bidirectional line
					(at 55.88 -104.14 180)
					(length 5.08)
					(name "MGTXRXP3_118"
						(effects
							(font
								(size 1.27 1.27)
							)
						)
					)
					(number "A8"
						(effects
							(font
								(size 1.27 1.27)
							)
						)
					)
				)
				(pin bidirectional line
					(at 55.88 -106.68 180)
					(length 5.08)
					(name "MGTXRXN3_118"
						(effects
							(font
								(size 1.27 1.27)
							)
						)
					)
					(number "A7"
						(effects
							(font
								(size 1.27 1.27)
							)
						)
					)
				)
				(pin bidirectional line
					(at 55.88 -111.76 180)
					(length 5.08)
					(name "MGTREFCLK0P_118"
						(effects
							(font
								(size 1.27 1.27)
							)
						)
					)
					(number "C8"
						(effects
							(font
								(size 1.27 1.27)
							)
						)
					)
				)
				(pin bidirectional line
					(at 55.88 -114.3 180)
					(length 5.08)
					(name "MGTREFCLK0N_118"
						(effects
							(font
								(size 1.27 1.27)
							)
						)
					)
					(number "C7"
						(effects
							(font
								(size 1.27 1.27)
							)
						)
					)
				)
				(pin bidirectional line
					(at 55.88 -116.84 180)
					(length 5.08)
					(name "MGTREFCLK1P_118"
						(effects
							(font
								(size 1.27 1.27)
							)
						)
					)
					(number "E8"
						(effects
							(font
								(size 1.27 1.27)
							)
						)
					)
				)
				(pin bidirectional line
					(at 55.88 -119.38 180)
					(length 5.08)
					(name "MGTREFCLK1N_118"
						(effects
							(font
								(size 1.27 1.27)
							)
						)
					)
					(number "E7"
						(effects
							(font
								(size 1.27 1.27)
							)
						)
					)
				)
			)
			(symbol "XC7K410T-2FFG900I_2_7_1"
				(rectangle
					(start 5.08 2.54)
					(end 35.56 -30.48)
					(stroke
						(width 0.254)
						(type default)
					)
					(fill
						(type background)
					)
				)
				(pin bidirectional line
					(at 0 0 0)
					(length 5.08)
					(name "MGTAVCC"
						(effects
							(font
								(size 1.27 1.27)
							)
						)
					)
					(number "B7"
						(effects
							(font
								(size 1.27 1.27)
							)
						)
					)
				)
				(pin passive line
					(at 0 0 0)
					(length 5.08)
					(hide yes)
					(name "MGTAVCC"
						(effects
							(font
								(size 1.27 1.27)
							)
						)
					)
					(number "D7"
						(effects
							(font
								(size 1.27 1.27)
							)
						)
					)
				)
				(pin passive line
					(at 0 0 0)
					(length 5.08)
					(hide yes)
					(name "MGTAVCC"
						(effects
							(font
								(size 1.27 1.27)
							)
						)
					)
					(number "F7"
						(effects
							(font
								(size 1.27 1.27)
							)
						)
					)
				)
				(pin passive line
					(at 0 0 0)
					(length 5.08)
					(hide yes)
					(name "MGTAVCC"
						(effects
							(font
								(size 1.27 1.27)
							)
						)
					)
					(number "H7"
						(effects
							(font
								(size 1.27 1.27)
							)
						)
					)
				)
				(pin passive line
					(at 0 0 0)
					(length 5.08)
					(hide yes)
					(name "MGTAVCC"
						(effects
							(font
								(size 1.27 1.27)
							)
						)
					)
					(number "K7"
						(effects
							(font
								(size 1.27 1.27)
							)
						)
					)
				)
				(pin passive line
					(at 0 0 0)
					(length 5.08)
					(hide yes)
					(name "MGTAVCC"
						(effects
							(font
								(size 1.27 1.27)
							)
						)
					)
					(number "M7"
						(effects
							(font
								(size 1.27 1.27)
							)
						)
					)
				)
				(pin passive line
					(at 0 0 0)
					(length 5.08)
					(hide yes)
					(name "MGTAVCC"
						(effects
							(font
								(size 1.27 1.27)
							)
						)
					)
					(number "P7"
						(effects
							(font
								(size 1.27 1.27)
							)
						)
					)
				)
				(pin bidirectional line
					(at 0 -17.78 0)
					(length 5.08)
					(name "MGTAVTT"
						(effects
							(font
								(size 1.27 1.27)
							)
						)
					)
					(number "B3"
						(effects
							(font
								(size 1.27 1.27)
							)
						)
					)
				)
				(pin passive line
					(at 0 -17.78 0)
					(length 5.08)
					(hide yes)
					(name "MGTAVTT"
						(effects
							(font
								(size 1.27 1.27)
							)
						)
					)
					(number "C5"
						(effects
							(font
								(size 1.27 1.27)
							)
						)
					)
				)
				(pin passive line
					(at 0 -17.78 0)
					(length 5.08)
					(hide yes)
					(name "MGTAVTT"
						(effects
							(font
								(size 1.27 1.27)
							)
						)
					)
					(number "D3"
						(effects
							(font
								(size 1.27 1.27)
							)
						)
					)
				)
				(pin passive line
					(at 0 -17.78 0)
					(length 5.08)
					(hide yes)
					(name "MGTAVTT"
						(effects
							(font
								(size 1.27 1.27)
							)
						)
					)
					(number "E5"
						(effects
							(font
								(size 1.27 1.27)
							)
						)
					)
				)
				(pin passive line
					(at 0 -17.78 0)
					(length 5.08)
					(hide yes)
					(name "MGTAVTT"
						(effects
							(font
								(size 1.27 1.27)
							)
						)
					)
					(number "F3"
						(effects
							(font
								(size 1.27 1.27)
							)
						)
					)
				)
				(pin passive line
					(at 0 -17.78 0)
					(length 5.08)
					(hide yes)
					(name "MGTAVTT"
						(effects
							(font
								(size 1.27 1.27)
							)
						)
					)
					(number "G5"
						(effects
							(font
								(size 1.27 1.27)
							)
						)
					)
				)
				(pin passive line
					(at 0 -17.78 0)
					(length 5.08)
					(hide yes)
					(name "MGTAVTT"
						(effects
							(font
								(size 1.27 1.27)
							)
						)
					)
					(number "H3"
						(effects
							(font
								(size 1.27 1.27)
							)
						)
					)
				)
				(pin passive line
					(at 0 -17.78 0)
					(length 5.08)
					(hide yes)
					(name "MGTAVTT"
						(effects
							(font
								(size 1.27 1.27)
							)
						)
					)
					(number "J5"
						(effects
							(font
								(size 1.27 1.27)
							)
						)
					)
				)
				(pin passive line
					(at 0 -17.78 0)
					(length 5.08)
					(hide yes)
					(name "MGTAVTT"
						(effects
							(font
								(size 1.27 1.27)
							)
						)
					)
					(number "K3"
						(effects
							(font
								(size 1.27 1.27)
							)
						)
					)
				)
				(pin passive line
					(at 0 -17.78 0)
					(length 5.08)
					(hide yes)
					(name "MGTAVTT"
						(effects
							(font
								(size 1.27 1.27)
							)
						)
					)
					(number "L5"
						(effects
							(font
								(size 1.27 1.27)
							)
						)
					)
				)
				(pin passive line
					(at 0 -17.78 0)
					(length 5.08)
					(hide yes)
					(name "MGTAVTT"
						(effects
							(font
								(size 1.27 1.27)
							)
						)
					)
					(number "M3"
						(effects
							(font
								(size 1.27 1.27)
							)
						)
					)
				)
				(pin passive line
					(at 0 -17.78 0)
					(length 5.08)
					(hide yes)
					(name "MGTAVTT"
						(effects
							(font
								(size 1.27 1.27)
							)
						)
					)
					(number "N5"
						(effects
							(font
								(size 1.27 1.27)
							)
						)
					)
				)
				(pin passive line
					(at 0 -17.78 0)
					(length 5.08)
					(hide yes)
					(name "MGTAVTT"
						(effects
							(font
								(size 1.27 1.27)
							)
						)
					)
					(number "P3"
						(effects
							(font
								(size 1.27 1.27)
							)
						)
					)
				)
				(pin passive line
					(at 0 -17.78 0)
					(length 5.08)
					(hide yes)
					(name "MGTAVTT"
						(effects
							(font
								(size 1.27 1.27)
							)
						)
					)
					(number "R5"
						(effects
							(font
								(size 1.27 1.27)
							)
						)
					)
				)
				(pin passive line
					(at 0 -17.78 0)
					(length 5.08)
					(hide yes)
					(name "MGTAVTT"
						(effects
							(font
								(size 1.27 1.27)
							)
						)
					)
					(number "T3"
						(effects
							(font
								(size 1.27 1.27)
							)
						)
					)
				)
				(pin passive line
					(at 0 -17.78 0)
					(length 5.08)
					(hide yes)
					(name "MGTAVTT"
						(effects
							(font
								(size 1.27 1.27)
							)
						)
					)
					(number "U5"
						(effects
							(font
								(size 1.27 1.27)
							)
						)
					)
				)
				(pin passive line
					(at 0 -17.78 0)
					(length 5.08)
					(hide yes)
					(name "MGTAVTT"
						(effects
							(font
								(size 1.27 1.27)
							)
						)
					)
					(number "V3"
						(effects
							(font
								(size 1.27 1.27)
							)
						)
					)
				)
				(pin passive line
					(at 0 -17.78 0)
					(length 5.08)
					(hide yes)
					(name "MGTAVTT"
						(effects
							(font
								(size 1.27 1.27)
							)
						)
					)
					(number "W5"
						(effects
							(font
								(size 1.27 1.27)
							)
						)
					)
				)
				(pin bidirectional line
					(at 40.64 0 180)
					(length 5.08)
					(name "MGTVCCAUX"
						(effects
							(font
								(size 1.27 1.27)
							)
						)
					)
					(number "T7"
						(effects
							(font
								(size 1.27 1.27)
							)
						)
					)
				)
				(pin passive line
					(at 40.64 0 180)
					(length 5.08)
					(hide yes)
					(name "MGTVCCAUX"
						(effects
							(font
								(size 1.27 1.27)
							)
						)
					)
					(number "V7"
						(effects
							(font
								(size 1.27 1.27)
							)
						)
					)
				)
				(pin bidirectional line
					(at 40.64 -17.78 180)
					(length 5.08)
					(name "MGTAVTTRCAL_115"
						(effects
							(font
								(size 1.27 1.27)
							)
						)
					)
					(number "W7"
						(effects
							(font
								(size 1.27 1.27)
							)
						)
					)
				)
				(pin bidirectional line
					(at 40.64 -27.94 180)
					(length 5.08)
					(name "MGTRREF_115"
						(effects
							(font
								(size 1.27 1.27)
							)
						)
					)
					(number "W8"
						(effects
							(font
								(size 1.27 1.27)
							)
						)
					)
				)
			)
			(symbol "XC7K410T-2FFG900I_2_8_1"
				(rectangle
					(start 5.08 3.81)
					(end 25.4 -38.1)
					(stroke
						(width 0.254)
						(type default)
					)
					(fill
						(type background)
					)
				)
				(pin bidirectional line
					(at 0 0 0)
					(length 5.08)
					(name "CCLK_0"
						(effects
							(font
								(size 1.27 1.27)
							)
						)
					)
					(number "B10"
						(effects
							(font
								(size 1.27 1.27)
							)
						)
					)
				)
				(pin bidirectional line
					(at 0 -2.54 0)
					(length 5.08)
					(name "M0_0"
						(effects
							(font
								(size 1.27 1.27)
							)
						)
					)
					(number "AB5"
						(effects
							(font
								(size 1.27 1.27)
							)
						)
					)
				)
				(pin bidirectional line
					(at 0 -5.08 0)
					(length 5.08)
					(name "M1_0"
						(effects
							(font
								(size 1.27 1.27)
							)
						)
					)
					(number "AB2"
						(effects
							(font
								(size 1.27 1.27)
							)
						)
					)
				)
				(pin bidirectional line
					(at 0 -7.62 0)
					(length 5.08)
					(name "M2_0"
						(effects
							(font
								(size 1.27 1.27)
							)
						)
					)
					(number "AB1"
						(effects
							(font
								(size 1.27 1.27)
							)
						)
					)
				)
				(pin bidirectional line
					(at 0 -27.94 0)
					(length 5.08)
					(name "TDI_0"
						(effects
							(font
								(size 1.27 1.27)
							)
						)
					)
					(number "H10"
						(effects
							(font
								(size 1.27 1.27)
							)
						)
					)
				)
				(pin bidirectional line
					(at 0 -30.48 0)
					(length 5.08)
					(name "TDO_0"
						(effects
							(font
								(size 1.27 1.27)
							)
						)
					)
					(number "G10"
						(effects
							(font
								(size 1.27 1.27)
							)
						)
					)
				)
				(pin bidirectional line
					(at 0 -33.02 0)
					(length 5.08)
					(name "TMS_0"
						(effects
							(font
								(size 1.27 1.27)
							)
						)
					)
					(number "F10"
						(effects
							(font
								(size 1.27 1.27)
							)
						)
					)
				)
				(pin bidirectional line
					(at 0 -35.56 0)
					(length 5.08)
					(name "TCK_0"
						(effects
							(font
								(size 1.27 1.27)
							)
						)
					)
					(number "E10"
						(effects
							(font
								(size 1.27 1.27)
							)
						)
					)
				)
				(pin bidirectional line
					(at 30.48 0 180)
					(length 5.08)
					(name "DONE_0"
						(effects
							(font
								(size 1.27 1.27)
							)
						)
					)
					(number "M10"
						(effects
							(font
								(size 1.27 1.27)
							)
						)
					)
				)
				(pin bidirectional line
					(at 30.48 -2.54 180)
					(length 5.08)
					(name "INIT_B_0"
						(effects
							(font
								(size 1.27 1.27)
							)
						)
					)
					(number "A10"
						(effects
							(font
								(size 1.27 1.27)
							)
						)
					)
				)
				(pin bidirectional line
					(at 30.48 -5.08 180)
					(length 5.08)
					(name "PROGRAM_B_0"
						(effects
							(font
								(size 1.27 1.27)
							)
						)
					)
					(number "K10"
						(effects
							(font
								(size 1.27 1.27)
							)
						)
					)
				)
				(pin bidirectional line
					(at 30.48 -12.7 180)
					(length 5.08)
					(name "CFGBVS_0"
						(effects
							(font
								(size 1.27 1.27)
							)
						)
					)
					(number "L10"
						(effects
							(font
								(size 1.27 1.27)
							)
						)
					)
				)
				(pin bidirectional line
					(at 30.48 -17.78 180)
					(length 5.08)
					(name "VP_0"
						(effects
							(font
								(size 1.27 1.27)
							)
						)
					)
					(number "R15"
						(effects
							(font
								(size 1.27 1.27)
							)
						)
					)
				)
				(pin bidirectional line
					(at 30.48 -20.32 180)
					(length 5.08)
					(name "VN_0"
						(effects
							(font
								(size 1.27 1.27)
							)
						)
					)
					(number "T14"
						(effects
							(font
								(size 1.27 1.27)
							)
						)
					)
				)
				(pin bidirectional line
					(at 30.48 -25.4 180)
					(length 5.08)
					(name "VREFP_0"
						(effects
							(font
								(size 1.27 1.27)
							)
						)
					)
					(number "T15"
						(effects
							(font
								(size 1.27 1.27)
							)
						)
					)
				)
				(pin bidirectional line
					(at 30.48 -27.94 180)
					(length 5.08)
					(name "VREFN_0"
						(effects
							(font
								(size 1.27 1.27)
							)
						)
					)
					(number "R14"
						(effects
							(font
								(size 1.27 1.27)
							)
						)
					)
				)
				(pin bidirectional line
					(at 30.48 -33.02 180)
					(length 5.08)
					(name "DXP_0"
						(effects
							(font
								(size 1.27 1.27)
							)
						)
					)
					(number "U15"
						(effects
							(font
								(size 1.27 1.27)
							)
						)
					)
				)
				(pin bidirectional line
					(at 30.48 -35.56 180)
					(length 5.08)
					(name "DXN_0"
						(effects
							(font
								(size 1.27 1.27)
							)
						)
					)
					(number "U14"
						(effects
							(font
								(size 1.27 1.27)
							)
						)
					)
				)
			)
			(symbol "XC7K410T-2FFG900I_2_9_1"
				(rectangle
					(start 5.08 2.54)
					(end 29.21 -91.44)
					(stroke
						(width 0.254)
						(type default)
					)
					(fill
						(type background)
					)
				)
				(pin bidirectional line
					(at 0 0 0)
					(length 5.08)
					(name "VCCO_0"
						(effects
							(font
								(size 1.27 1.27)
							)
						)
					)
					(number "AB6"
						(effects
							(font
								(size 1.27 1.27)
							)
						)
					)
				)
				(pin passive line
					(at 0 0 0)
					(length 5.08)
					(hide yes)
					(name "VCCO_0"
						(effects
							(font
								(size 1.27 1.27)
							)
						)
					)
					(number "T9"
						(effects
							(font
								(size 1.27 1.27)
							)
						)
					)
				)
				(pin bidirectional line
					(at 0 -17.78 0)
					(length 5.08)
					(name "VCCO_12"
						(effects
							(font
								(size 1.27 1.27)
							)
						)
					)
					(number "AC23"
						(effects
							(font
								(size 1.27 1.27)
							)
						)
					)
				)
				(pin passive line
					(at 0 -17.78 0)
					(length 5.08)
					(hide yes)
					(name "VCCO_12"
						(effects
							(font
								(size 1.27 1.27)
							)
						)
					)
					(number "AD20"
						(effects
							(font
								(size 1.27 1.27)
							)
						)
					)
				)
				(pin passive line
					(at 0 -17.78 0)
					(length 5.08)
					(hide yes)
					(name "VCCO_12"
						(effects
							(font
								(size 1.27 1.27)
							)
						)
					)
					(number "AF24"
						(effects
							(font
								(size 1.27 1.27)
							)
						)
					)
				)
				(pin passive line
					(at 0 -17.78 0)
					(length 5.08)
					(hide yes)
					(name "VCCO_12"
						(effects
							(font
								(size 1.27 1.27)
							)
						)
					)
					(number "AG21"
						(effects
							(font
								(size 1.27 1.27)
							)
						)
					)
				)
				(pin passive line
					(at 0 -17.78 0)
					(length 5.08)
					(hide yes)
					(name "VCCO_12"
						(effects
							(font
								(size 1.27 1.27)
							)
						)
					)
					(number "AK22"
						(effects
							(font
								(size 1.27 1.27)
							)
						)
					)
				)
				(pin passive line
					(at 0 -17.78 0)
					(length 5.08)
					(hide yes)
					(name "VCCO_12"
						(effects
							(font
								(size 1.27 1.27)
							)
						)
					)
					(number "Y22"
						(effects
							(font
								(size 1.27 1.27)
							)
						)
					)
				)
				(pin bidirectional line
					(at 0 -35.56 0)
					(length 5.08)
					(name "VCCO_13"
						(effects
							(font
								(size 1.27 1.27)
							)
						)
					)
					(number "AA29"
						(effects
							(font
								(size 1.27 1.27)
							)
						)
					)
				)
				(pin passive line
					(at 0 -35.56 0)
					(length 5.08)
					(hide yes)
					(name "VCCO_13"
						(effects
							(font
								(size 1.27 1.27)
							)
						)
					)
					(number "AB26"
						(effects
							(font
								(size 1.27 1.27)
							)
						)
					)
				)
				(pin passive line
					(at 0 -35.56 0)
					(length 5.08)
					(hide yes)
					(name "VCCO_13"
						(effects
							(font
								(size 1.27 1.27)
							)
						)
					)
					(number "AD30"
						(effects
							(font
								(size 1.27 1.27)
							)
						)
					)
				)
				(pin passive line
					(at 0 -35.56 0)
					(length 5.08)
					(hide yes)
					(name "VCCO_13"
						(effects
							(font
								(size 1.27 1.27)
							)
						)
					)
					(number "AE27"
						(effects
							(font
								(size 1.27 1.27)
							)
						)
					)
				)
				(pin passive line
					(at 0 -35.56 0)
					(length 5.08)
					(hide yes)
					(name "VCCO_13"
						(effects
							(font
								(size 1.27 1.27)
							)
						)
					)
					(number "AH28"
						(effects
							(font
								(size 1.27 1.27)
							)
						)
					)
				)
				(pin passive line
					(at 0 -35.56 0)
					(length 5.08)
					(hide yes)
					(name "VCCO_13"
						(effects
							(font
								(size 1.27 1.27)
							)
						)
					)
					(number "AJ25"
						(effects
							(font
								(size 1.27 1.27)
							)
						)
					)
				)
				(pin bidirectional line
					(at 0 -53.34 0)
					(length 5.08)
					(name "VCCO_14"
						(effects
							(font
								(size 1.27 1.27)
							)
						)
					)
					(number "P30"
						(effects
							(font
								(size 1.27 1.27)
							)
						)
					)
				)
				(pin passive line
					(at 0 -53.34 0)
					(length 5.08)
					(hide yes)
					(name "VCCO_14"
						(effects
							(font
								(size 1.27 1.27)
							)
						)
					)
					(number "R27"
						(effects
							(font
								(size 1.27 1.27)
							)
						)
					)
				)
				(pin passive line
					(at 0 -53.34 0)
					(length 5.08)
					(hide yes)
					(name "VCCO_14"
						(effects
							(font
								(size 1.27 1.27)
							)
						)
					)
					(number "T24"
						(effects
							(font
								(size 1.27 1.27)
							)
						)
					)
				)
				(pin passive line
					(at 0 -53.34 0)
					(length 5.08)
					(hide yes)
					(name "VCCO_14"
						(effects
							(font
								(size 1.27 1.27)
							)
						)
					)
					(number "U21"
						(effects
							(font
								(size 1.27 1.27)
							)
						)
					)
				)
				(pin passive line
					(at 0 -53.34 0)
					(length 5.08)
					(hide yes)
					(name "VCCO_14"
						(effects
							(font
								(size 1.27 1.27)
							)
						)
					)
					(number "V28"
						(effects
							(font
								(size 1.27 1.27)
							)
						)
					)
				)
				(pin passive line
					(at 0 -53.34 0)
					(length 5.08)
					(hide yes)
					(name "VCCO_14"
						(effects
							(font
								(size 1.27 1.27)
							)
						)
					)
					(number "W25"
						(effects
							(font
								(size 1.27 1.27)
							)
						)
					)
				)
				(pin bidirectional line
					(at 0 -71.12 0)
					(length 5.08)
					(name "VCCO_15"
						(effects
							(font
								(size 1.27 1.27)
							)
						)
					)
					(number "J25"
						(effects
							(font
								(size 1.27 1.27)
							)
						)
					)
				)
				(pin passive line
					(at 0 -71.12 0)
					(length 5.08)
					(hide yes)
					(name "VCCO_15"
						(effects
							(font
								(size 1.27 1.27)
							)
						)
					)
					(number "K22"
						(effects
							(font
								(size 1.27 1.27)
							)
						)
					)
				)
				(pin passive line
					(at 0 -71.12 0)
					(length 5.08)
					(hide yes)
					(name "VCCO_15"
						(effects
							(font
								(size 1.27 1.27)
							)
						)
					)
					(number "L29"
						(effects
							(font
								(size 1.27 1.27)
							)
						)
					)
				)
				(pin passive line
					(at 0 -71.12 0)
					(length 5.08)
					(hide yes)
					(name "VCCO_15"
						(effects
							(font
								(size 1.27 1.27)
							)
						)
					)
					(number "M26"
						(effects
							(font
								(size 1.27 1.27)
							)
						)
					)
				)
				(pin passive line
					(at 0 -71.12 0)
					(length 5.08)
					(hide yes)
					(name "VCCO_15"
						(effects
							(font
								(size 1.27 1.27)
							)
						)
					)
					(number "N23"
						(effects
							(font
								(size 1.27 1.27)
							)
						)
					)
				)
				(pin passive line
					(at 0 -71.12 0)
					(length 5.08)
					(hide yes)
					(name "VCCO_15"
						(effects
							(font
								(size 1.27 1.27)
							)
						)
					)
					(number "P20"
						(effects
							(font
								(size 1.27 1.27)
							)
						)
					)
				)
				(pin bidirectional line
					(at 0 -88.9 0)
					(length 5.08)
					(name "VCCO_16"
						(effects
							(font
								(size 1.27 1.27)
							)
						)
					)
					(number "A29"
						(effects
							(font
								(size 1.27 1.27)
							)
						)
					)
				)
				(pin passive line
					(at 0 -88.9 0)
					(length 5.08)
					(hide yes)
					(name "VCCO_16"
						(effects
							(font
								(size 1.27 1.27)
							)
						)
					)
					(number "B26"
						(effects
							(font
								(size 1.27 1.27)
							)
						)
					)
				)
				(pin passive line
					(at 0 -88.9 0)
					(length 5.08)
					(hide yes)
					(name "VCCO_16"
						(effects
							(font
								(size 1.27 1.27)
							)
						)
					)
					(number "C23"
						(effects
							(font
								(size 1.27 1.27)
							)
						)
					)
				)
				(pin passive line
					(at 0 -88.9 0)
					(length 5.08)
					(hide yes)
					(name "VCCO_16"
						(effects
							(font
								(size 1.27 1.27)
							)
						)
					)
					(number "D30"
						(effects
							(font
								(size 1.27 1.27)
							)
						)
					)
				)
				(pin passive line
					(at 0 -88.9 0)
					(length 5.08)
					(hide yes)
					(name "VCCO_16"
						(effects
							(font
								(size 1.27 1.27)
							)
						)
					)
					(number "E27"
						(effects
							(font
								(size 1.27 1.27)
							)
						)
					)
				)
				(pin passive line
					(at 0 -88.9 0)
					(length 5.08)
					(hide yes)
					(name "VCCO_16"
						(effects
							(font
								(size 1.27 1.27)
							)
						)
					)
					(number "F24"
						(effects
							(font
								(size 1.27 1.27)
							)
						)
					)
				)
				(pin passive line
					(at 0 -88.9 0)
					(length 5.08)
					(hide yes)
					(name "VCCO_16"
						(effects
							(font
								(size 1.27 1.27)
							)
						)
					)
					(number "H28"
						(effects
							(font
								(size 1.27 1.27)
							)
						)
					)
				)
				(pin bidirectional line
					(at 34.29 -17.78 180)
					(length 5.08)
					(name "VCCO_17"
						(effects
							(font
								(size 1.27 1.27)
							)
						)
					)
					(number "A19"
						(effects
							(font
								(size 1.27 1.27)
							)
						)
					)
				)
				(pin passive line
					(at 34.29 -17.78 180)
					(length 5.08)
					(hide yes)
					(name "VCCO_17"
						(effects
							(font
								(size 1.27 1.27)
							)
						)
					)
					(number "B16"
						(effects
							(font
								(size 1.27 1.27)
							)
						)
					)
				)
				(pin passive line
					(at 34.29 -17.78 180)
					(length 5.08)
					(hide yes)
					(name "VCCO_17"
						(effects
							(font
								(size 1.27 1.27)
							)
						)
					)
					(number "D20"
						(effects
							(font
								(size 1.27 1.27)
							)
						)
					)
				)
				(pin passive line
					(at 34.29 -17.78 180)
					(length 5.08)
					(hide yes)
					(name "VCCO_17"
						(effects
							(font
								(size 1.27 1.27)
							)
						)
					)
					(number "E17"
						(effects
							(font
								(size 1.27 1.27)
							)
						)
					)
				)
				(pin passive line
					(at 34.29 -17.78 180)
					(length 5.08)
					(hide yes)
					(name "VCCO_17"
						(effects
							(font
								(size 1.27 1.27)
							)
						)
					)
					(number "G21"
						(effects
							(font
								(size 1.27 1.27)
							)
						)
					)
				)
				(pin passive line
					(at 34.29 -17.78 180)
					(length 5.08)
					(hide yes)
					(name "VCCO_17"
						(effects
							(font
								(size 1.27 1.27)
							)
						)
					)
					(number "H18"
						(effects
							(font
								(size 1.27 1.27)
							)
						)
					)
				)
				(pin passive line
					(at 34.29 -17.78 180)
					(length 5.08)
					(hide yes)
					(name "VCCO_17"
						(effects
							(font
								(size 1.27 1.27)
							)
						)
					)
					(number "L19"
						(effects
							(font
								(size 1.27 1.27)
							)
						)
					)
				)
				(pin bidirectional line
					(at 34.29 -35.56 180)
					(length 5.08)
					(name "VCCO_18"
						(effects
							(font
								(size 1.27 1.27)
							)
						)
					)
					(number "C13"
						(effects
							(font
								(size 1.27 1.27)
							)
						)
					)
				)
				(pin passive line
					(at 34.29 -35.56 180)
					(length 5.08)
					(hide yes)
					(name "VCCO_18"
						(effects
							(font
								(size 1.27 1.27)
							)
						)
					)
					(number "D10"
						(effects
							(font
								(size 1.27 1.27)
							)
						)
					)
				)
				(pin passive line
					(at 34.29 -35.56 180)
					(length 5.08)
					(hide yes)
					(name "VCCO_18"
						(effects
							(font
								(size 1.27 1.27)
							)
						)
					)
					(number "F14"
						(effects
							(font
								(size 1.27 1.27)
							)
						)
					)
				)
				(pin passive line
					(at 34.29 -35.56 180)
					(length 5.08)
					(hide yes)
					(name "VCCO_18"
						(effects
							(font
								(size 1.27 1.27)
							)
						)
					)
					(number "G11"
						(effects
							(font
								(size 1.27 1.27)
							)
						)
					)
				)
				(pin passive line
					(at 34.29 -35.56 180)
					(length 5.08)
					(hide yes)
					(name "VCCO_18"
						(effects
							(font
								(size 1.27 1.27)
							)
						)
					)
					(number "J15"
						(effects
							(font
								(size 1.27 1.27)
							)
						)
					)
				)
				(pin passive line
					(at 34.29 -35.56 180)
					(length 5.08)
					(hide yes)
					(name "VCCO_18"
						(effects
							(font
								(size 1.27 1.27)
							)
						)
					)
					(number "K12"
						(effects
							(font
								(size 1.27 1.27)
							)
						)
					)
				)
				(pin bidirectional line
					(at 34.29 -53.34 180)
					(length 5.08)
					(name "VCCO_32"
						(effects
							(font
								(size 1.27 1.27)
							)
						)
					)
					(number "AA19"
						(effects
							(font
								(size 1.27 1.27)
							)
						)
					)
				)
				(pin passive line
					(at 34.29 -53.34 180)
					(length 5.08)
					(hide yes)
					(name "VCCO_32"
						(effects
							(font
								(size 1.27 1.27)
							)
						)
					)
					(number "AB16"
						(effects
							(font
								(size 1.27 1.27)
							)
						)
					)
				)
				(pin passive line
					(at 34.29 -53.34 180)
					(length 5.08)
					(hide yes)
					(name "VCCO_32"
						(effects
							(font
								(size 1.27 1.27)
							)
						)
					)
					(number "AE17"
						(effects
							(font
								(size 1.27 1.27)
							)
						)
					)
				)
				(pin passive line
					(at 34.29 -53.34 180)
					(length 5.08)
					(hide yes)
					(name "VCCO_32"
						(effects
							(font
								(size 1.27 1.27)
							)
						)
					)
					(number "AF14"
						(effects
							(font
								(size 1.27 1.27)
							)
						)
					)
				)
				(pin passive line
					(at 34.29 -53.34 180)
					(length 5.08)
					(hide yes)
					(name "VCCO_32"
						(effects
							(font
								(size 1.27 1.27)
							)
						)
					)
					(number "AH18"
						(effects
							(font
								(size 1.27 1.27)
							)
						)
					)
				)
				(pin passive line
					(at 34.29 -53.34 180)
					(length 5.08)
					(hide yes)
					(name "VCCO_32"
						(effects
							(font
								(size 1.27 1.27)
							)
						)
					)
					(number "AJ15"
						(effects
							(font
								(size 1.27 1.27)
							)
						)
					)
				)
				(pin bidirectional line
					(at 34.29 -71.12 180)
					(length 5.08)
					(name "VCCO_33"
						(effects
							(font
								(size 1.27 1.27)
							)
						)
					)
					(number "AA9"
						(effects
							(font
								(size 1.27 1.27)
							)
						)
					)
				)
				(pin passive line
					(at 34.29 -71.12 180)
					(length 5.08)
					(hide yes)
					(name "VCCO_33"
						(effects
							(font
								(size 1.27 1.27)
							)
						)
					)
					(number "AC13"
						(effects
							(font
								(size 1.27 1.27)
							)
						)
					)
				)
				(pin passive line
					(at 34.29 -71.12 180)
					(length 5.08)
					(hide yes)
					(name "VCCO_33"
						(effects
							(font
								(size 1.27 1.27)
							)
						)
					)
					(number "AD10"
						(effects
							(font
								(size 1.27 1.27)
							)
						)
					)
				)
				(pin passive line
					(at 34.29 -71.12 180)
					(length 5.08)
					(hide yes)
					(name "VCCO_33"
						(effects
							(font
								(size 1.27 1.27)
							)
						)
					)
					(number "AG11"
						(effects
							(font
								(size 1.27 1.27)
							)
						)
					)
				)
				(pin passive line
					(at 34.29 -71.12 180)
					(length 5.08)
					(hide yes)
					(name "VCCO_33"
						(effects
							(font
								(size 1.27 1.27)
							)
						)
					)
					(number "AK12"
						(effects
							(font
								(size 1.27 1.27)
							)
						)
					)
				)
				(pin passive line
					(at 34.29 -71.12 180)
					(length 5.08)
					(hide yes)
					(name "VCCO_33"
						(effects
							(font
								(size 1.27 1.27)
							)
						)
					)
					(number "Y12"
						(effects
							(font
								(size 1.27 1.27)
							)
						)
					)
				)
				(pin bidirectional line
					(at 34.29 -88.9 180)
					(length 5.08)
					(name "VCCO_34"
						(effects
							(font
								(size 1.27 1.27)
							)
						)
					)
					(number "AC3"
						(effects
							(font
								(size 1.27 1.27)
							)
						)
					)
				)
				(pin passive line
					(at 34.29 -88.9 180)
					(length 5.08)
					(hide yes)
					(name "VCCO_34"
						(effects
							(font
								(size 1.27 1.27)
							)
						)
					)
					(number "AE7"
						(effects
							(font
								(size 1.27 1.27)
							)
						)
					)
				)
				(pin passive line
					(at 34.29 -88.9 180)
					(length 5.08)
					(hide yes)
					(name "VCCO_34"
						(effects
							(font
								(size 1.27 1.27)
							)
						)
					)
					(number "AF4"
						(effects
							(font
								(size 1.27 1.27)
							)
						)
					)
				)
				(pin passive line
					(at 34.29 -88.9 180)
					(length 5.08)
					(hide yes)
					(name "VCCO_34"
						(effects
							(font
								(size 1.27 1.27)
							)
						)
					)
					(number "AG1"
						(effects
							(font
								(size 1.27 1.27)
							)
						)
					)
				)
				(pin passive line
					(at 34.29 -88.9 180)
					(length 5.08)
					(hide yes)
					(name "VCCO_34"
						(effects
							(font
								(size 1.27 1.27)
							)
						)
					)
					(number "AH8"
						(effects
							(font
								(size 1.27 1.27)
							)
						)
					)
				)
				(pin passive line
					(at 34.29 -88.9 180)
					(length 5.08)
					(hide yes)
					(name "VCCO_34"
						(effects
							(font
								(size 1.27 1.27)
							)
						)
					)
					(number "AJ5"
						(effects
							(font
								(size 1.27 1.27)
							)
						)
					)
				)
				(pin passive line
					(at 34.29 -88.9 180)
					(length 5.08)
					(hide yes)
					(name "VCCO_34"
						(effects
							(font
								(size 1.27 1.27)
							)
						)
					)
					(number "AK2"
						(effects
							(font
								(size 1.27 1.27)
							)
						)
					)
				)
			)
			(symbol "XC7K410T-2FFG900I_2_10_1"
				(rectangle
					(start 5.08 2.54)
					(end 30.48 -58.42)
					(stroke
						(width 0.254)
						(type default)
					)
					(fill
						(type background)
					)
				)
				(pin bidirectional line
					(at 0 0 0)
					(length 5.08)
					(name "VCCAUX"
						(effects
							(font
								(size 1.27 1.27)
							)
						)
					)
					(number "P13"
						(effects
							(font
								(size 1.27 1.27)
							)
						)
					)
				)
				(pin passive line
					(at 0 0 0)
					(length 5.08)
					(hide yes)
					(name "VCCAUX"
						(effects
							(font
								(size 1.27 1.27)
							)
						)
					)
					(number "T13"
						(effects
							(font
								(size 1.27 1.27)
							)
						)
					)
				)
				(pin passive line
					(at 0 0 0)
					(length 5.08)
					(hide yes)
					(name "VCCAUX"
						(effects
							(font
								(size 1.27 1.27)
							)
						)
					)
					(number "V13"
						(effects
							(font
								(size 1.27 1.27)
							)
						)
					)
				)
				(pin passive line
					(at 0 0 0)
					(length 5.08)
					(hide yes)
					(name "VCCAUX"
						(effects
							(font
								(size 1.27 1.27)
							)
						)
					)
					(number "V15"
						(effects
							(font
								(size 1.27 1.27)
							)
						)
					)
				)
				(pin passive line
					(at 0 0 0)
					(length 5.08)
					(hide yes)
					(name "VCCAUX"
						(effects
							(font
								(size 1.27 1.27)
							)
						)
					)
					(number "W14"
						(effects
							(font
								(size 1.27 1.27)
							)
						)
					)
				)
				(pin bidirectional line
					(at 0 -17.78 0)
					(length 5.08)
					(name "VCCAUX_IO_G0"
						(effects
							(font
								(size 1.27 1.27)
							)
						)
					)
					(number "V11"
						(effects
							(font
								(size 1.27 1.27)
							)
						)
					)
				)
				(pin passive line
					(at 0 -17.78 0)
					(length 5.08)
					(hide yes)
					(name "VCCAUX_IO_G0"
						(effects
							(font
								(size 1.27 1.27)
							)
						)
					)
					(number "W10"
						(effects
							(font
								(size 1.27 1.27)
							)
						)
					)
				)
				(pin passive line
					(at 0 -17.78 0)
					(length 5.08)
					(hide yes)
					(name "VCCAUX_IO_G0"
						(effects
							(font
								(size 1.27 1.27)
							)
						)
					)
					(number "W12"
						(effects
							(font
								(size 1.27 1.27)
							)
						)
					)
				)
				(pin bidirectional line
					(at 0 -35.56 0)
					(length 5.08)
					(name "VCCADC_0"
						(effects
							(font
								(size 1.27 1.27)
							)
						)
					)
					(number "P15"
						(effects
							(font
								(size 1.27 1.27)
							)
						)
					)
				)
				(pin bidirectional line
					(at 0 -53.34 0)
					(length 5.08)
					(name "GNDADC_0"
						(effects
							(font
								(size 1.27 1.27)
							)
						)
					)
					(number "P14"
						(effects
							(font
								(size 1.27 1.27)
							)
						)
					)
				)
				(pin bidirectional line
					(at 0 -55.88 0)
					(length 5.08)
					(name "GND"
						(effects
							(font
								(size 1.27 1.27)
							)
						)
					)
					(number "A1"
						(effects
							(font
								(size 1.27 1.27)
							)
						)
					)
				)
				(pin passive line
					(at 0 -55.88 0)
					(length 5.08)
					(hide yes)
					(name "GND"
						(effects
							(font
								(size 1.27 1.27)
							)
						)
					)
					(number "A14"
						(effects
							(font
								(size 1.27 1.27)
							)
						)
					)
				)
				(pin passive line
					(at 0 -55.88 0)
					(length 5.08)
					(hide yes)
					(name "GND"
						(effects
							(font
								(size 1.27 1.27)
							)
						)
					)
					(number "A2"
						(effects
							(font
								(size 1.27 1.27)
							)
						)
					)
				)
				(pin passive line
					(at 0 -55.88 0)
					(length 5.08)
					(hide yes)
					(name "GND"
						(effects
							(font
								(size 1.27 1.27)
							)
						)
					)
					(number "A24"
						(effects
							(font
								(size 1.27 1.27)
							)
						)
					)
				)
				(pin passive line
					(at 0 -55.88 0)
					(length 5.08)
					(hide yes)
					(name "GND"
						(effects
							(font
								(size 1.27 1.27)
							)
						)
					)
					(number "A5"
						(effects
							(font
								(size 1.27 1.27)
							)
						)
					)
				)
				(pin passive line
					(at 0 -55.88 0)
					(length 5.08)
					(hide yes)
					(name "GND"
						(effects
							(font
								(size 1.27 1.27)
							)
						)
					)
					(number "A6"
						(effects
							(font
								(size 1.27 1.27)
							)
						)
					)
				)
				(pin passive line
					(at 0 -55.88 0)
					(length 5.08)
					(hide yes)
					(name "GND"
						(effects
							(font
								(size 1.27 1.27)
							)
						)
					)
					(number "A9"
						(effects
							(font
								(size 1.27 1.27)
							)
						)
					)
				)
				(pin passive line
					(at 0 -55.88 0)
					(length 5.08)
					(hide yes)
					(name "GND"
						(effects
							(font
								(size 1.27 1.27)
							)
						)
					)
					(number "AA1"
						(effects
							(font
								(size 1.27 1.27)
							)
						)
					)
				)
				(pin passive line
					(at 0 -55.88 0)
					(length 5.08)
					(hide yes)
					(name "GND"
						(effects
							(font
								(size 1.27 1.27)
							)
						)
					)
					(number "AA14"
						(effects
							(font
								(size 1.27 1.27)
							)
						)
					)
				)
				(pin passive line
					(at 0 -55.88 0)
					(length 5.08)
					(hide yes)
					(name "GND"
						(effects
							(font
								(size 1.27 1.27)
							)
						)
					)
					(number "AA2"
						(effects
							(font
								(size 1.27 1.27)
							)
						)
					)
				)
				(pin passive line
					(at 0 -55.88 0)
					(length 5.08)
					(hide yes)
					(name "GND"
						(effects
							(font
								(size 1.27 1.27)
							)
						)
					)
					(number "AA24"
						(effects
							(font
								(size 1.27 1.27)
							)
						)
					)
				)
				(pin passive line
					(at 0 -55.88 0)
					(length 5.08)
					(hide yes)
					(name "GND"
						(effects
							(font
								(size 1.27 1.27)
							)
						)
					)
					(number "AA5"
						(effects
							(font
								(size 1.27 1.27)
							)
						)
					)
				)
				(pin passive line
					(at 0 -55.88 0)
					(length 5.08)
					(hide yes)
					(name "GND"
						(effects
							(font
								(size 1.27 1.27)
							)
						)
					)
					(number "AA6"
						(effects
							(font
								(size 1.27 1.27)
							)
						)
					)
				)
				(pin passive line
					(at 0 -55.88 0)
					(length 5.08)
					(hide yes)
					(name "GND"
						(effects
							(font
								(size 1.27 1.27)
							)
						)
					)
					(number "AA7"
						(effects
							(font
								(size 1.27 1.27)
							)
						)
					)
				)
				(pin passive line
					(at 0 -55.88 0)
					(length 5.08)
					(hide yes)
					(name "GND"
						(effects
							(font
								(size 1.27 1.27)
							)
						)
					)
					(number "AB11"
						(effects
							(font
								(size 1.27 1.27)
							)
						)
					)
				)
				(pin passive line
					(at 0 -55.88 0)
					(length 5.08)
					(hide yes)
					(name "GND"
						(effects
							(font
								(size 1.27 1.27)
							)
						)
					)
					(number "AB21"
						(effects
							(font
								(size 1.27 1.27)
							)
						)
					)
				)
				(pin passive line
					(at 0 -55.88 0)
					(length 5.08)
					(hide yes)
					(name "GND"
						(effects
							(font
								(size 1.27 1.27)
							)
						)
					)
					(number "AB3"
						(effects
							(font
								(size 1.27 1.27)
							)
						)
					)
				)
				(pin passive line
					(at 0 -55.88 0)
					(length 5.08)
					(hide yes)
					(name "GND"
						(effects
							(font
								(size 1.27 1.27)
							)
						)
					)
					(number "AB4"
						(effects
							(font
								(size 1.27 1.27)
							)
						)
					)
				)
				(pin passive line
					(at 0 -55.88 0)
					(length 5.08)
					(hide yes)
					(name "GND"
						(effects
							(font
								(size 1.27 1.27)
							)
						)
					)
					(number "AC18"
						(effects
							(font
								(size 1.27 1.27)
							)
						)
					)
				)
				(pin passive line
					(at 0 -55.88 0)
					(length 5.08)
					(hide yes)
					(name "GND"
						(effects
							(font
								(size 1.27 1.27)
							)
						)
					)
					(number "AC28"
						(effects
							(font
								(size 1.27 1.27)
							)
						)
					)
				)
				(pin passive line
					(at 0 -55.88 0)
					(length 5.08)
					(hide yes)
					(name "GND"
						(effects
							(font
								(size 1.27 1.27)
							)
						)
					)
					(number "AC8"
						(effects
							(font
								(size 1.27 1.27)
							)
						)
					)
				)
				(pin passive line
					(at 0 -55.88 0)
					(length 5.08)
					(hide yes)
					(name "GND"
						(effects
							(font
								(size 1.27 1.27)
							)
						)
					)
					(number "AD15"
						(effects
							(font
								(size 1.27 1.27)
							)
						)
					)
				)
				(pin passive line
					(at 0 -55.88 0)
					(length 5.08)
					(hide yes)
					(name "GND"
						(effects
							(font
								(size 1.27 1.27)
							)
						)
					)
					(number "AD25"
						(effects
							(font
								(size 1.27 1.27)
							)
						)
					)
				)
				(pin passive line
					(at 0 -55.88 0)
					(length 5.08)
					(hide yes)
					(name "GND"
						(effects
							(font
								(size 1.27 1.27)
							)
						)
					)
					(number "AD5"
						(effects
							(font
								(size 1.27 1.27)
							)
						)
					)
				)
				(pin passive line
					(at 0 -55.88 0)
					(length 5.08)
					(hide yes)
					(name "GND"
						(effects
							(font
								(size 1.27 1.27)
							)
						)
					)
					(number "AE12"
						(effects
							(font
								(size 1.27 1.27)
							)
						)
					)
				)
				(pin passive line
					(at 0 -55.88 0)
					(length 5.08)
					(hide yes)
					(name "GND"
						(effects
							(font
								(size 1.27 1.27)
							)
						)
					)
					(number "AE2"
						(effects
							(font
								(size 1.27 1.27)
							)
						)
					)
				)
				(pin passive line
					(at 0 -55.88 0)
					(length 5.08)
					(hide yes)
					(name "GND"
						(effects
							(font
								(size 1.27 1.27)
							)
						)
					)
					(number "AE22"
						(effects
							(font
								(size 1.27 1.27)
							)
						)
					)
				)
				(pin passive line
					(at 0 -55.88 0)
					(length 5.08)
					(hide yes)
					(name "GND"
						(effects
							(font
								(size 1.27 1.27)
							)
						)
					)
					(number "AF19"
						(effects
							(font
								(size 1.27 1.27)
							)
						)
					)
				)
				(pin passive line
					(at 0 -55.88 0)
					(length 5.08)
					(hide yes)
					(name "GND"
						(effects
							(font
								(size 1.27 1.27)
							)
						)
					)
					(number "AF29"
						(effects
							(font
								(size 1.27 1.27)
							)
						)
					)
				)
				(pin passive line
					(at 0 -55.88 0)
					(length 5.08)
					(hide yes)
					(name "GND"
						(effects
							(font
								(size 1.27 1.27)
							)
						)
					)
					(number "AF9"
						(effects
							(font
								(size 1.27 1.27)
							)
						)
					)
				)
				(pin passive line
					(at 0 -55.88 0)
					(length 5.08)
					(hide yes)
					(name "GND"
						(effects
							(font
								(size 1.27 1.27)
							)
						)
					)
					(number "AG16"
						(effects
							(font
								(size 1.27 1.27)
							)
						)
					)
				)
				(pin passive line
					(at 0 -55.88 0)
					(length 5.08)
					(hide yes)
					(name "GND"
						(effects
							(font
								(size 1.27 1.27)
							)
						)
					)
					(number "AG26"
						(effects
							(font
								(size 1.27 1.27)
							)
						)
					)
				)
				(pin passive line
					(at 0 -55.88 0)
					(length 5.08)
					(hide yes)
					(name "GND"
						(effects
							(font
								(size 1.27 1.27)
							)
						)
					)
					(number "AG6"
						(effects
							(font
								(size 1.27 1.27)
							)
						)
					)
				)
				(pin passive line
					(at 0 -55.88 0)
					(length 5.08)
					(hide yes)
					(name "GND"
						(effects
							(font
								(size 1.27 1.27)
							)
						)
					)
					(number "AH13"
						(effects
							(font
								(size 1.27 1.27)
							)
						)
					)
				)
				(pin passive line
					(at 0 -55.88 0)
					(length 5.08)
					(hide yes)
					(name "GND"
						(effects
							(font
								(size 1.27 1.27)
							)
						)
					)
					(number "AH23"
						(effects
							(font
								(size 1.27 1.27)
							)
						)
					)
				)
				(pin passive line
					(at 0 -55.88 0)
					(length 5.08)
					(hide yes)
					(name "GND"
						(effects
							(font
								(size 1.27 1.27)
							)
						)
					)
					(number "AH3"
						(effects
							(font
								(size 1.27 1.27)
							)
						)
					)
				)
				(pin passive line
					(at 0 -55.88 0)
					(length 5.08)
					(hide yes)
					(name "GND"
						(effects
							(font
								(size 1.27 1.27)
							)
						)
					)
					(number "AJ10"
						(effects
							(font
								(size 1.27 1.27)
							)
						)
					)
				)
				(pin passive line
					(at 0 -55.88 0)
					(length 5.08)
					(hide yes)
					(name "GND"
						(effects
							(font
								(size 1.27 1.27)
							)
						)
					)
					(number "AJ20"
						(effects
							(font
								(size 1.27 1.27)
							)
						)
					)
				)
				(pin passive line
					(at 0 -55.88 0)
					(length 5.08)
					(hide yes)
					(name "GND"
						(effects
							(font
								(size 1.27 1.27)
							)
						)
					)
					(number "AJ30"
						(effects
							(font
								(size 1.27 1.27)
							)
						)
					)
				)
				(pin passive line
					(at 0 -55.88 0)
					(length 5.08)
					(hide yes)
					(name "GND"
						(effects
							(font
								(size 1.27 1.27)
							)
						)
					)
					(number "AK17"
						(effects
							(font
								(size 1.27 1.27)
							)
						)
					)
				)
				(pin passive line
					(at 0 -55.88 0)
					(length 5.08)
					(hide yes)
					(name "GND"
						(effects
							(font
								(size 1.27 1.27)
							)
						)
					)
					(number "AK27"
						(effects
							(font
								(size 1.27 1.27)
							)
						)
					)
				)
				(pin passive line
					(at 0 -55.88 0)
					(length 5.08)
					(hide yes)
					(name "GND"
						(effects
							(font
								(size 1.27 1.27)
							)
						)
					)
					(number "AK7"
						(effects
							(font
								(size 1.27 1.27)
							)
						)
					)
				)
				(pin passive line
					(at 0 -55.88 0)
					(length 5.08)
					(hide yes)
					(name "GND"
						(effects
							(font
								(size 1.27 1.27)
							)
						)
					)
					(number "B11"
						(effects
							(font
								(size 1.27 1.27)
							)
						)
					)
				)
				(pin passive line
					(at 0 -55.88 0)
					(length 5.08)
					(hide yes)
					(name "GND"
						(effects
							(font
								(size 1.27 1.27)
							)
						)
					)
					(number "B21"
						(effects
							(font
								(size 1.27 1.27)
							)
						)
					)
				)
				(pin passive line
					(at 0 -55.88 0)
					(length 5.08)
					(hide yes)
					(name "GND"
						(effects
							(font
								(size 1.27 1.27)
							)
						)
					)
					(number "B4"
						(effects
							(font
								(size 1.27 1.27)
							)
						)
					)
				)
				(pin passive line
					(at 0 -55.88 0)
					(length 5.08)
					(hide yes)
					(name "GND"
						(effects
							(font
								(size 1.27 1.27)
							)
						)
					)
					(number "B8"
						(effects
							(font
								(size 1.27 1.27)
							)
						)
					)
				)
				(pin passive line
					(at 0 -55.88 0)
					(length 5.08)
					(hide yes)
					(name "GND"
						(effects
							(font
								(size 1.27 1.27)
							)
						)
					)
					(number "B9"
						(effects
							(font
								(size 1.27 1.27)
							)
						)
					)
				)
				(pin passive line
					(at 0 -55.88 0)
					(length 5.08)
					(hide yes)
					(name "GND"
						(effects
							(font
								(size 1.27 1.27)
							)
						)
					)
					(number "C1"
						(effects
							(font
								(size 1.27 1.27)
							)
						)
					)
				)
				(pin passive line
					(at 0 -55.88 0)
					(length 5.08)
					(hide yes)
					(name "GND"
						(effects
							(font
								(size 1.27 1.27)
							)
						)
					)
					(number "C18"
						(effects
							(font
								(size 1.27 1.27)
							)
						)
					)
				)
				(pin passive line
					(at 0 -55.88 0)
					(length 5.08)
					(hide yes)
					(name "GND"
						(effects
							(font
								(size 1.27 1.27)
							)
						)
					)
					(number "C2"
						(effects
							(font
								(size 1.27 1.27)
							)
						)
					)
				)
				(pin passive line
					(at 0 -55.88 0)
					(length 5.08)
					(hide yes)
					(name "GND"
						(effects
							(font
								(size 1.27 1.27)
							)
						)
					)
					(number "C28"
						(effects
							(font
								(size 1.27 1.27)
							)
						)
					)
				)
				(pin passive line
					(at 0 -55.88 0)
					(length 5.08)
					(hide yes)
					(name "GND"
						(effects
							(font
								(size 1.27 1.27)
							)
						)
					)
					(number "C6"
						(effects
							(font
								(size 1.27 1.27)
							)
						)
					)
				)
				(pin passive line
					(at 0 -55.88 0)
					(length 5.08)
					(hide yes)
					(name "GND"
						(effects
							(font
								(size 1.27 1.27)
							)
						)
					)
					(number "C9"
						(effects
							(font
								(size 1.27 1.27)
							)
						)
					)
				)
				(pin passive line
					(at 0 -55.88 0)
					(length 5.08)
					(hide yes)
					(name "GND"
						(effects
							(font
								(size 1.27 1.27)
							)
						)
					)
					(number "D15"
						(effects
							(font
								(size 1.27 1.27)
							)
						)
					)
				)
				(pin passive line
					(at 0 -55.88 0)
					(length 5.08)
					(hide yes)
					(name "GND"
						(effects
							(font
								(size 1.27 1.27)
							)
						)
					)
					(number "D25"
						(effects
							(font
								(size 1.27 1.27)
							)
						)
					)
				)
				(pin passive line
					(at 0 -55.88 0)
					(length 5.08)
					(hide yes)
					(name "GND"
						(effects
							(font
								(size 1.27 1.27)
							)
						)
					)
					(number "D4"
						(effects
							(font
								(size 1.27 1.27)
							)
						)
					)
				)
				(pin passive line
					(at 0 -55.88 0)
					(length 5.08)
					(hide yes)
					(name "GND"
						(effects
							(font
								(size 1.27 1.27)
							)
						)
					)
					(number "D8"
						(effects
							(font
								(size 1.27 1.27)
							)
						)
					)
				)
				(pin passive line
					(at 0 -55.88 0)
					(length 5.08)
					(hide yes)
					(name "GND"
						(effects
							(font
								(size 1.27 1.27)
							)
						)
					)
					(number "D9"
						(effects
							(font
								(size 1.27 1.27)
							)
						)
					)
				)
				(pin passive line
					(at 0 -55.88 0)
					(length 5.08)
					(hide yes)
					(name "GND"
						(effects
							(font
								(size 1.27 1.27)
							)
						)
					)
					(number "E1"
						(effects
							(font
								(size 1.27 1.27)
							)
						)
					)
				)
				(pin passive line
					(at 0 -55.88 0)
					(length 5.08)
					(hide yes)
					(name "GND"
						(effects
							(font
								(size 1.27 1.27)
							)
						)
					)
					(number "E12"
						(effects
							(font
								(size 1.27 1.27)
							)
						)
					)
				)
				(pin passive line
					(at 0 -55.88 0)
					(length 5.08)
					(hide yes)
					(name "GND"
						(effects
							(font
								(size 1.27 1.27)
							)
						)
					)
					(number "E2"
						(effects
							(font
								(size 1.27 1.27)
							)
						)
					)
				)
				(pin passive line
					(at 0 -55.88 0)
					(length 5.08)
					(hide yes)
					(name "GND"
						(effects
							(font
								(size 1.27 1.27)
							)
						)
					)
					(number "E22"
						(effects
							(font
								(size 1.27 1.27)
							)
						)
					)
				)
				(pin passive line
					(at 0 -55.88 0)
					(length 5.08)
					(hide yes)
					(name "GND"
						(effects
							(font
								(size 1.27 1.27)
							)
						)
					)
					(number "E6"
						(effects
							(font
								(size 1.27 1.27)
							)
						)
					)
				)
				(pin passive line
					(at 0 -55.88 0)
					(length 5.08)
					(hide yes)
					(name "GND"
						(effects
							(font
								(size 1.27 1.27)
							)
						)
					)
					(number "E9"
						(effects
							(font
								(size 1.27 1.27)
							)
						)
					)
				)
				(pin passive line
					(at 0 -55.88 0)
					(length 5.08)
					(hide yes)
					(name "GND"
						(effects
							(font
								(size 1.27 1.27)
							)
						)
					)
					(number "F19"
						(effects
							(font
								(size 1.27 1.27)
							)
						)
					)
				)
				(pin passive line
					(at 0 -55.88 0)
					(length 5.08)
					(hide yes)
					(name "GND"
						(effects
							(font
								(size 1.27 1.27)
							)
						)
					)
					(number "F29"
						(effects
							(font
								(size 1.27 1.27)
							)
						)
					)
				)
				(pin passive line
					(at 0 -55.88 0)
					(length 5.08)
					(hide yes)
					(name "GND"
						(effects
							(font
								(size 1.27 1.27)
							)
						)
					)
					(number "F4"
						(effects
							(font
								(size 1.27 1.27)
							)
						)
					)
				)
				(pin passive line
					(at 0 -55.88 0)
					(length 5.08)
					(hide yes)
					(name "GND"
						(effects
							(font
								(size 1.27 1.27)
							)
						)
					)
					(number "F8"
						(effects
							(font
								(size 1.27 1.27)
							)
						)
					)
				)
				(pin passive line
					(at 0 -55.88 0)
					(length 5.08)
					(hide yes)
					(name "GND"
						(effects
							(font
								(size 1.27 1.27)
							)
						)
					)
					(number "F9"
						(effects
							(font
								(size 1.27 1.27)
							)
						)
					)
				)
				(pin passive line
					(at 0 -55.88 0)
					(length 5.08)
					(hide yes)
					(name "GND"
						(effects
							(font
								(size 1.27 1.27)
							)
						)
					)
					(number "G1"
						(effects
							(font
								(size 1.27 1.27)
							)
						)
					)
				)
				(pin passive line
					(at 0 -55.88 0)
					(length 5.08)
					(hide yes)
					(name "GND"
						(effects
							(font
								(size 1.27 1.27)
							)
						)
					)
					(number "G16"
						(effects
							(font
								(size 1.27 1.27)
							)
						)
					)
				)
				(pin passive line
					(at 0 -55.88 0)
					(length 5.08)
					(hide yes)
					(name "GND"
						(effects
							(font
								(size 1.27 1.27)
							)
						)
					)
					(number "G2"
						(effects
							(font
								(size 1.27 1.27)
							)
						)
					)
				)
				(pin passive line
					(at 0 -55.88 0)
					(length 5.08)
					(hide yes)
					(name "GND"
						(effects
							(font
								(size 1.27 1.27)
							)
						)
					)
					(number "G26"
						(effects
							(font
								(size 1.27 1.27)
							)
						)
					)
				)
				(pin passive line
					(at 0 -55.88 0)
					(length 5.08)
					(hide yes)
					(name "GND"
						(effects
							(font
								(size 1.27 1.27)
							)
						)
					)
					(number "G6"
						(effects
							(font
								(size 1.27 1.27)
							)
						)
					)
				)
				(pin passive line
					(at 0 -55.88 0)
					(length 5.08)
					(hide yes)
					(name "GND"
						(effects
							(font
								(size 1.27 1.27)
							)
						)
					)
					(number "G9"
						(effects
							(font
								(size 1.27 1.27)
							)
						)
					)
				)
				(pin passive line
					(at 0 -55.88 0)
					(length 5.08)
					(hide yes)
					(name "GND"
						(effects
							(font
								(size 1.27 1.27)
							)
						)
					)
					(number "H13"
						(effects
							(font
								(size 1.27 1.27)
							)
						)
					)
				)
				(pin passive line
					(at 0 -55.88 0)
					(length 5.08)
					(hide yes)
					(name "GND"
						(effects
							(font
								(size 1.27 1.27)
							)
						)
					)
					(number "H23"
						(effects
							(font
								(size 1.27 1.27)
							)
						)
					)
				)
				(pin passive line
					(at 0 -55.88 0)
					(length 5.08)
					(hide yes)
					(name "GND"
						(effects
							(font
								(size 1.27 1.27)
							)
						)
					)
					(number "H4"
						(effects
							(font
								(size 1.27 1.27)
							)
						)
					)
				)
				(pin passive line
					(at 0 -55.88 0)
					(length 5.08)
					(hide yes)
					(name "GND"
						(effects
							(font
								(size 1.27 1.27)
							)
						)
					)
					(number "H8"
						(effects
							(font
								(size 1.27 1.27)
							)
						)
					)
				)
				(pin passive line
					(at 0 -55.88 0)
					(length 5.08)
					(hide yes)
					(name "GND"
						(effects
							(font
								(size 1.27 1.27)
							)
						)
					)
					(number "H9"
						(effects
							(font
								(size 1.27 1.27)
							)
						)
					)
				)
				(pin passive line
					(at 0 -55.88 0)
					(length 5.08)
					(hide yes)
					(name "GND"
						(effects
							(font
								(size 1.27 1.27)
							)
						)
					)
					(number "J1"
						(effects
							(font
								(size 1.27 1.27)
							)
						)
					)
				)
				(pin passive line
					(at 0 -55.88 0)
					(length 5.08)
					(hide yes)
					(name "GND"
						(effects
							(font
								(size 1.27 1.27)
							)
						)
					)
					(number "J10"
						(effects
							(font
								(size 1.27 1.27)
							)
						)
					)
				)
				(pin passive line
					(at 0 -55.88 0)
					(length 5.08)
					(hide yes)
					(name "GND"
						(effects
							(font
								(size 1.27 1.27)
							)
						)
					)
					(number "J2"
						(effects
							(font
								(size 1.27 1.27)
							)
						)
					)
				)
				(pin passive line
					(at 0 -55.88 0)
					(length 5.08)
					(hide yes)
					(name "GND"
						(effects
							(font
								(size 1.27 1.27)
							)
						)
					)
					(number "J20"
						(effects
							(font
								(size 1.27 1.27)
							)
						)
					)
				)
				(pin passive line
					(at 0 -55.88 0)
					(length 5.08)
					(hide yes)
					(name "GND"
						(effects
							(font
								(size 1.27 1.27)
							)
						)
					)
					(number "J30"
						(effects
							(font
								(size 1.27 1.27)
							)
						)
					)
				)
				(pin passive line
					(at 0 -55.88 0)
					(length 5.08)
					(hide yes)
					(name "GND"
						(effects
							(font
								(size 1.27 1.27)
							)
						)
					)
					(number "J6"
						(effects
							(font
								(size 1.27 1.27)
							)
						)
					)
				)
				(pin passive line
					(at 0 -55.88 0)
					(length 5.08)
					(hide yes)
					(name "GND"
						(effects
							(font
								(size 1.27 1.27)
							)
						)
					)
					(number "J9"
						(effects
							(font
								(size 1.27 1.27)
							)
						)
					)
				)
				(pin passive line
					(at 0 -55.88 0)
					(length 5.08)
					(hide yes)
					(name "GND"
						(effects
							(font
								(size 1.27 1.27)
							)
						)
					)
					(number "K17"
						(effects
							(font
								(size 1.27 1.27)
							)
						)
					)
				)
				(pin passive line
					(at 0 -55.88 0)
					(length 5.08)
					(hide yes)
					(name "GND"
						(effects
							(font
								(size 1.27 1.27)
							)
						)
					)
					(number "K27"
						(effects
							(font
								(size 1.27 1.27)
							)
						)
					)
				)
				(pin passive line
					(at 0 -55.88 0)
					(length 5.08)
					(hide yes)
					(name "GND"
						(effects
							(font
								(size 1.27 1.27)
							)
						)
					)
					(number "K4"
						(effects
							(font
								(size 1.27 1.27)
							)
						)
					)
				)
				(pin passive line
					(at 0 -55.88 0)
					(length 5.08)
					(hide yes)
					(name "GND"
						(effects
							(font
								(size 1.27 1.27)
							)
						)
					)
					(number "K8"
						(effects
							(font
								(size 1.27 1.27)
							)
						)
					)
				)
				(pin passive line
					(at 0 -55.88 0)
					(length 5.08)
					(hide yes)
					(name "GND"
						(effects
							(font
								(size 1.27 1.27)
							)
						)
					)
					(number "K9"
						(effects
							(font
								(size 1.27 1.27)
							)
						)
					)
				)
				(pin passive line
					(at 0 -55.88 0)
					(length 5.08)
					(hide yes)
					(name "GND"
						(effects
							(font
								(size 1.27 1.27)
							)
						)
					)
					(number "L1"
						(effects
							(font
								(size 1.27 1.27)
							)
						)
					)
				)
				(pin passive line
					(at 0 -55.88 0)
					(length 5.08)
					(hide yes)
					(name "GND"
						(effects
							(font
								(size 1.27 1.27)
							)
						)
					)
					(number "L14"
						(effects
							(font
								(size 1.27 1.27)
							)
						)
					)
				)
				(pin passive line
					(at 0 -55.88 0)
					(length 5.08)
					(hide yes)
					(name "GND"
						(effects
							(font
								(size 1.27 1.27)
							)
						)
					)
					(number "L2"
						(effects
							(font
								(size 1.27 1.27)
							)
						)
					)
				)
				(pin passive line
					(at 0 -55.88 0)
					(length 5.08)
					(hide yes)
					(name "GND"
						(effects
							(font
								(size 1.27 1.27)
							)
						)
					)
					(number "L24"
						(effects
							(font
								(size 1.27 1.27)
							)
						)
					)
				)
				(pin passive line
					(at 0 -55.88 0)
					(length 5.08)
					(hide yes)
					(name "GND"
						(effects
							(font
								(size 1.27 1.27)
							)
						)
					)
					(number "L6"
						(effects
							(font
								(size 1.27 1.27)
							)
						)
					)
				)
				(pin passive line
					(at 0 -55.88 0)
					(length 5.08)
					(hide yes)
					(name "GND"
						(effects
							(font
								(size 1.27 1.27)
							)
						)
					)
					(number "L9"
						(effects
							(font
								(size 1.27 1.27)
							)
						)
					)
				)
				(pin passive line
					(at 0 -55.88 0)
					(length 5.08)
					(hide yes)
					(name "GND"
						(effects
							(font
								(size 1.27 1.27)
							)
						)
					)
					(number "M12"
						(effects
							(font
								(size 1.27 1.27)
							)
						)
					)
				)
				(pin passive line
					(at 0 -55.88 0)
					(length 5.08)
					(hide yes)
					(name "GND"
						(effects
							(font
								(size 1.27 1.27)
							)
						)
					)
					(number "M14"
						(effects
							(font
								(size 1.27 1.27)
							)
						)
					)
				)
				(pin passive line
					(at 0 -55.88 0)
					(length 5.08)
					(hide yes)
					(name "GND"
						(effects
							(font
								(size 1.27 1.27)
							)
						)
					)
					(number "M16"
						(effects
							(font
								(size 1.27 1.27)
							)
						)
					)
				)
				(pin passive line
					(at 0 -55.88 0)
					(length 5.08)
					(hide yes)
					(name "GND"
						(effects
							(font
								(size 1.27 1.27)
							)
						)
					)
					(number "M18"
						(effects
							(font
								(size 1.27 1.27)
							)
						)
					)
				)
				(pin passive line
					(at 0 -55.88 0)
					(length 5.08)
					(hide yes)
					(name "GND"
						(effects
							(font
								(size 1.27 1.27)
							)
						)
					)
					(number "M21"
						(effects
							(font
								(size 1.27 1.27)
							)
						)
					)
				)
				(pin passive line
					(at 0 -55.88 0)
					(length 5.08)
					(hide yes)
					(name "GND"
						(effects
							(font
								(size 1.27 1.27)
							)
						)
					)
					(number "M4"
						(effects
							(font
								(size 1.27 1.27)
							)
						)
					)
				)
				(pin passive line
					(at 0 -55.88 0)
					(length 5.08)
					(hide yes)
					(name "GND"
						(effects
							(font
								(size 1.27 1.27)
							)
						)
					)
					(number "M8"
						(effects
							(font
								(size 1.27 1.27)
							)
						)
					)
				)
				(pin passive line
					(at 0 -55.88 0)
					(length 5.08)
					(hide yes)
					(name "GND"
						(effects
							(font
								(size 1.27 1.27)
							)
						)
					)
					(number "M9"
						(effects
							(font
								(size 1.27 1.27)
							)
						)
					)
				)
				(pin passive line
					(at 0 -55.88 0)
					(length 5.08)
					(hide yes)
					(name "GND"
						(effects
							(font
								(size 1.27 1.27)
							)
						)
					)
					(number "N1"
						(effects
							(font
								(size 1.27 1.27)
							)
						)
					)
				)
				(pin passive line
					(at 0 -55.88 0)
					(length 5.08)
					(hide yes)
					(name "GND"
						(effects
							(font
								(size 1.27 1.27)
							)
						)
					)
					(number "N11"
						(effects
							(font
								(size 1.27 1.27)
							)
						)
					)
				)
				(pin passive line
					(at 0 -55.88 0)
					(length 5.08)
					(hide yes)
					(name "GND"
						(effects
							(font
								(size 1.27 1.27)
							)
						)
					)
					(number "N13"
						(effects
							(font
								(size 1.27 1.27)
							)
						)
					)
				)
				(pin passive line
					(at 0 -55.88 0)
					(length 5.08)
					(hide yes)
					(name "GND"
						(effects
							(font
								(size 1.27 1.27)
							)
						)
					)
					(number "N15"
						(effects
							(font
								(size 1.27 1.27)
							)
						)
					)
				)
				(pin passive line
					(at 0 -55.88 0)
					(length 5.08)
					(hide yes)
					(name "GND"
						(effects
							(font
								(size 1.27 1.27)
							)
						)
					)
					(number "N17"
						(effects
							(font
								(size 1.27 1.27)
							)
						)
					)
				)
				(pin passive line
					(at 0 -55.88 0)
					(length 5.08)
					(hide yes)
					(name "GND"
						(effects
							(font
								(size 1.27 1.27)
							)
						)
					)
					(number "N2"
						(effects
							(font
								(size 1.27 1.27)
							)
						)
					)
				)
				(pin passive line
					(at 0 -55.88 0)
					(length 5.08)
					(hide yes)
					(name "GND"
						(effects
							(font
								(size 1.27 1.27)
							)
						)
					)
					(number "N28"
						(effects
							(font
								(size 1.27 1.27)
							)
						)
					)
				)
				(pin passive line
					(at 0 -55.88 0)
					(length 5.08)
					(hide yes)
					(name "GND"
						(effects
							(font
								(size 1.27 1.27)
							)
						)
					)
					(number "N6"
						(effects
							(font
								(size 1.27 1.27)
							)
						)
					)
				)
				(pin passive line
					(at 0 -55.88 0)
					(length 5.08)
					(hide yes)
					(name "GND"
						(effects
							(font
								(size 1.27 1.27)
							)
						)
					)
					(number "N9"
						(effects
							(font
								(size 1.27 1.27)
							)
						)
					)
				)
				(pin passive line
					(at 0 -55.88 0)
					(length 5.08)
					(hide yes)
					(name "GND"
						(effects
							(font
								(size 1.27 1.27)
							)
						)
					)
					(number "P10"
						(effects
							(font
								(size 1.27 1.27)
							)
						)
					)
				)
				(pin passive line
					(at 0 -55.88 0)
					(length 5.08)
					(hide yes)
					(name "GND"
						(effects
							(font
								(size 1.27 1.27)
							)
						)
					)
					(number "P12"
						(effects
							(font
								(size 1.27 1.27)
							)
						)
					)
				)
				(pin passive line
					(at 0 -55.88 0)
					(length 5.08)
					(hide yes)
					(name "GND"
						(effects
							(font
								(size 1.27 1.27)
							)
						)
					)
					(number "P16"
						(effects
							(font
								(size 1.27 1.27)
							)
						)
					)
				)
				(pin passive line
					(at 0 -55.88 0)
					(length 5.08)
					(hide yes)
					(name "GND"
						(effects
							(font
								(size 1.27 1.27)
							)
						)
					)
					(number "P18"
						(effects
							(font
								(size 1.27 1.27)
							)
						)
					)
				)
				(pin passive line
					(at 0 -55.88 0)
					(length 5.08)
					(hide yes)
					(name "GND"
						(effects
							(font
								(size 1.27 1.27)
							)
						)
					)
					(number "P25"
						(effects
							(font
								(size 1.27 1.27)
							)
						)
					)
				)
				(pin passive line
					(at 0 -55.88 0)
					(length 5.08)
					(hide yes)
					(name "GND"
						(effects
							(font
								(size 1.27 1.27)
							)
						)
					)
					(number "P4"
						(effects
							(font
								(size 1.27 1.27)
							)
						)
					)
				)
				(pin passive line
					(at 0 -55.88 0)
					(length 5.08)
					(hide yes)
					(name "GND"
						(effects
							(font
								(size 1.27 1.27)
							)
						)
					)
					(number "P8"
						(effects
							(font
								(size 1.27 1.27)
							)
						)
					)
				)
				(pin passive line
					(at 0 -55.88 0)
					(length 5.08)
					(hide yes)
					(name "GND"
						(effects
							(font
								(size 1.27 1.27)
							)
						)
					)
					(number "P9"
						(effects
							(font
								(size 1.27 1.27)
							)
						)
					)
				)
				(pin passive line
					(at 0 -55.88 0)
					(length 5.08)
					(hide yes)
					(name "GND"
						(effects
							(font
								(size 1.27 1.27)
							)
						)
					)
					(number "R1"
						(effects
							(font
								(size 1.27 1.27)
							)
						)
					)
				)
				(pin passive line
					(at 0 -55.88 0)
					(length 5.08)
					(hide yes)
					(name "GND"
						(effects
							(font
								(size 1.27 1.27)
							)
						)
					)
					(number "R11"
						(effects
							(font
								(size 1.27 1.27)
							)
						)
					)
				)
				(pin passive line
					(at 0 -55.88 0)
					(length 5.08)
					(hide yes)
					(name "GND"
						(effects
							(font
								(size 1.27 1.27)
							)
						)
					)
					(number "R13"
						(effects
							(font
								(size 1.27 1.27)
							)
						)
					)
				)
				(pin passive line
					(at 0 -55.88 0)
					(length 5.08)
					(hide yes)
					(name "GND"
						(effects
							(font
								(size 1.27 1.27)
							)
						)
					)
					(number "R17"
						(effects
							(font
								(size 1.27 1.27)
							)
						)
					)
				)
				(pin passive line
					(at 0 -55.88 0)
					(length 5.08)
					(hide yes)
					(name "GND"
						(effects
							(font
								(size 1.27 1.27)
							)
						)
					)
					(number "R2"
						(effects
							(font
								(size 1.27 1.27)
							)
						)
					)
				)
				(pin passive line
					(at 0 -55.88 0)
					(length 5.08)
					(hide yes)
					(name "GND"
						(effects
							(font
								(size 1.27 1.27)
							)
						)
					)
					(number "R22"
						(effects
							(font
								(size 1.27 1.27)
							)
						)
					)
				)
				(pin passive line
					(at 0 -55.88 0)
					(length 5.08)
					(hide yes)
					(name "GND"
						(effects
							(font
								(size 1.27 1.27)
							)
						)
					)
					(number "R6"
						(effects
							(font
								(size 1.27 1.27)
							)
						)
					)
				)
				(pin passive line
					(at 0 -55.88 0)
					(length 5.08)
					(hide yes)
					(name "GND"
						(effects
							(font
								(size 1.27 1.27)
							)
						)
					)
					(number "R9"
						(effects
							(font
								(size 1.27 1.27)
							)
						)
					)
				)
				(pin passive line
					(at 0 -55.88 0)
					(length 5.08)
					(hide yes)
					(name "GND"
						(effects
							(font
								(size 1.27 1.27)
							)
						)
					)
					(number "T10"
						(effects
							(font
								(size 1.27 1.27)
							)
						)
					)
				)
				(pin passive line
					(at 0 -55.88 0)
					(length 5.08)
					(hide yes)
					(name "GND"
						(effects
							(font
								(size 1.27 1.27)
							)
						)
					)
					(number "T12"
						(effects
							(font
								(size 1.27 1.27)
							)
						)
					)
				)
				(pin passive line
					(at 0 -55.88 0)
					(length 5.08)
					(hide yes)
					(name "GND"
						(effects
							(font
								(size 1.27 1.27)
							)
						)
					)
					(number "T16"
						(effects
							(font
								(size 1.27 1.27)
							)
						)
					)
				)
				(pin passive line
					(at 0 -55.88 0)
					(length 5.08)
					(hide yes)
					(name "GND"
						(effects
							(font
								(size 1.27 1.27)
							)
						)
					)
					(number "T18"
						(effects
							(font
								(size 1.27 1.27)
							)
						)
					)
				)
				(pin passive line
					(at 0 -55.88 0)
					(length 5.08)
					(hide yes)
					(name "GND"
						(effects
							(font
								(size 1.27 1.27)
							)
						)
					)
					(number "T19"
						(effects
							(font
								(size 1.27 1.27)
							)
						)
					)
				)
				(pin passive line
					(at 0 -55.88 0)
					(length 5.08)
					(hide yes)
					(name "GND"
						(effects
							(font
								(size 1.27 1.27)
							)
						)
					)
					(number "T29"
						(effects
							(font
								(size 1.27 1.27)
							)
						)
					)
				)
				(pin passive line
					(at 0 -55.88 0)
					(length 5.08)
					(hide yes)
					(name "GND"
						(effects
							(font
								(size 1.27 1.27)
							)
						)
					)
					(number "T4"
						(effects
							(font
								(size 1.27 1.27)
							)
						)
					)
				)
				(pin passive line
					(at 0 -55.88 0)
					(length 5.08)
					(hide yes)
					(name "GND"
						(effects
							(font
								(size 1.27 1.27)
							)
						)
					)
					(number "T8"
						(effects
							(font
								(size 1.27 1.27)
							)
						)
					)
				)
				(pin passive line
					(at 0 -55.88 0)
					(length 5.08)
					(hide yes)
					(name "GND"
						(effects
							(font
								(size 1.27 1.27)
							)
						)
					)
					(number "U1"
						(effects
							(font
								(size 1.27 1.27)
							)
						)
					)
				)
				(pin passive line
					(at 0 -55.88 0)
					(length 5.08)
					(hide yes)
					(name "GND"
						(effects
							(font
								(size 1.27 1.27)
							)
						)
					)
					(number "U11"
						(effects
							(font
								(size 1.27 1.27)
							)
						)
					)
				)
				(pin passive line
					(at 0 -55.88 0)
					(length 5.08)
					(hide yes)
					(name "GND"
						(effects
							(font
								(size 1.27 1.27)
							)
						)
					)
					(number "U13"
						(effects
							(font
								(size 1.27 1.27)
							)
						)
					)
				)
				(pin passive line
					(at 0 -55.88 0)
					(length 5.08)
					(hide yes)
					(name "GND"
						(effects
							(font
								(size 1.27 1.27)
							)
						)
					)
					(number "U17"
						(effects
							(font
								(size 1.27 1.27)
							)
						)
					)
				)
				(pin passive line
					(at 0 -55.88 0)
					(length 5.08)
					(hide yes)
					(name "GND"
						(effects
							(font
								(size 1.27 1.27)
							)
						)
					)
					(number "U2"
						(effects
							(font
								(size 1.27 1.27)
							)
						)
					)
				)
				(pin passive line
					(at 0 -55.88 0)
					(length 5.08)
					(hide yes)
					(name "GND"
						(effects
							(font
								(size 1.27 1.27)
							)
						)
					)
					(number "U26"
						(effects
							(font
								(size 1.27 1.27)
							)
						)
					)
				)
				(pin passive line
					(at 0 -55.88 0)
					(length 5.08)
					(hide yes)
					(name "GND"
						(effects
							(font
								(size 1.27 1.27)
							)
						)
					)
					(number "U6"
						(effects
							(font
								(size 1.27 1.27)
							)
						)
					)
				)
				(pin passive line
					(at 0 -55.88 0)
					(length 5.08)
					(hide yes)
					(name "GND"
						(effects
							(font
								(size 1.27 1.27)
							)
						)
					)
					(number "U9"
						(effects
							(font
								(size 1.27 1.27)
							)
						)
					)
				)
				(pin passive line
					(at 0 -55.88 0)
					(length 5.08)
					(hide yes)
					(name "GND"
						(effects
							(font
								(size 1.27 1.27)
							)
						)
					)
					(number "V10"
						(effects
							(font
								(size 1.27 1.27)
							)
						)
					)
				)
				(pin passive line
					(at 0 -55.88 0)
					(length 5.08)
					(hide yes)
					(name "GND"
						(effects
							(font
								(size 1.27 1.27)
							)
						)
					)
					(number "V12"
						(effects
							(font
								(size 1.27 1.27)
							)
						)
					)
				)
				(pin passive line
					(at 0 -55.88 0)
					(length 5.08)
					(hide yes)
					(name "GND"
						(effects
							(font
								(size 1.27 1.27)
							)
						)
					)
					(number "V14"
						(effects
							(font
								(size 1.27 1.27)
							)
						)
					)
				)
				(pin passive line
					(at 0 -55.88 0)
					(length 5.08)
					(hide yes)
					(name "GND"
						(effects
							(font
								(size 1.27 1.27)
							)
						)
					)
					(number "V16"
						(effects
							(font
								(size 1.27 1.27)
							)
						)
					)
				)
				(pin passive line
					(at 0 -55.88 0)
					(length 5.08)
					(hide yes)
					(name "GND"
						(effects
							(font
								(size 1.27 1.27)
							)
						)
					)
					(number "V18"
						(effects
							(font
								(size 1.27 1.27)
							)
						)
					)
				)
				(pin passive line
					(at 0 -55.88 0)
					(length 5.08)
					(hide yes)
					(name "GND"
						(effects
							(font
								(size 1.27 1.27)
							)
						)
					)
					(number "V23"
						(effects
							(font
								(size 1.27 1.27)
							)
						)
					)
				)
				(pin passive line
					(at 0 -55.88 0)
					(length 5.08)
					(hide yes)
					(name "GND"
						(effects
							(font
								(size 1.27 1.27)
							)
						)
					)
					(number "V4"
						(effects
							(font
								(size 1.27 1.27)
							)
						)
					)
				)
				(pin passive line
					(at 0 -55.88 0)
					(length 5.08)
					(hide yes)
					(name "GND"
						(effects
							(font
								(size 1.27 1.27)
							)
						)
					)
					(number "V8"
						(effects
							(font
								(size 1.27 1.27)
							)
						)
					)
				)
				(pin passive line
					(at 0 -55.88 0)
					(length 5.08)
					(hide yes)
					(name "GND"
						(effects
							(font
								(size 1.27 1.27)
							)
						)
					)
					(number "V9"
						(effects
							(font
								(size 1.27 1.27)
							)
						)
					)
				)
				(pin passive line
					(at 0 -55.88 0)
					(length 5.08)
					(hide yes)
					(name "GND"
						(effects
							(font
								(size 1.27 1.27)
							)
						)
					)
					(number "W1"
						(effects
							(font
								(size 1.27 1.27)
							)
						)
					)
				)
				(pin passive line
					(at 0 -55.88 0)
					(length 5.08)
					(hide yes)
					(name "GND"
						(effects
							(font
								(size 1.27 1.27)
							)
						)
					)
					(number "W11"
						(effects
							(font
								(size 1.27 1.27)
							)
						)
					)
				)
				(pin passive line
					(at 0 -55.88 0)
					(length 5.08)
					(hide yes)
					(name "GND"
						(effects
							(font
								(size 1.27 1.27)
							)
						)
					)
					(number "W13"
						(effects
							(font
								(size 1.27 1.27)
							)
						)
					)
				)
				(pin passive line
					(at 0 -55.88 0)
					(length 5.08)
					(hide yes)
					(name "GND"
						(effects
							(font
								(size 1.27 1.27)
							)
						)
					)
					(number "W15"
						(effects
							(font
								(size 1.27 1.27)
							)
						)
					)
				)
				(pin passive line
					(at 0 -55.88 0)
					(length 5.08)
					(hide yes)
					(name "GND"
						(effects
							(font
								(size 1.27 1.27)
							)
						)
					)
					(number "W17"
						(effects
							(font
								(size 1.27 1.27)
							)
						)
					)
				)
				(pin passive line
					(at 0 -55.88 0)
					(length 5.08)
					(hide yes)
					(name "GND"
						(effects
							(font
								(size 1.27 1.27)
							)
						)
					)
					(number "W2"
						(effects
							(font
								(size 1.27 1.27)
							)
						)
					)
				)
				(pin passive line
					(at 0 -55.88 0)
					(length 5.08)
					(hide yes)
					(name "GND"
						(effects
							(font
								(size 1.27 1.27)
							)
						)
					)
					(number "W20"
						(effects
							(font
								(size 1.27 1.27)
							)
						)
					)
				)
				(pin passive line
					(at 0 -55.88 0)
					(length 5.08)
					(hide yes)
					(name "GND"
						(effects
							(font
								(size 1.27 1.27)
							)
						)
					)
					(number "W30"
						(effects
							(font
								(size 1.27 1.27)
							)
						)
					)
				)
				(pin passive line
					(at 0 -55.88 0)
					(length 5.08)
					(hide yes)
					(name "GND"
						(effects
							(font
								(size 1.27 1.27)
							)
						)
					)
					(number "W6"
						(effects
							(font
								(size 1.27 1.27)
							)
						)
					)
				)
				(pin passive line
					(at 0 -55.88 0)
					(length 5.08)
					(hide yes)
					(name "GND"
						(effects
							(font
								(size 1.27 1.27)
							)
						)
					)
					(number "W9"
						(effects
							(font
								(size 1.27 1.27)
							)
						)
					)
				)
				(pin passive line
					(at 0 -55.88 0)
					(length 5.08)
					(hide yes)
					(name "GND"
						(effects
							(font
								(size 1.27 1.27)
							)
						)
					)
					(number "Y17"
						(effects
							(font
								(size 1.27 1.27)
							)
						)
					)
				)
				(pin passive line
					(at 0 -55.88 0)
					(length 5.08)
					(hide yes)
					(name "GND"
						(effects
							(font
								(size 1.27 1.27)
							)
						)
					)
					(number "Y27"
						(effects
							(font
								(size 1.27 1.27)
							)
						)
					)
				)
				(pin passive line
					(at 0 -55.88 0)
					(length 5.08)
					(hide yes)
					(name "GND"
						(effects
							(font
								(size 1.27 1.27)
							)
						)
					)
					(number "Y3"
						(effects
							(font
								(size 1.27 1.27)
							)
						)
					)
				)
				(pin passive line
					(at 0 -55.88 0)
					(length 5.08)
					(hide yes)
					(name "GND"
						(effects
							(font
								(size 1.27 1.27)
							)
						)
					)
					(number "Y4"
						(effects
							(font
								(size 1.27 1.27)
							)
						)
					)
				)
				(pin passive line
					(at 0 -55.88 0)
					(length 5.08)
					(hide yes)
					(name "GND"
						(effects
							(font
								(size 1.27 1.27)
							)
						)
					)
					(number "Y7"
						(effects
							(font
								(size 1.27 1.27)
							)
						)
					)
				)
				(pin passive line
					(at 0 -55.88 0)
					(length 5.08)
					(hide yes)
					(name "GND"
						(effects
							(font
								(size 1.27 1.27)
							)
						)
					)
					(number "Y8"
						(effects
							(font
								(size 1.27 1.27)
							)
						)
					)
				)
				(pin passive line
					(at 0 -55.88 0)
					(length 5.08)
					(hide yes)
					(name "GND"
						(effects
							(font
								(size 1.27 1.27)
							)
						)
					)
					(number "Y9"
						(effects
							(font
								(size 1.27 1.27)
							)
						)
					)
				)
				(pin bidirectional line
					(at 35.56 0 180)
					(length 5.08)
					(name "VCCINT"
						(effects
							(font
								(size 1.27 1.27)
							)
						)
					)
					(number "M11"
						(effects
							(font
								(size 1.27 1.27)
							)
						)
					)
				)
				(pin passive line
					(at 35.56 0 180)
					(length 5.08)
					(hide yes)
					(name "VCCINT"
						(effects
							(font
								(size 1.27 1.27)
							)
						)
					)
					(number "M13"
						(effects
							(font
								(size 1.27 1.27)
							)
						)
					)
				)
				(pin passive line
					(at 35.56 0 180)
					(length 5.08)
					(hide yes)
					(name "VCCINT"
						(effects
							(font
								(size 1.27 1.27)
							)
						)
					)
					(number "M15"
						(effects
							(font
								(size 1.27 1.27)
							)
						)
					)
				)
				(pin passive line
					(at 35.56 0 180)
					(length 5.08)
					(hide yes)
					(name "VCCINT"
						(effects
							(font
								(size 1.27 1.27)
							)
						)
					)
					(number "M17"
						(effects
							(font
								(size 1.27 1.27)
							)
						)
					)
				)
				(pin passive line
					(at 35.56 0 180)
					(length 5.08)
					(hide yes)
					(name "VCCINT"
						(effects
							(font
								(size 1.27 1.27)
							)
						)
					)
					(number "N10"
						(effects
							(font
								(size 1.27 1.27)
							)
						)
					)
				)
				(pin passive line
					(at 35.56 0 180)
					(length 5.08)
					(hide yes)
					(name "VCCINT"
						(effects
							(font
								(size 1.27 1.27)
							)
						)
					)
					(number "N12"
						(effects
							(font
								(size 1.27 1.27)
							)
						)
					)
				)
				(pin passive line
					(at 35.56 0 180)
					(length 5.08)
					(hide yes)
					(name "VCCINT"
						(effects
							(font
								(size 1.27 1.27)
							)
						)
					)
					(number "N14"
						(effects
							(font
								(size 1.27 1.27)
							)
						)
					)
				)
				(pin passive line
					(at 35.56 0 180)
					(length 5.08)
					(hide yes)
					(name "VCCINT"
						(effects
							(font
								(size 1.27 1.27)
							)
						)
					)
					(number "N18"
						(effects
							(font
								(size 1.27 1.27)
							)
						)
					)
				)
				(pin passive line
					(at 35.56 0 180)
					(length 5.08)
					(hide yes)
					(name "VCCINT"
						(effects
							(font
								(size 1.27 1.27)
							)
						)
					)
					(number "P11"
						(effects
							(font
								(size 1.27 1.27)
							)
						)
					)
				)
				(pin passive line
					(at 35.56 0 180)
					(length 5.08)
					(hide yes)
					(name "VCCINT"
						(effects
							(font
								(size 1.27 1.27)
							)
						)
					)
					(number "P17"
						(effects
							(font
								(size 1.27 1.27)
							)
						)
					)
				)
				(pin passive line
					(at 35.56 0 180)
					(length 5.08)
					(hide yes)
					(name "VCCINT"
						(effects
							(font
								(size 1.27 1.27)
							)
						)
					)
					(number "R10"
						(effects
							(font
								(size 1.27 1.27)
							)
						)
					)
				)
				(pin passive line
					(at 35.56 0 180)
					(length 5.08)
					(hide yes)
					(name "VCCINT"
						(effects
							(font
								(size 1.27 1.27)
							)
						)
					)
					(number "R12"
						(effects
							(font
								(size 1.27 1.27)
							)
						)
					)
				)
				(pin passive line
					(at 35.56 0 180)
					(length 5.08)
					(hide yes)
					(name "VCCINT"
						(effects
							(font
								(size 1.27 1.27)
							)
						)
					)
					(number "R18"
						(effects
							(font
								(size 1.27 1.27)
							)
						)
					)
				)
				(pin passive line
					(at 35.56 0 180)
					(length 5.08)
					(hide yes)
					(name "VCCINT"
						(effects
							(font
								(size 1.27 1.27)
							)
						)
					)
					(number "T11"
						(effects
							(font
								(size 1.27 1.27)
							)
						)
					)
				)
				(pin passive line
					(at 35.56 0 180)
					(length 5.08)
					(hide yes)
					(name "VCCINT"
						(effects
							(font
								(size 1.27 1.27)
							)
						)
					)
					(number "T17"
						(effects
							(font
								(size 1.27 1.27)
							)
						)
					)
				)
				(pin passive line
					(at 35.56 0 180)
					(length 5.08)
					(hide yes)
					(name "VCCINT"
						(effects
							(font
								(size 1.27 1.27)
							)
						)
					)
					(number "U10"
						(effects
							(font
								(size 1.27 1.27)
							)
						)
					)
				)
				(pin passive line
					(at 35.56 0 180)
					(length 5.08)
					(hide yes)
					(name "VCCINT"
						(effects
							(font
								(size 1.27 1.27)
							)
						)
					)
					(number "U12"
						(effects
							(font
								(size 1.27 1.27)
							)
						)
					)
				)
				(pin passive line
					(at 35.56 0 180)
					(length 5.08)
					(hide yes)
					(name "VCCINT"
						(effects
							(font
								(size 1.27 1.27)
							)
						)
					)
					(number "U18"
						(effects
							(font
								(size 1.27 1.27)
							)
						)
					)
				)
				(pin passive line
					(at 35.56 0 180)
					(length 5.08)
					(hide yes)
					(name "VCCINT"
						(effects
							(font
								(size 1.27 1.27)
							)
						)
					)
					(number "V17"
						(effects
							(font
								(size 1.27 1.27)
							)
						)
					)
				)
				(pin passive line
					(at 35.56 0 180)
					(length 5.08)
					(hide yes)
					(name "VCCINT"
						(effects
							(font
								(size 1.27 1.27)
							)
						)
					)
					(number "W18"
						(effects
							(font
								(size 1.27 1.27)
							)
						)
					)
				)
				(pin bidirectional line
					(at 35.56 -35.56 180)
					(length 5.08)
					(name "VCCBRAM"
						(effects
							(font
								(size 1.27 1.27)
							)
						)
					)
					(number "N16"
						(effects
							(font
								(size 1.27 1.27)
							)
						)
					)
				)
				(pin passive line
					(at 35.56 -35.56 180)
					(length 5.08)
					(hide yes)
					(name "VCCBRAM"
						(effects
							(font
								(size 1.27 1.27)
							)
						)
					)
					(number "R16"
						(effects
							(font
								(size 1.27 1.27)
							)
						)
					)
				)
				(pin passive line
					(at 35.56 -35.56 180)
					(length 5.08)
					(hide yes)
					(name "VCCBRAM"
						(effects
							(font
								(size 1.27 1.27)
							)
						)
					)
					(number "U16"
						(effects
							(font
								(size 1.27 1.27)
							)
						)
					)
				)
				(pin passive line
					(at 35.56 -35.56 180)
					(length 5.08)
					(hide yes)
					(name "VCCBRAM"
						(effects
							(font
								(size 1.27 1.27)
							)
						)
					)
					(number "W16"
						(effects
							(font
								(size 1.27 1.27)
							)
						)
					)
				)
				(pin bidirectional line
					(at 35.56 -53.34 180)
					(length 5.08)
					(name "VCCBATT_0"
						(effects
							(font
								(size 1.27 1.27)
							)
						)
					)
					(number "C10"
						(effects
							(font
								(size 1.27 1.27)
							)
						)
					)
				)
			)
			(symbol "XC7K410T-2FFG900I_2_11_1"
				(rectangle
					(start -40.64 7.62)
					(end -5.08 -129.54)
					(stroke
						(width 0.254)
						(type default)
					)
					(fill
						(type background)
					)
				)
				(polyline
					(pts
						(xy -30.48 1.27) (xy -38.1 1.27) (xy -38.1 -125.73) (xy -30.48 -125.73)
					)
					(stroke
						(width 0.254)
						(type default)
					)
					(fill
						(type background)
					)
				)
				(text "BANK 13"
					(at -24.13 3.81 0)
					(effects
						(font
							(size 1.27 1.27)
							(thickness 0.15)
						)
						(justify left bottom)
					)
				)
				(pin bidirectional line
					(at 0 0 180)
					(length 5.08)
					(name "IO_0_13"
						(effects
							(font
								(size 1.27 1.27)
							)
						)
					)
					(number "Y25"
						(effects
							(font
								(size 1.27 1.27)
							)
						)
					)
				)
				(pin bidirectional line
					(at 0 -2.54 180)
					(length 5.08)
					(name "IO_L1P_T0_13"
						(effects
							(font
								(size 1.27 1.27)
							)
						)
					)
					(number "Y26"
						(effects
							(font
								(size 1.27 1.27)
							)
						)
					)
				)
				(pin bidirectional line
					(at 0 -5.08 180)
					(length 5.08)
					(name "IO_L1N_T0_13"
						(effects
							(font
								(size 1.27 1.27)
							)
						)
					)
					(number "AA26"
						(effects
							(font
								(size 1.27 1.27)
							)
						)
					)
				)
				(pin bidirectional line
					(at 0 -7.62 180)
					(length 5.08)
					(name "IO_L2P_T0_13"
						(effects
							(font
								(size 1.27 1.27)
							)
						)
					)
					(number "W27"
						(effects
							(font
								(size 1.27 1.27)
							)
						)
					)
				)
				(pin bidirectional line
					(at 0 -10.16 180)
					(length 5.08)
					(name "IO_L2N_T0_13"
						(effects
							(font
								(size 1.27 1.27)
							)
						)
					)
					(number "W28"
						(effects
							(font
								(size 1.27 1.27)
							)
						)
					)
				)
				(pin bidirectional line
					(at 0 -12.7 180)
					(length 5.08)
					(name "IO_L3P_T0_DQS_13"
						(effects
							(font
								(size 1.27 1.27)
							)
						)
					)
					(number "Y28"
						(effects
							(font
								(size 1.27 1.27)
							)
						)
					)
				)
				(pin bidirectional line
					(at 0 -15.24 180)
					(length 5.08)
					(name "IO_L3N_T0_DQS_13"
						(effects
							(font
								(size 1.27 1.27)
							)
						)
					)
					(number "AA28"
						(effects
							(font
								(size 1.27 1.27)
							)
						)
					)
				)
				(pin bidirectional line
					(at 0 -17.78 180)
					(length 5.08)
					(name "IO_L4P_T0_13"
						(effects
							(font
								(size 1.27 1.27)
							)
						)
					)
					(number "W29"
						(effects
							(font
								(size 1.27 1.27)
							)
						)
					)
				)
				(pin bidirectional line
					(at 0 -20.32 180)
					(length 5.08)
					(name "IO_L4N_T0_13"
						(effects
							(font
								(size 1.27 1.27)
							)
						)
					)
					(number "Y29"
						(effects
							(font
								(size 1.27 1.27)
							)
						)
					)
				)
				(pin bidirectional line
					(at 0 -22.86 180)
					(length 5.08)
					(name "IO_L5P_T0_13"
						(effects
							(font
								(size 1.27 1.27)
							)
						)
					)
					(number "AA27"
						(effects
							(font
								(size 1.27 1.27)
							)
						)
					)
				)
				(pin bidirectional line
					(at 0 -25.4 180)
					(length 5.08)
					(name "IO_L5N_T0_13"
						(effects
							(font
								(size 1.27 1.27)
							)
						)
					)
					(number "AB28"
						(effects
							(font
								(size 1.27 1.27)
							)
						)
					)
				)
				(pin bidirectional line
					(at 0 -27.94 180)
					(length 5.08)
					(name "IO_L6P_T0_13"
						(effects
							(font
								(size 1.27 1.27)
							)
						)
					)
					(number "AA25"
						(effects
							(font
								(size 1.27 1.27)
							)
						)
					)
				)
				(pin bidirectional line
					(at 0 -30.48 180)
					(length 5.08)
					(name "IO_L6N_T0_VREF_13"
						(effects
							(font
								(size 1.27 1.27)
							)
						)
					)
					(number "AB25"
						(effects
							(font
								(size 1.27 1.27)
							)
						)
					)
				)
				(pin bidirectional line
					(at 0 -33.02 180)
					(length 5.08)
					(name "IO_L7P_T1_13"
						(effects
							(font
								(size 1.27 1.27)
							)
						)
					)
					(number "AC29"
						(effects
							(font
								(size 1.27 1.27)
							)
						)
					)
				)
				(pin bidirectional line
					(at 0 -35.56 180)
					(length 5.08)
					(name "IO_L7N_T1_13"
						(effects
							(font
								(size 1.27 1.27)
							)
						)
					)
					(number "AC30"
						(effects
							(font
								(size 1.27 1.27)
							)
						)
					)
				)
				(pin bidirectional line
					(at 0 -38.1 180)
					(length 5.08)
					(name "IO_L8P_T1_13"
						(effects
							(font
								(size 1.27 1.27)
							)
						)
					)
					(number "Y30"
						(effects
							(font
								(size 1.27 1.27)
							)
						)
					)
				)
				(pin bidirectional line
					(at 0 -40.64 180)
					(length 5.08)
					(name "IO_L8N_T1_13"
						(effects
							(font
								(size 1.27 1.27)
							)
						)
					)
					(number "AA30"
						(effects
							(font
								(size 1.27 1.27)
							)
						)
					)
				)
				(pin bidirectional line
					(at 0 -43.18 180)
					(length 5.08)
					(name "IO_L9P_T1_DQS_13"
						(effects
							(font
								(size 1.27 1.27)
							)
						)
					)
					(number "AD29"
						(effects
							(font
								(size 1.27 1.27)
							)
						)
					)
				)
				(pin bidirectional line
					(at 0 -45.72 180)
					(length 5.08)
					(name "IO_L9N_T1_DQS_13"
						(effects
							(font
								(size 1.27 1.27)
							)
						)
					)
					(number "AE29"
						(effects
							(font
								(size 1.27 1.27)
							)
						)
					)
				)
				(pin bidirectional line
					(at 0 -48.26 180)
					(length 5.08)
					(name "IO_L10P_T1_13"
						(effects
							(font
								(size 1.27 1.27)
							)
						)
					)
					(number "AB29"
						(effects
							(font
								(size 1.27 1.27)
							)
						)
					)
				)
				(pin bidirectional line
					(at 0 -50.8 180)
					(length 5.08)
					(name "IO_L10N_T1_13"
						(effects
							(font
								(size 1.27 1.27)
							)
						)
					)
					(number "AB30"
						(effects
							(font
								(size 1.27 1.27)
							)
						)
					)
				)
				(pin bidirectional line
					(at 0 -53.34 180)
					(length 5.08)
					(name "IO_L11P_T1_SRCC_13"
						(effects
							(font
								(size 1.27 1.27)
							)
						)
					)
					(number "AD27"
						(effects
							(font
								(size 1.27 1.27)
							)
						)
					)
				)
				(pin bidirectional line
					(at 0 -55.88 180)
					(length 5.08)
					(name "IO_L11N_T1_SRCC_13"
						(effects
							(font
								(size 1.27 1.27)
							)
						)
					)
					(number "AD28"
						(effects
							(font
								(size 1.27 1.27)
							)
						)
					)
				)
				(pin bidirectional line
					(at 0 -58.42 180)
					(length 5.08)
					(name "IO_L12P_T1_MRCC_13"
						(effects
							(font
								(size 1.27 1.27)
							)
						)
					)
					(number "AB27"
						(effects
							(font
								(size 1.27 1.27)
							)
						)
					)
				)
				(pin bidirectional line
					(at 0 -60.96 180)
					(length 5.08)
					(name "IO_L12N_T1_MRCC_13"
						(effects
							(font
								(size 1.27 1.27)
							)
						)
					)
					(number "AC27"
						(effects
							(font
								(size 1.27 1.27)
							)
						)
					)
				)
				(pin bidirectional line
					(at 0 -63.5 180)
					(length 5.08)
					(name "IO_L13P_T2_MRCC_13"
						(effects
							(font
								(size 1.27 1.27)
							)
						)
					)
					(number "AG29"
						(effects
							(font
								(size 1.27 1.27)
							)
						)
					)
				)
				(pin bidirectional line
					(at 0 -66.04 180)
					(length 5.08)
					(name "IO_L13N_T2_MRCC_13"
						(effects
							(font
								(size 1.27 1.27)
							)
						)
					)
					(number "AH29"
						(effects
							(font
								(size 1.27 1.27)
							)
						)
					)
				)
				(pin bidirectional line
					(at 0 -68.58 180)
					(length 5.08)
					(name "IO_L14P_T2_SRCC_13"
						(effects
							(font
								(size 1.27 1.27)
							)
						)
					)
					(number "AE28"
						(effects
							(font
								(size 1.27 1.27)
							)
						)
					)
				)
				(pin bidirectional line
					(at 0 -71.12 180)
					(length 5.08)
					(name "IO_L14N_T2_SRCC_13"
						(effects
							(font
								(size 1.27 1.27)
							)
						)
					)
					(number "AF28"
						(effects
							(font
								(size 1.27 1.27)
							)
						)
					)
				)
				(pin bidirectional line
					(at 0 -73.66 180)
					(length 5.08)
					(name "IO_L15P_T2_DQS_13"
						(effects
							(font
								(size 1.27 1.27)
							)
						)
					)
					(number "AK29"
						(effects
							(font
								(size 1.27 1.27)
							)
						)
					)
				)
				(pin bidirectional line
					(at 0 -76.2 180)
					(length 5.08)
					(name "IO_L15N_T2_DQS_13"
						(effects
							(font
								(size 1.27 1.27)
							)
						)
					)
					(number "AK30"
						(effects
							(font
								(size 1.27 1.27)
							)
						)
					)
				)
				(pin bidirectional line
					(at 0 -78.74 180)
					(length 5.08)
					(name "IO_L16P_T2_13"
						(effects
							(font
								(size 1.27 1.27)
							)
						)
					)
					(number "AE30"
						(effects
							(font
								(size 1.27 1.27)
							)
						)
					)
				)
				(pin bidirectional line
					(at 0 -81.28 180)
					(length 5.08)
					(name "IO_L16N_T2_13"
						(effects
							(font
								(size 1.27 1.27)
							)
						)
					)
					(number "AF30"
						(effects
							(font
								(size 1.27 1.27)
							)
						)
					)
				)
				(pin bidirectional line
					(at 0 -83.82 180)
					(length 5.08)
					(name "IO_L17P_T2_13"
						(effects
							(font
								(size 1.27 1.27)
							)
						)
					)
					(number "AJ28"
						(effects
							(font
								(size 1.27 1.27)
							)
						)
					)
				)
				(pin bidirectional line
					(at 0 -86.36 180)
					(length 5.08)
					(name "IO_L17N_T2_13"
						(effects
							(font
								(size 1.27 1.27)
							)
						)
					)
					(number "AJ29"
						(effects
							(font
								(size 1.27 1.27)
							)
						)
					)
				)
				(pin bidirectional line
					(at 0 -88.9 180)
					(length 5.08)
					(name "IO_L18P_T2_13"
						(effects
							(font
								(size 1.27 1.27)
							)
						)
					)
					(number "AG30"
						(effects
							(font
								(size 1.27 1.27)
							)
						)
					)
				)
				(pin bidirectional line
					(at 0 -91.44 180)
					(length 5.08)
					(name "IO_L18N_T2_13"
						(effects
							(font
								(size 1.27 1.27)
							)
						)
					)
					(number "AH30"
						(effects
							(font
								(size 1.27 1.27)
							)
						)
					)
				)
				(pin bidirectional line
					(at 0 -93.98 180)
					(length 5.08)
					(name "IO_L19P_T3_13"
						(effects
							(font
								(size 1.27 1.27)
							)
						)
					)
					(number "AC26"
						(effects
							(font
								(size 1.27 1.27)
							)
						)
					)
				)
				(pin bidirectional line
					(at 0 -96.52 180)
					(length 5.08)
					(name "IO_L19N_T3_VREF_13"
						(effects
							(font
								(size 1.27 1.27)
							)
						)
					)
					(number "AD26"
						(effects
							(font
								(size 1.27 1.27)
							)
						)
					)
				)
				(pin bidirectional line
					(at 0 -99.06 180)
					(length 5.08)
					(name "IO_L20P_T3_13"
						(effects
							(font
								(size 1.27 1.27)
							)
						)
					)
					(number "AJ27"
						(effects
							(font
								(size 1.27 1.27)
							)
						)
					)
				)
				(pin bidirectional line
					(at 0 -101.6 180)
					(length 5.08)
					(name "IO_L20N_T3_13"
						(effects
							(font
								(size 1.27 1.27)
							)
						)
					)
					(number "AK28"
						(effects
							(font
								(size 1.27 1.27)
							)
						)
					)
				)
				(pin bidirectional line
					(at 0 -104.14 180)
					(length 5.08)
					(name "IO_L21P_T3_DQS_13"
						(effects
							(font
								(size 1.27 1.27)
							)
						)
					)
					(number "AG27"
						(effects
							(font
								(size 1.27 1.27)
							)
						)
					)
				)
				(pin bidirectional line
					(at 0 -106.68 180)
					(length 5.08)
					(name "IO_L21N_T3_DQS_13"
						(effects
							(font
								(size 1.27 1.27)
							)
						)
					)
					(number "AG28"
						(effects
							(font
								(size 1.27 1.27)
							)
						)
					)
				)
				(pin bidirectional line
					(at 0 -109.22 180)
					(length 5.08)
					(name "IO_L22P_T3_13"
						(effects
							(font
								(size 1.27 1.27)
							)
						)
					)
					(number "AH26"
						(effects
							(font
								(size 1.27 1.27)
							)
						)
					)
				)
				(pin bidirectional line
					(at 0 -111.76 180)
					(length 5.08)
					(name "IO_L22N_T3_13"
						(effects
							(font
								(size 1.27 1.27)
							)
						)
					)
					(number "AH27"
						(effects
							(font
								(size 1.27 1.27)
							)
						)
					)
				)
				(pin bidirectional line
					(at 0 -114.3 180)
					(length 5.08)
					(name "IO_L23P_T3_13"
						(effects
							(font
								(size 1.27 1.27)
							)
						)
					)
					(number "AF26"
						(effects
							(font
								(size 1.27 1.27)
							)
						)
					)
				)
				(pin bidirectional line
					(at 0 -116.84 180)
					(length 5.08)
					(name "IO_L23N_T3_13"
						(effects
							(font
								(size 1.27 1.27)
							)
						)
					)
					(number "AF27"
						(effects
							(font
								(size 1.27 1.27)
							)
						)
					)
				)
				(pin bidirectional line
					(at 0 -119.38 180)
					(length 5.08)
					(name "IO_L24P_T3_13"
						(effects
							(font
								(size 1.27 1.27)
							)
						)
					)
					(number "AJ26"
						(effects
							(font
								(size 1.27 1.27)
							)
						)
					)
				)
				(pin bidirectional line
					(at 0 -121.92 180)
					(length 5.08)
					(name "IO_L24N_T3_13"
						(effects
							(font
								(size 1.27 1.27)
							)
						)
					)
					(number "AK26"
						(effects
							(font
								(size 1.27 1.27)
							)
						)
					)
				)
				(pin bidirectional line
					(at 0 -124.46 180)
					(length 5.08)
					(name "IO_25_13"
						(effects
							(font
								(size 1.27 1.27)
							)
						)
					)
					(number "AE26"
						(effects
							(font
								(size 1.27 1.27)
							)
						)
					)
				)
			)
			(symbol "XC7K410T-2FFG900I_2_12_1"
				(rectangle
					(start -40.64 7.62)
					(end -5.08 -129.54)
					(stroke
						(width 0.254)
						(type default)
					)
					(fill
						(type background)
					)
				)
				(polyline
					(pts
						(xy -30.48 1.27) (xy -38.1 1.27) (xy -38.1 -125.73) (xy -30.48 -125.73)
					)
					(stroke
						(width 0.254)
						(type default)
					)
					(fill
						(type background)
					)
				)
				(text "BANK 15"
					(at -24.13 3.81 0)
					(effects
						(font
							(size 1.27 1.27)
							(thickness 0.15)
						)
						(justify left bottom)
					)
				)
				(pin bidirectional line
					(at 0 0 180)
					(length 5.08)
					(name "IO_0_15"
						(effects
							(font
								(size 1.27 1.27)
							)
						)
					)
					(number "M19"
						(effects
							(font
								(size 1.27 1.27)
							)
						)
					)
				)
				(pin bidirectional line
					(at 0 -2.54 180)
					(length 5.08)
					(name "IO_L1P_T0_AD0P_15"
						(effects
							(font
								(size 1.27 1.27)
							)
						)
					)
					(number "J23"
						(effects
							(font
								(size 1.27 1.27)
							)
						)
					)
				)
				(pin bidirectional line
					(at 0 -5.08 180)
					(length 5.08)
					(name "IO_L1N_T0_AD0N_15"
						(effects
							(font
								(size 1.27 1.27)
							)
						)
					)
					(number "J24"
						(effects
							(font
								(size 1.27 1.27)
							)
						)
					)
				)
				(pin bidirectional line
					(at 0 -7.62 180)
					(length 5.08)
					(name "IO_L2P_T0_AD8P_15"
						(effects
							(font
								(size 1.27 1.27)
							)
						)
					)
					(number "L22"
						(effects
							(font
								(size 1.27 1.27)
							)
						)
					)
				)
				(pin bidirectional line
					(at 0 -10.16 180)
					(length 5.08)
					(name "IO_L2N_T0_AD8N_15"
						(effects
							(font
								(size 1.27 1.27)
							)
						)
					)
					(number "L23"
						(effects
							(font
								(size 1.27 1.27)
							)
						)
					)
				)
				(pin bidirectional line
					(at 0 -12.7 180)
					(length 5.08)
					(name "IO_L3P_T0_DQS_AD1P_15"
						(effects
							(font
								(size 1.27 1.27)
							)
						)
					)
					(number "K23"
						(effects
							(font
								(size 1.27 1.27)
							)
						)
					)
				)
				(pin bidirectional line
					(at 0 -15.24 180)
					(length 5.08)
					(name "IO_L3N_T0_DQS_AD1N_15"
						(effects
							(font
								(size 1.27 1.27)
							)
						)
					)
					(number "K24"
						(effects
							(font
								(size 1.27 1.27)
							)
						)
					)
				)
				(pin bidirectional line
					(at 0 -17.78 180)
					(length 5.08)
					(name "IO_L4P_T0_AD9P_15"
						(effects
							(font
								(size 1.27 1.27)
							)
						)
					)
					(number "L21"
						(effects
							(font
								(size 1.27 1.27)
							)
						)
					)
				)
				(pin bidirectional line
					(at 0 -20.32 180)
					(length 5.08)
					(name "IO_L4N_T0_AD9N_15"
						(effects
							(font
								(size 1.27 1.27)
							)
						)
					)
					(number "K21"
						(effects
							(font
								(size 1.27 1.27)
							)
						)
					)
				)
				(pin bidirectional line
					(at 0 -22.86 180)
					(length 5.08)
					(name "IO_L5P_T0_AD2P_15"
						(effects
							(font
								(size 1.27 1.27)
							)
						)
					)
					(number "J21"
						(effects
							(font
								(size 1.27 1.27)
							)
						)
					)
				)
				(pin bidirectional line
					(at 0 -25.4 180)
					(length 5.08)
					(name "IO_L5N_T0_AD2N_15"
						(effects
							(font
								(size 1.27 1.27)
							)
						)
					)
					(number "J22"
						(effects
							(font
								(size 1.27 1.27)
							)
						)
					)
				)
				(pin bidirectional line
					(at 0 -27.94 180)
					(length 5.08)
					(name "IO_L6P_T0_15"
						(effects
							(font
								(size 1.27 1.27)
							)
						)
					)
					(number "M20"
						(effects
							(font
								(size 1.27 1.27)
							)
						)
					)
				)
				(pin bidirectional line
					(at 0 -30.48 180)
					(length 5.08)
					(name "IO_L6N_T0_VREF_15"
						(effects
							(font
								(size 1.27 1.27)
							)
						)
					)
					(number "L20"
						(effects
							(font
								(size 1.27 1.27)
							)
						)
					)
				)
				(pin bidirectional line
					(at 0 -33.02 180)
					(length 5.08)
					(name "IO_L7P_T1_AD10P_15"
						(effects
							(font
								(size 1.27 1.27)
							)
						)
					)
					(number "J29"
						(effects
							(font
								(size 1.27 1.27)
							)
						)
					)
				)
				(pin bidirectional line
					(at 0 -35.56 180)
					(length 5.08)
					(name "IO_L7N_T1_AD10N_15"
						(effects
							(font
								(size 1.27 1.27)
							)
						)
					)
					(number "H29"
						(effects
							(font
								(size 1.27 1.27)
							)
						)
					)
				)
				(pin bidirectional line
					(at 0 -38.1 180)
					(length 5.08)
					(name "IO_L8P_T1_AD3P_15"
						(effects
							(font
								(size 1.27 1.27)
							)
						)
					)
					(number "J27"
						(effects
							(font
								(size 1.27 1.27)
							)
						)
					)
				)
				(pin bidirectional line
					(at 0 -40.64 180)
					(length 5.08)
					(name "IO_L8N_T1_AD3N_15"
						(effects
							(font
								(size 1.27 1.27)
							)
						)
					)
					(number "J28"
						(effects
							(font
								(size 1.27 1.27)
							)
						)
					)
				)
				(pin bidirectional line
					(at 0 -43.18 180)
					(length 5.08)
					(name "IO_L9P_T1_DQS_AD11P_15"
						(effects
							(font
								(size 1.27 1.27)
							)
						)
					)
					(number "L30"
						(effects
							(font
								(size 1.27 1.27)
							)
						)
					)
				)
				(pin bidirectional line
					(at 0 -45.72 180)
					(length 5.08)
					(name "IO_L9N_T1_DQS_AD11N_15"
						(effects
							(font
								(size 1.27 1.27)
							)
						)
					)
					(number "K30"
						(effects
							(font
								(size 1.27 1.27)
							)
						)
					)
				)
				(pin bidirectional line
					(at 0 -48.26 180)
					(length 5.08)
					(name "IO_L10P_T1_AD4P_15"
						(effects
							(font
								(size 1.27 1.27)
							)
						)
					)
					(number "K26"
						(effects
							(font
								(size 1.27 1.27)
							)
						)
					)
				)
				(pin bidirectional line
					(at 0 -50.8 180)
					(length 5.08)
					(name "IO_L10N_T1_AD4N_15"
						(effects
							(font
								(size 1.27 1.27)
							)
						)
					)
					(number "J26"
						(effects
							(font
								(size 1.27 1.27)
							)
						)
					)
				)
				(pin bidirectional line
					(at 0 -53.34 180)
					(length 5.08)
					(name "IO_L11P_T1_SRCC_AD12P_15"
						(effects
							(font
								(size 1.27 1.27)
							)
						)
					)
					(number "L26"
						(effects
							(font
								(size 1.27 1.27)
							)
						)
					)
				)
				(pin bidirectional line
					(at 0 -55.88 180)
					(length 5.08)
					(name "IO_L11N_T1_SRCC_AD12N_15"
						(effects
							(font
								(size 1.27 1.27)
							)
						)
					)
					(number "L27"
						(effects
							(font
								(size 1.27 1.27)
							)
						)
					)
				)
				(pin bidirectional line
					(at 0 -58.42 180)
					(length 5.08)
					(name "IO_L12P_T1_MRCC_AD5P_15"
						(effects
							(font
								(size 1.27 1.27)
							)
						)
					)
					(number "L25"
						(effects
							(font
								(size 1.27 1.27)
							)
						)
					)
				)
				(pin bidirectional line
					(at 0 -60.96 180)
					(length 5.08)
					(name "IO_L12N_T1_MRCC_AD5N_15"
						(effects
							(font
								(size 1.27 1.27)
							)
						)
					)
					(number "K25"
						(effects
							(font
								(size 1.27 1.27)
							)
						)
					)
				)
				(pin bidirectional line
					(at 0 -63.5 180)
					(length 5.08)
					(name "IO_L13P_T2_MRCC_15"
						(effects
							(font
								(size 1.27 1.27)
							)
						)
					)
					(number "K28"
						(effects
							(font
								(size 1.27 1.27)
							)
						)
					)
				)
				(pin bidirectional line
					(at 0 -66.04 180)
					(length 5.08)
					(name "IO_L13N_T2_MRCC_15"
						(effects
							(font
								(size 1.27 1.27)
							)
						)
					)
					(number "K29"
						(effects
							(font
								(size 1.27 1.27)
							)
						)
					)
				)
				(pin bidirectional line
					(at 0 -68.58 180)
					(length 5.08)
					(name "IO_L14P_T2_SRCC_15"
						(effects
							(font
								(size 1.27 1.27)
							)
						)
					)
					(number "M28"
						(effects
							(font
								(size 1.27 1.27)
							)
						)
					)
				)
				(pin bidirectional line
					(at 0 -71.12 180)
					(length 5.08)
					(name "IO_L14N_T2_SRCC_15"
						(effects
							(font
								(size 1.27 1.27)
							)
						)
					)
					(number "L28"
						(effects
							(font
								(size 1.27 1.27)
							)
						)
					)
				)
				(pin bidirectional line
					(at 0 -73.66 180)
					(length 5.08)
					(name "IO_L15P_T2_DQS_15"
						(effects
							(font
								(size 1.27 1.27)
							)
						)
					)
					(number "M29"
						(effects
							(font
								(size 1.27 1.27)
							)
						)
					)
				)
				(pin bidirectional line
					(at 0 -76.2 180)
					(length 5.08)
					(name "IO_L15N_T2_DQS_ADV_B_15"
						(effects
							(font
								(size 1.27 1.27)
							)
						)
					)
					(number "M30"
						(effects
							(font
								(size 1.27 1.27)
							)
						)
					)
				)
				(pin bidirectional line
					(at 0 -78.74 180)
					(length 5.08)
					(name "IO_L16P_T2_A28_15"
						(effects
							(font
								(size 1.27 1.27)
							)
						)
					)
					(number "N27"
						(effects
							(font
								(size 1.27 1.27)
							)
						)
					)
				)
				(pin bidirectional line
					(at 0 -81.28 180)
					(length 5.08)
					(name "IO_L16N_T2_A27_15"
						(effects
							(font
								(size 1.27 1.27)
							)
						)
					)
					(number "M27"
						(effects
							(font
								(size 1.27 1.27)
							)
						)
					)
				)
				(pin bidirectional line
					(at 0 -83.82 180)
					(length 5.08)
					(name "IO_L17P_T2_A26_15"
						(effects
							(font
								(size 1.27 1.27)
							)
						)
					)
					(number "N29"
						(effects
							(font
								(size 1.27 1.27)
							)
						)
					)
				)
				(pin bidirectional line
					(at 0 -86.36 180)
					(length 5.08)
					(name "IO_L17N_T2_A25_15"
						(effects
							(font
								(size 1.27 1.27)
							)
						)
					)
					(number "N30"
						(effects
							(font
								(size 1.27 1.27)
							)
						)
					)
				)
				(pin bidirectional line
					(at 0 -88.9 180)
					(length 5.08)
					(name "IO_L18P_T2_A24_15"
						(effects
							(font
								(size 1.27 1.27)
							)
						)
					)
					(number "N25"
						(effects
							(font
								(size 1.27 1.27)
							)
						)
					)
				)
				(pin bidirectional line
					(at 0 -91.44 180)
					(length 5.08)
					(name "IO_L18N_T2_A23_15"
						(effects
							(font
								(size 1.27 1.27)
							)
						)
					)
					(number "N26"
						(effects
							(font
								(size 1.27 1.27)
							)
						)
					)
				)
				(pin bidirectional line
					(at 0 -93.98 180)
					(length 5.08)
					(name "IO_L19P_T3_A22_15"
						(effects
							(font
								(size 1.27 1.27)
							)
						)
					)
					(number "N19"
						(effects
							(font
								(size 1.27 1.27)
							)
						)
					)
				)
				(pin bidirectional line
					(at 0 -96.52 180)
					(length 5.08)
					(name "IO_L19N_T3_A21_VREF_15"
						(effects
							(font
								(size 1.27 1.27)
							)
						)
					)
					(number "N20"
						(effects
							(font
								(size 1.27 1.27)
							)
						)
					)
				)
				(pin bidirectional line
					(at 0 -99.06 180)
					(length 5.08)
					(name "IO_L20P_T3_A20_15"
						(effects
							(font
								(size 1.27 1.27)
							)
						)
					)
					(number "N21"
						(effects
							(font
								(size 1.27 1.27)
							)
						)
					)
				)
				(pin bidirectional line
					(at 0 -101.6 180)
					(length 5.08)
					(name "IO_L20N_T3_A19_15"
						(effects
							(font
								(size 1.27 1.27)
							)
						)
					)
					(number "N22"
						(effects
							(font
								(size 1.27 1.27)
							)
						)
					)
				)
				(pin bidirectional line
					(at 0 -104.14 180)
					(length 5.08)
					(name "IO_L21P_T3_DQS_15"
						(effects
							(font
								(size 1.27 1.27)
							)
						)
					)
					(number "P23"
						(effects
							(font
								(size 1.27 1.27)
							)
						)
					)
				)
				(pin bidirectional line
					(at 0 -106.68 180)
					(length 5.08)
					(name "IO_L21N_T3_DQS_A18_15"
						(effects
							(font
								(size 1.27 1.27)
							)
						)
					)
					(number "N24"
						(effects
							(font
								(size 1.27 1.27)
							)
						)
					)
				)
				(pin bidirectional line
					(at 0 -109.22 180)
					(length 5.08)
					(name "IO_L22P_T3_A17_15"
						(effects
							(font
								(size 1.27 1.27)
							)
						)
					)
					(number "P21"
						(effects
							(font
								(size 1.27 1.27)
							)
						)
					)
				)
				(pin bidirectional line
					(at 0 -111.76 180)
					(length 5.08)
					(name "IO_L22N_T3_A16_15"
						(effects
							(font
								(size 1.27 1.27)
							)
						)
					)
					(number "P22"
						(effects
							(font
								(size 1.27 1.27)
							)
						)
					)
				)
				(pin bidirectional line
					(at 0 -114.3 180)
					(length 5.08)
					(name "IO_L23P_T3_FOE_B_15"
						(effects
							(font
								(size 1.27 1.27)
							)
						)
					)
					(number "M24"
						(effects
							(font
								(size 1.27 1.27)
							)
						)
					)
				)
				(pin bidirectional line
					(at 0 -116.84 180)
					(length 5.08)
					(name "IO_L23N_T3_FWE_B_15"
						(effects
							(font
								(size 1.27 1.27)
							)
						)
					)
					(number "M25"
						(effects
							(font
								(size 1.27 1.27)
							)
						)
					)
				)
				(pin bidirectional line
					(at 0 -119.38 180)
					(length 5.08)
					(name "IO_L24P_T3_RS1_15"
						(effects
							(font
								(size 1.27 1.27)
							)
						)
					)
					(number "M22"
						(effects
							(font
								(size 1.27 1.27)
							)
						)
					)
				)
				(pin bidirectional line
					(at 0 -121.92 180)
					(length 5.08)
					(name "IO_L24N_T3_RS0_15"
						(effects
							(font
								(size 1.27 1.27)
							)
						)
					)
					(number "M23"
						(effects
							(font
								(size 1.27 1.27)
							)
						)
					)
				)
				(pin bidirectional line
					(at 0 -124.46 180)
					(length 5.08)
					(name "IO_25_15"
						(effects
							(font
								(size 1.27 1.27)
							)
						)
					)
					(number "P19"
						(effects
							(font
								(size 1.27 1.27)
							)
						)
					)
				)
			)
			(symbol "XC7K410T-2FFG900I_2_13_1"
				(rectangle
					(start -40.64 7.62)
					(end -5.08 -129.54)
					(stroke
						(width 0.254)
						(type default)
					)
					(fill
						(type background)
					)
				)
				(polyline
					(pts
						(xy -30.48 1.27) (xy -38.1 1.27) (xy -38.1 -125.73) (xy -30.48 -125.73)
					)
					(stroke
						(width 0.254)
						(type default)
					)
					(fill
						(type background)
					)
				)
				(text "BANK 17"
					(at -24.13 3.81 0)
					(effects
						(font
							(size 1.27 1.27)
							(thickness 0.15)
						)
						(justify left bottom)
					)
				)
				(pin bidirectional line
					(at 0 0 180)
					(length 5.08)
					(name "IO_0_17"
						(effects
							(font
								(size 1.27 1.27)
							)
						)
					)
					(number "G19"
						(effects
							(font
								(size 1.27 1.27)
							)
						)
					)
				)
				(pin bidirectional line
					(at 0 -2.54 180)
					(length 5.08)
					(name "IO_L1P_T0_17"
						(effects
							(font
								(size 1.27 1.27)
							)
						)
					)
					(number "K18"
						(effects
							(font
								(size 1.27 1.27)
							)
						)
					)
				)
				(pin bidirectional line
					(at 0 -5.08 180)
					(length 5.08)
					(name "IO_L1N_T0_17"
						(effects
							(font
								(size 1.27 1.27)
							)
						)
					)
					(number "J18"
						(effects
							(font
								(size 1.27 1.27)
							)
						)
					)
				)
				(pin bidirectional line
					(at 0 -7.62 180)
					(length 5.08)
					(name "IO_L2P_T0_17"
						(effects
							(font
								(size 1.27 1.27)
							)
						)
					)
					(number "H20"
						(effects
							(font
								(size 1.27 1.27)
							)
						)
					)
				)
				(pin bidirectional line
					(at 0 -10.16 180)
					(length 5.08)
					(name "IO_L2N_T0_17"
						(effects
							(font
								(size 1.27 1.27)
							)
						)
					)
					(number "G20"
						(effects
							(font
								(size 1.27 1.27)
							)
						)
					)
				)
				(pin bidirectional line
					(at 0 -12.7 180)
					(length 5.08)
					(name "IO_L3P_T0_DQS_17"
						(effects
							(font
								(size 1.27 1.27)
							)
						)
					)
					(number "J17"
						(effects
							(font
								(size 1.27 1.27)
							)
						)
					)
				)
				(pin bidirectional line
					(at 0 -15.24 180)
					(length 5.08)
					(name "IO_L3N_T0_DQS_17"
						(effects
							(font
								(size 1.27 1.27)
							)
						)
					)
					(number "H17"
						(effects
							(font
								(size 1.27 1.27)
							)
						)
					)
				)
				(pin bidirectional line
					(at 0 -17.78 180)
					(length 5.08)
					(name "IO_L4P_T0_17"
						(effects
							(font
								(size 1.27 1.27)
							)
						)
					)
					(number "J19"
						(effects
							(font
								(size 1.27 1.27)
							)
						)
					)
				)
				(pin bidirectional line
					(at 0 -20.32 180)
					(length 5.08)
					(name "IO_L4N_T0_17"
						(effects
							(font
								(size 1.27 1.27)
							)
						)
					)
					(number "H19"
						(effects
							(font
								(size 1.27 1.27)
							)
						)
					)
				)
				(pin bidirectional line
					(at 0 -22.86 180)
					(length 5.08)
					(name "IO_L5P_T0_17"
						(effects
							(font
								(size 1.27 1.27)
							)
						)
					)
					(number "L17"
						(effects
							(font
								(size 1.27 1.27)
							)
						)
					)
				)
				(pin bidirectional line
					(at 0 -25.4 180)
					(length 5.08)
					(name "IO_L5N_T0_17"
						(effects
							(font
								(size 1.27 1.27)
							)
						)
					)
					(number "L18"
						(effects
							(font
								(size 1.27 1.27)
							)
						)
					)
				)
				(pin bidirectional line
					(at 0 -27.94 180)
					(length 5.08)
					(name "IO_L6P_T0_17"
						(effects
							(font
								(size 1.27 1.27)
							)
						)
					)
					(number "K19"
						(effects
							(font
								(size 1.27 1.27)
							)
						)
					)
				)
				(pin bidirectional line
					(at 0 -30.48 180)
					(length 5.08)
					(name "IO_L6N_T0_VREF_17"
						(effects
							(font
								(size 1.27 1.27)
							)
						)
					)
					(number "K20"
						(effects
							(font
								(size 1.27 1.27)
							)
						)
					)
				)
				(pin bidirectional line
					(at 0 -33.02 180)
					(length 5.08)
					(name "IO_L7P_T1_17"
						(effects
							(font
								(size 1.27 1.27)
							)
						)
					)
					(number "H21"
						(effects
							(font
								(size 1.27 1.27)
							)
						)
					)
				)
				(pin bidirectional line
					(at 0 -35.56 180)
					(length 5.08)
					(name "IO_L7N_T1_17"
						(effects
							(font
								(size 1.27 1.27)
							)
						)
					)
					(number "H22"
						(effects
							(font
								(size 1.27 1.27)
							)
						)
					)
				)
				(pin bidirectional line
					(at 0 -38.1 180)
					(length 5.08)
					(name "IO_L8P_T1_17"
						(effects
							(font
								(size 1.27 1.27)
							)
						)
					)
					(number "D21"
						(effects
							(font
								(size 1.27 1.27)
							)
						)
					)
				)
				(pin bidirectional line
					(at 0 -40.64 180)
					(length 5.08)
					(name "IO_L8N_T1_17"
						(effects
							(font
								(size 1.27 1.27)
							)
						)
					)
					(number "C21"
						(effects
							(font
								(size 1.27 1.27)
							)
						)
					)
				)
				(pin bidirectional line
					(at 0 -43.18 180)
					(length 5.08)
					(name "IO_L9P_T1_DQS_17"
						(effects
							(font
								(size 1.27 1.27)
							)
						)
					)
					(number "G22"
						(effects
							(font
								(size 1.27 1.27)
							)
						)
					)
				)
				(pin bidirectional line
					(at 0 -45.72 180)
					(length 5.08)
					(name "IO_L9N_T1_DQS_17"
						(effects
							(font
								(size 1.27 1.27)
							)
						)
					)
					(number "F22"
						(effects
							(font
								(size 1.27 1.27)
							)
						)
					)
				)
				(pin bidirectional line
					(at 0 -48.26 180)
					(length 5.08)
					(name "IO_L10P_T1_17"
						(effects
							(font
								(size 1.27 1.27)
							)
						)
					)
					(number "D22"
						(effects
							(font
								(size 1.27 1.27)
							)
						)
					)
				)
				(pin bidirectional line
					(at 0 -50.8 180)
					(length 5.08)
					(name "IO_L10N_T1_17"
						(effects
							(font
								(size 1.27 1.27)
							)
						)
					)
					(number "C22"
						(effects
							(font
								(size 1.27 1.27)
							)
						)
					)
				)
				(pin bidirectional line
					(at 0 -53.34 180)
					(length 5.08)
					(name "IO_L11P_T1_SRCC_17"
						(effects
							(font
								(size 1.27 1.27)
							)
						)
					)
					(number "F21"
						(effects
							(font
								(size 1.27 1.27)
							)
						)
					)
				)
				(pin bidirectional line
					(at 0 -55.88 180)
					(length 5.08)
					(name "IO_L11N_T1_SRCC_17"
						(effects
							(font
								(size 1.27 1.27)
							)
						)
					)
					(number "E21"
						(effects
							(font
								(size 1.27 1.27)
							)
						)
					)
				)
				(pin bidirectional line
					(at 0 -58.42 180)
					(length 5.08)
					(name "IO_L12P_T1_MRCC_17"
						(effects
							(font
								(size 1.27 1.27)
							)
						)
					)
					(number "F20"
						(effects
							(font
								(size 1.27 1.27)
							)
						)
					)
				)
				(pin bidirectional line
					(at 0 -60.96 180)
					(length 5.08)
					(name "IO_L12N_T1_MRCC_17"
						(effects
							(font
								(size 1.27 1.27)
							)
						)
					)
					(number "E20"
						(effects
							(font
								(size 1.27 1.27)
							)
						)
					)
				)
				(pin bidirectional line
					(at 0 -63.5 180)
					(length 5.08)
					(name "IO_L13P_T2_MRCC_17"
						(effects
							(font
								(size 1.27 1.27)
							)
						)
					)
					(number "D17"
						(effects
							(font
								(size 1.27 1.27)
							)
						)
					)
				)
				(pin bidirectional line
					(at 0 -66.04 180)
					(length 5.08)
					(name "IO_L13N_T2_MRCC_17"
						(effects
							(font
								(size 1.27 1.27)
							)
						)
					)
					(number "D18"
						(effects
							(font
								(size 1.27 1.27)
							)
						)
					)
				)
				(pin bidirectional line
					(at 0 -68.58 180)
					(length 5.08)
					(name "IO_L14P_T2_SRCC_17"
						(effects
							(font
								(size 1.27 1.27)
							)
						)
					)
					(number "E19"
						(effects
							(font
								(size 1.27 1.27)
							)
						)
					)
				)
				(pin bidirectional line
					(at 0 -71.12 180)
					(length 5.08)
					(name "IO_L14N_T2_SRCC_17"
						(effects
							(font
								(size 1.27 1.27)
							)
						)
					)
					(number "D19"
						(effects
							(font
								(size 1.27 1.27)
							)
						)
					)
				)
				(pin bidirectional line
					(at 0 -73.66 180)
					(length 5.08)
					(name "IO_L15P_T2_DQS_17"
						(effects
							(font
								(size 1.27 1.27)
							)
						)
					)
					(number "D16"
						(effects
							(font
								(size 1.27 1.27)
							)
						)
					)
				)
				(pin bidirectional line
					(at 0 -76.2 180)
					(length 5.08)
					(name "IO_L15N_T2_DQS_17"
						(effects
							(font
								(size 1.27 1.27)
							)
						)
					)
					(number "C16"
						(effects
							(font
								(size 1.27 1.27)
							)
						)
					)
				)
				(pin bidirectional line
					(at 0 -78.74 180)
					(length 5.08)
					(name "IO_L16P_T2_17"
						(effects
							(font
								(size 1.27 1.27)
							)
						)
					)
					(number "G18"
						(effects
							(font
								(size 1.27 1.27)
							)
						)
					)
				)
				(pin bidirectional line
					(at 0 -81.28 180)
					(length 5.08)
					(name "IO_L16N_T2_17"
						(effects
							(font
								(size 1.27 1.27)
							)
						)
					)
					(number "F18"
						(effects
							(font
								(size 1.27 1.27)
							)
						)
					)
				)
				(pin bidirectional line
					(at 0 -83.82 180)
					(length 5.08)
					(name "IO_L17P_T2_17"
						(effects
							(font
								(size 1.27 1.27)
							)
						)
					)
					(number "C17"
						(effects
							(font
								(size 1.27 1.27)
							)
						)
					)
				)
				(pin bidirectional line
					(at 0 -86.36 180)
					(length 5.08)
					(name "IO_L17N_T2_17"
						(effects
							(font
								(size 1.27 1.27)
							)
						)
					)
					(number "B17"
						(effects
							(font
								(size 1.27 1.27)
							)
						)
					)
				)
				(pin bidirectional line
					(at 0 -88.9 180)
					(length 5.08)
					(name "IO_L18P_T2_17"
						(effects
							(font
								(size 1.27 1.27)
							)
						)
					)
					(number "G17"
						(effects
							(font
								(size 1.27 1.27)
							)
						)
					)
				)
				(pin bidirectional line
					(at 0 -91.44 180)
					(length 5.08)
					(name "IO_L18N_T2_17"
						(effects
							(font
								(size 1.27 1.27)
							)
						)
					)
					(number "F17"
						(effects
							(font
								(size 1.27 1.27)
							)
						)
					)
				)
				(pin bidirectional line
					(at 0 -93.98 180)
					(length 5.08)
					(name "IO_L19P_T3_17"
						(effects
							(font
								(size 1.27 1.27)
							)
						)
					)
					(number "C20"
						(effects
							(font
								(size 1.27 1.27)
							)
						)
					)
				)
				(pin bidirectional line
					(at 0 -96.52 180)
					(length 5.08)
					(name "IO_L19N_T3_VREF_17"
						(effects
							(font
								(size 1.27 1.27)
							)
						)
					)
					(number "B20"
						(effects
							(font
								(size 1.27 1.27)
							)
						)
					)
				)
				(pin bidirectional line
					(at 0 -99.06 180)
					(length 5.08)
					(name "IO_L20P_T3_17"
						(effects
							(font
								(size 1.27 1.27)
							)
						)
					)
					(number "A16"
						(effects
							(font
								(size 1.27 1.27)
							)
						)
					)
				)
				(pin bidirectional line
					(at 0 -101.6 180)
					(length 5.08)
					(name "IO_L20N_T3_17"
						(effects
							(font
								(size 1.27 1.27)
							)
						)
					)
					(number "A17"
						(effects
							(font
								(size 1.27 1.27)
							)
						)
					)
				)
				(pin bidirectional line
					(at 0 -104.14 180)
					(length 5.08)
					(name "IO_L21P_T3_DQS_17"
						(effects
							(font
								(size 1.27 1.27)
							)
						)
					)
					(number "A20"
						(effects
							(font
								(size 1.27 1.27)
							)
						)
					)
				)
				(pin bidirectional line
					(at 0 -106.68 180)
					(length 5.08)
					(name "IO_L21N_T3_DQS_17"
						(effects
							(font
								(size 1.27 1.27)
							)
						)
					)
					(number "A21"
						(effects
							(font
								(size 1.27 1.27)
							)
						)
					)
				)
				(pin bidirectional line
					(at 0 -109.22 180)
					(length 5.08)
					(name "IO_L22P_T3_17"
						(effects
							(font
								(size 1.27 1.27)
							)
						)
					)
					(number "B18"
						(effects
							(font
								(size 1.27 1.27)
							)
						)
					)
				)
				(pin bidirectional line
					(at 0 -111.76 180)
					(length 5.08)
					(name "IO_L22N_T3_17"
						(effects
							(font
								(size 1.27 1.27)
							)
						)
					)
					(number "A18"
						(effects
							(font
								(size 1.27 1.27)
							)
						)
					)
				)
				(pin bidirectional line
					(at 0 -114.3 180)
					(length 5.08)
					(name "IO_L23P_T3_17"
						(effects
							(font
								(size 1.27 1.27)
							)
						)
					)
					(number "B22"
						(effects
							(font
								(size 1.27 1.27)
							)
						)
					)
				)
				(pin bidirectional line
					(at 0 -116.84 180)
					(length 5.08)
					(name "IO_L23N_T3_17"
						(effects
							(font
								(size 1.27 1.27)
							)
						)
					)
					(number "A22"
						(effects
							(font
								(size 1.27 1.27)
							)
						)
					)
				)
				(pin bidirectional line
					(at 0 -119.38 180)
					(length 5.08)
					(name "IO_L24P_T3_17"
						(effects
							(font
								(size 1.27 1.27)
							)
						)
					)
					(number "C19"
						(effects
							(font
								(size 1.27 1.27)
							)
						)
					)
				)
				(pin bidirectional line
					(at 0 -121.92 180)
					(length 5.08)
					(name "IO_L24N_T3_17"
						(effects
							(font
								(size 1.27 1.27)
							)
						)
					)
					(number "B19"
						(effects
							(font
								(size 1.27 1.27)
							)
						)
					)
				)
				(pin bidirectional line
					(at 0 -124.46 180)
					(length 5.08)
					(name "IO_25_17"
						(effects
							(font
								(size 1.27 1.27)
							)
						)
					)
					(number "E18"
						(effects
							(font
								(size 1.27 1.27)
							)
						)
					)
				)
			)
			(symbol "XC7K410T-2FFG900I_2_14_1"
				(rectangle
					(start -40.64 7.62)
					(end -5.08 -129.54)
					(stroke
						(width 0.254)
						(type default)
					)
					(fill
						(type background)
					)
				)
				(polyline
					(pts
						(xy -30.48 1.27) (xy -38.1 1.27) (xy -38.1 -125.73) (xy -30.48 -125.73)
					)
					(stroke
						(width 0.254)
						(type default)
					)
					(fill
						(type background)
					)
				)
				(text "BANK 32"
					(at -24.13 3.81 0)
					(effects
						(font
							(size 1.27 1.27)
							(thickness 0.15)
						)
						(justify left bottom)
					)
				)
				(pin bidirectional line
					(at 0 0 180)
					(length 5.08)
					(name "IO_0_VRN_32"
						(effects
							(font
								(size 1.27 1.27)
							)
						)
					)
					(number "Y14"
						(effects
							(font
								(size 1.27 1.27)
							)
						)
					)
				)
				(pin bidirectional line
					(at 0 -2.54 180)
					(length 5.08)
					(name "IO_L1P_T0_32"
						(effects
							(font
								(size 1.27 1.27)
							)
						)
					)
					(number "AK16"
						(effects
							(font
								(size 1.27 1.27)
							)
						)
					)
				)
				(pin bidirectional line
					(at 0 -5.08 180)
					(length 5.08)
					(name "IO_L1N_T0_32"
						(effects
							(font
								(size 1.27 1.27)
							)
						)
					)
					(number "AK15"
						(effects
							(font
								(size 1.27 1.27)
							)
						)
					)
				)
				(pin bidirectional line
					(at 0 -7.62 180)
					(length 5.08)
					(name "IO_L2P_T0_32"
						(effects
							(font
								(size 1.27 1.27)
							)
						)
					)
					(number "AG15"
						(effects
							(font
								(size 1.27 1.27)
							)
						)
					)
				)
				(pin bidirectional line
					(at 0 -10.16 180)
					(length 5.08)
					(name "IO_L2N_T0_32"
						(effects
							(font
								(size 1.27 1.27)
							)
						)
					)
					(number "AH15"
						(effects
							(font
								(size 1.27 1.27)
							)
						)
					)
				)
				(pin bidirectional line
					(at 0 -12.7 180)
					(length 5.08)
					(name "IO_L3P_T0_DQS_32"
						(effects
							(font
								(size 1.27 1.27)
							)
						)
					)
					(number "AH16"
						(effects
							(font
								(size 1.27 1.27)
							)
						)
					)
				)
				(pin bidirectional line
					(at 0 -15.24 180)
					(length 5.08)
					(name "IO_L3N_T0_DQS_32"
						(effects
							(font
								(size 1.27 1.27)
							)
						)
					)
					(number "AJ16"
						(effects
							(font
								(size 1.27 1.27)
							)
						)
					)
				)
				(pin bidirectional line
					(at 0 -17.78 180)
					(length 5.08)
					(name "IO_L4P_T0_32"
						(effects
							(font
								(size 1.27 1.27)
							)
						)
					)
					(number "AF15"
						(effects
							(font
								(size 1.27 1.27)
							)
						)
					)
				)
				(pin bidirectional line
					(at 0 -20.32 180)
					(length 5.08)
					(name "IO_L4N_T0_32"
						(effects
							(font
								(size 1.27 1.27)
							)
						)
					)
					(number "AG14"
						(effects
							(font
								(size 1.27 1.27)
							)
						)
					)
				)
				(pin bidirectional line
					(at 0 -22.86 180)
					(length 5.08)
					(name "IO_L5P_T0_32"
						(effects
							(font
								(size 1.27 1.27)
							)
						)
					)
					(number "AH17"
						(effects
							(font
								(size 1.27 1.27)
							)
						)
					)
				)
				(pin bidirectional line
					(at 0 -25.4 180)
					(length 5.08)
					(name "IO_L5N_T0_32"
						(effects
							(font
								(size 1.27 1.27)
							)
						)
					)
					(number "AJ17"
						(effects
							(font
								(size 1.27 1.27)
							)
						)
					)
				)
				(pin bidirectional line
					(at 0 -27.94 180)
					(length 5.08)
					(name "IO_L6P_T0_32"
						(effects
							(font
								(size 1.27 1.27)
							)
						)
					)
					(number "AE16"
						(effects
							(font
								(size 1.27 1.27)
							)
						)
					)
				)
				(pin bidirectional line
					(at 0 -30.48 180)
					(length 5.08)
					(name "IO_L6N_T0_VREF_32"
						(effects
							(font
								(size 1.27 1.27)
							)
						)
					)
					(number "AF16"
						(effects
							(font
								(size 1.27 1.27)
							)
						)
					)
				)
				(pin bidirectional line
					(at 0 -33.02 180)
					(length 5.08)
					(name "IO_L7P_T1_32"
						(effects
							(font
								(size 1.27 1.27)
							)
						)
					)
					(number "AJ19"
						(effects
							(font
								(size 1.27 1.27)
							)
						)
					)
				)
				(pin bidirectional line
					(at 0 -35.56 180)
					(length 5.08)
					(name "IO_L7N_T1_32"
						(effects
							(font
								(size 1.27 1.27)
							)
						)
					)
					(number "AK19"
						(effects
							(font
								(size 1.27 1.27)
							)
						)
					)
				)
				(pin bidirectional line
					(at 0 -38.1 180)
					(length 5.08)
					(name "IO_L8P_T1_32"
						(effects
							(font
								(size 1.27 1.27)
							)
						)
					)
					(number "AG19"
						(effects
							(font
								(size 1.27 1.27)
							)
						)
					)
				)
				(pin bidirectional line
					(at 0 -40.64 180)
					(length 5.08)
					(name "IO_L8N_T1_32"
						(effects
							(font
								(size 1.27 1.27)
							)
						)
					)
					(number "AH19"
						(effects
							(font
								(size 1.27 1.27)
							)
						)
					)
				)
				(pin bidirectional line
					(at 0 -43.18 180)
					(length 5.08)
					(name "IO_L9P_T1_DQS_32"
						(effects
							(font
								(size 1.27 1.27)
							)
						)
					)
					(number "AJ18"
						(effects
							(font
								(size 1.27 1.27)
							)
						)
					)
				)
				(pin bidirectional line
					(at 0 -45.72 180)
					(length 5.08)
					(name "IO_L9N_T1_DQS_32"
						(effects
							(font
								(size 1.27 1.27)
							)
						)
					)
					(number "AK18"
						(effects
							(font
								(size 1.27 1.27)
							)
						)
					)
				)
				(pin bidirectional line
					(at 0 -48.26 180)
					(length 5.08)
					(name "IO_L10P_T1_32"
						(effects
							(font
								(size 1.27 1.27)
							)
						)
					)
					(number "AD19"
						(effects
							(font
								(size 1.27 1.27)
							)
						)
					)
				)
				(pin bidirectional line
					(at 0 -50.8 180)
					(length 5.08)
					(name "IO_L10N_T1_32"
						(effects
							(font
								(size 1.27 1.27)
							)
						)
					)
					(number "AE19"
						(effects
							(font
								(size 1.27 1.27)
							)
						)
					)
				)
				(pin bidirectional line
					(at 0 -53.34 180)
					(length 5.08)
					(name "IO_L11P_T1_SRCC_32"
						(effects
							(font
								(size 1.27 1.27)
							)
						)
					)
					(number "AF18"
						(effects
							(font
								(size 1.27 1.27)
							)
						)
					)
				)
				(pin bidirectional line
					(at 0 -55.88 180)
					(length 5.08)
					(name "IO_L11N_T1_SRCC_32"
						(effects
							(font
								(size 1.27 1.27)
							)
						)
					)
					(number "AG18"
						(effects
							(font
								(size 1.27 1.27)
							)
						)
					)
				)
				(pin bidirectional line
					(at 0 -58.42 180)
					(length 5.08)
					(name "IO_L12P_T1_MRCC_32"
						(effects
							(font
								(size 1.27 1.27)
							)
						)
					)
					(number "AF17"
						(effects
							(font
								(size 1.27 1.27)
							)
						)
					)
				)
				(pin bidirectional line
					(at 0 -60.96 180)
					(length 5.08)
					(name "IO_L12N_T1_MRCC_32"
						(effects
							(font
								(size 1.27 1.27)
							)
						)
					)
					(number "AG17"
						(effects
							(font
								(size 1.27 1.27)
							)
						)
					)
				)
				(pin bidirectional line
					(at 0 -63.5 180)
					(length 5.08)
					(name "IO_L13P_T2_MRCC_32"
						(effects
							(font
								(size 1.27 1.27)
							)
						)
					)
					(number "AD18"
						(effects
							(font
								(size 1.27 1.27)
							)
						)
					)
				)
				(pin bidirectional line
					(at 0 -66.04 180)
					(length 5.08)
					(name "IO_L13N_T2_MRCC_32"
						(effects
							(font
								(size 1.27 1.27)
							)
						)
					)
					(number "AE18"
						(effects
							(font
								(size 1.27 1.27)
							)
						)
					)
				)
				(pin bidirectional line
					(at 0 -68.58 180)
					(length 5.08)
					(name "IO_L14P_T2_SRCC_32"
						(effects
							(font
								(size 1.27 1.27)
							)
						)
					)
					(number "AD17"
						(effects
							(font
								(size 1.27 1.27)
							)
						)
					)
				)
				(pin bidirectional line
					(at 0 -71.12 180)
					(length 5.08)
					(name "IO_L14N_T2_SRCC_32"
						(effects
							(font
								(size 1.27 1.27)
							)
						)
					)
					(number "AD16"
						(effects
							(font
								(size 1.27 1.27)
							)
						)
					)
				)
				(pin bidirectional line
					(at 0 -73.66 180)
					(length 5.08)
					(name "IO_L15P_T2_DQS_32"
						(effects
							(font
								(size 1.27 1.27)
							)
						)
					)
					(number "Y19"
						(effects
							(font
								(size 1.27 1.27)
							)
						)
					)
				)
				(pin bidirectional line
					(at 0 -76.2 180)
					(length 5.08)
					(name "IO_L15N_T2_DQS_32"
						(effects
							(font
								(size 1.27 1.27)
							)
						)
					)
					(number "Y18"
						(effects
							(font
								(size 1.27 1.27)
							)
						)
					)
				)
				(pin bidirectional line
					(at 0 -78.74 180)
					(length 5.08)
					(name "IO_L16P_T2_32"
						(effects
							(font
								(size 1.27 1.27)
							)
						)
					)
					(number "AA18"
						(effects
							(font
								(size 1.27 1.27)
							)
						)
					)
				)
				(pin bidirectional line
					(at 0 -81.28 180)
					(length 5.08)
					(name "IO_L16N_T2_32"
						(effects
							(font
								(size 1.27 1.27)
							)
						)
					)
					(number "AB18"
						(effects
							(font
								(size 1.27 1.27)
							)
						)
					)
				)
				(pin bidirectional line
					(at 0 -83.82 180)
					(length 5.08)
					(name "IO_L17P_T2_32"
						(effects
							(font
								(size 1.27 1.27)
							)
						)
					)
					(number "AB19"
						(effects
							(font
								(size 1.27 1.27)
							)
						)
					)
				)
				(pin bidirectional line
					(at 0 -86.36 180)
					(length 5.08)
					(name "IO_L17N_T2_32"
						(effects
							(font
								(size 1.27 1.27)
							)
						)
					)
					(number "AC19"
						(effects
							(font
								(size 1.27 1.27)
							)
						)
					)
				)
				(pin bidirectional line
					(at 0 -88.9 180)
					(length 5.08)
					(name "IO_L18P_T2_32"
						(effects
							(font
								(size 1.27 1.27)
							)
						)
					)
					(number "AB17"
						(effects
							(font
								(size 1.27 1.27)
							)
						)
					)
				)
				(pin bidirectional line
					(at 0 -91.44 180)
					(length 5.08)
					(name "IO_L18N_T2_32"
						(effects
							(font
								(size 1.27 1.27)
							)
						)
					)
					(number "AC17"
						(effects
							(font
								(size 1.27 1.27)
							)
						)
					)
				)
				(pin bidirectional line
					(at 0 -93.98 180)
					(length 5.08)
					(name "IO_L19P_T3_32"
						(effects
							(font
								(size 1.27 1.27)
							)
						)
					)
					(number "AE15"
						(effects
							(font
								(size 1.27 1.27)
							)
						)
					)
				)
				(pin bidirectional line
					(at 0 -96.52 180)
					(length 5.08)
					(name "IO_L19N_T3_VREF_32"
						(effects
							(font
								(size 1.27 1.27)
							)
						)
					)
					(number "AE14"
						(effects
							(font
								(size 1.27 1.27)
							)
						)
					)
				)
				(pin bidirectional line
					(at 0 -99.06 180)
					(length 5.08)
					(name "IO_L20P_T3_32"
						(effects
							(font
								(size 1.27 1.27)
							)
						)
					)
					(number "AA15"
						(effects
							(font
								(size 1.27 1.27)
							)
						)
					)
				)
				(pin bidirectional line
					(at 0 -101.6 180)
					(length 5.08)
					(name "IO_L20N_T3_32"
						(effects
							(font
								(size 1.27 1.27)
							)
						)
					)
					(number "AB15"
						(effects
							(font
								(size 1.27 1.27)
							)
						)
					)
				)
				(pin bidirectional line
					(at 0 -104.14 180)
					(length 5.08)
					(name "IO_L21P_T3_DQS_32"
						(effects
							(font
								(size 1.27 1.27)
							)
						)
					)
					(number "AC16"
						(effects
							(font
								(size 1.27 1.27)
							)
						)
					)
				)
				(pin bidirectional line
					(at 0 -106.68 180)
					(length 5.08)
					(name "IO_L21N_T3_DQS_32"
						(effects
							(font
								(size 1.27 1.27)
							)
						)
					)
					(number "AC15"
						(effects
							(font
								(size 1.27 1.27)
							)
						)
					)
				)
				(pin bidirectional line
					(at 0 -109.22 180)
					(length 5.08)
					(name "IO_L22P_T3_32"
						(effects
							(font
								(size 1.27 1.27)
							)
						)
					)
					(number "AC14"
						(effects
							(font
								(size 1.27 1.27)
							)
						)
					)
				)
				(pin bidirectional line
					(at 0 -111.76 180)
					(length 5.08)
					(name "IO_L22N_T3_32"
						(effects
							(font
								(size 1.27 1.27)
							)
						)
					)
					(number "AD14"
						(effects
							(font
								(size 1.27 1.27)
							)
						)
					)
				)
				(pin bidirectional line
					(at 0 -114.3 180)
					(length 5.08)
					(name "IO_L23P_T3_32"
						(effects
							(font
								(size 1.27 1.27)
							)
						)
					)
					(number "AA17"
						(effects
							(font
								(size 1.27 1.27)
							)
						)
					)
				)
				(pin bidirectional line
					(at 0 -116.84 180)
					(length 5.08)
					(name "IO_L23N_T3_32"
						(effects
							(font
								(size 1.27 1.27)
							)
						)
					)
					(number "AA16"
						(effects
							(font
								(size 1.27 1.27)
							)
						)
					)
				)
				(pin bidirectional line
					(at 0 -119.38 180)
					(length 5.08)
					(name "IO_L24P_T3_32"
						(effects
							(font
								(size 1.27 1.27)
							)
						)
					)
					(number "Y16"
						(effects
							(font
								(size 1.27 1.27)
							)
						)
					)
				)
				(pin bidirectional line
					(at 0 -121.92 180)
					(length 5.08)
					(name "IO_L24N_T3_32"
						(effects
							(font
								(size 1.27 1.27)
							)
						)
					)
					(number "Y15"
						(effects
							(font
								(size 1.27 1.27)
							)
						)
					)
				)
				(pin bidirectional line
					(at 0 -124.46 180)
					(length 5.08)
					(name "IO_25_VRP_32"
						(effects
							(font
								(size 1.27 1.27)
							)
						)
					)
					(number "AB14"
						(effects
							(font
								(size 1.27 1.27)
							)
						)
					)
				)
			)
			(symbol "XC7K410T-2FFG900I_2_15_1"
				(rectangle
					(start -40.64 7.62)
					(end -5.08 -129.54)
					(stroke
						(width 0.254)
						(type default)
					)
					(fill
						(type background)
					)
				)
				(polyline
					(pts
						(xy -30.48 1.27) (xy -38.1 1.27) (xy -38.1 -125.73) (xy -30.48 -125.73)
					)
					(stroke
						(width 0.254)
						(type default)
					)
					(fill
						(type background)
					)
				)
				(text "BANK 34"
					(at -24.13 3.81 0)
					(effects
						(font
							(size 1.27 1.27)
							(thickness 0.15)
						)
						(justify left bottom)
					)
				)
				(pin bidirectional line
					(at 0 0 180)
					(length 5.08)
					(name "IO_0_VRN_34"
						(effects
							(font
								(size 1.27 1.27)
							)
						)
					)
					(number "AC6"
						(effects
							(font
								(size 1.27 1.27)
							)
						)
					)
				)
				(pin bidirectional line
					(at 0 -2.54 180)
					(length 5.08)
					(name "IO_L1P_T0_34"
						(effects
							(font
								(size 1.27 1.27)
							)
						)
					)
					(number "AD4"
						(effects
							(font
								(size 1.27 1.27)
							)
						)
					)
				)
				(pin bidirectional line
					(at 0 -5.08 180)
					(length 5.08)
					(name "IO_L1N_T0_34"
						(effects
							(font
								(size 1.27 1.27)
							)
						)
					)
					(number "AD3"
						(effects
							(font
								(size 1.27 1.27)
							)
						)
					)
				)
				(pin bidirectional line
					(at 0 -7.62 180)
					(length 5.08)
					(name "IO_L2P_T0_34"
						(effects
							(font
								(size 1.27 1.27)
							)
						)
					)
					(number "AC2"
						(effects
							(font
								(size 1.27 1.27)
							)
						)
					)
				)
				(pin bidirectional line
					(at 0 -10.16 180)
					(length 5.08)
					(name "IO_L2N_T0_34"
						(effects
							(font
								(size 1.27 1.27)
							)
						)
					)
					(number "AC1"
						(effects
							(font
								(size 1.27 1.27)
							)
						)
					)
				)
				(pin bidirectional line
					(at 0 -12.7 180)
					(length 5.08)
					(name "IO_L3P_T0_DQS_34"
						(effects
							(font
								(size 1.27 1.27)
							)
						)
					)
					(number "AD2"
						(effects
							(font
								(size 1.27 1.27)
							)
						)
					)
				)
				(pin bidirectional line
					(at 0 -15.24 180)
					(length 5.08)
					(name "IO_L3N_T0_DQS_34"
						(effects
							(font
								(size 1.27 1.27)
							)
						)
					)
					(number "AD1"
						(effects
							(font
								(size 1.27 1.27)
							)
						)
					)
				)
				(pin bidirectional line
					(at 0 -17.78 180)
					(length 5.08)
					(name "IO_L4P_T0_34"
						(effects
							(font
								(size 1.27 1.27)
							)
						)
					)
					(number "AC5"
						(effects
							(font
								(size 1.27 1.27)
							)
						)
					)
				)
				(pin bidirectional line
					(at 0 -20.32 180)
					(length 5.08)
					(name "IO_L4N_T0_34"
						(effects
							(font
								(size 1.27 1.27)
							)
						)
					)
					(number "AC4"
						(effects
							(font
								(size 1.27 1.27)
							)
						)
					)
				)
				(pin bidirectional line
					(at 0 -22.86 180)
					(length 5.08)
					(name "IO_L5P_T0_34"
						(effects
							(font
								(size 1.27 1.27)
							)
						)
					)
					(number "AD6"
						(effects
							(font
								(size 1.27 1.27)
							)
						)
					)
				)
				(pin bidirectional line
					(at 0 -25.4 180)
					(length 5.08)
					(name "IO_L5N_T0_34"
						(effects
							(font
								(size 1.27 1.27)
							)
						)
					)
					(number "AE6"
						(effects
							(font
								(size 1.27 1.27)
							)
						)
					)
				)
				(pin bidirectional line
					(at 0 -27.94 180)
					(length 5.08)
					(name "IO_L6P_T0_34"
						(effects
							(font
								(size 1.27 1.27)
							)
						)
					)
					(number "AC7"
						(effects
							(font
								(size 1.27 1.27)
							)
						)
					)
				)
				(pin bidirectional line
					(at 0 -30.48 180)
					(length 5.08)
					(name "IO_L6N_T0_VREF_34"
						(effects
							(font
								(size 1.27 1.27)
							)
						)
					)
					(number "AD7"
						(effects
							(font
								(size 1.27 1.27)
							)
						)
					)
				)
				(pin bidirectional line
					(at 0 -33.02 180)
					(length 5.08)
					(name "IO_L7P_T1_34"
						(effects
							(font
								(size 1.27 1.27)
							)
						)
					)
					(number "AF3"
						(effects
							(font
								(size 1.27 1.27)
							)
						)
					)
				)
				(pin bidirectional line
					(at 0 -35.56 180)
					(length 5.08)
					(name "IO_L7N_T1_34"
						(effects
							(font
								(size 1.27 1.27)
							)
						)
					)
					(number "AF2"
						(effects
							(font
								(size 1.27 1.27)
							)
						)
					)
				)
				(pin bidirectional line
					(at 0 -38.1 180)
					(length 5.08)
					(name "IO_L8P_T1_34"
						(effects
							(font
								(size 1.27 1.27)
							)
						)
					)
					(number "AE1"
						(effects
							(font
								(size 1.27 1.27)
							)
						)
					)
				)
				(pin bidirectional line
					(at 0 -40.64 180)
					(length 5.08)
					(name "IO_L8N_T1_34"
						(effects
							(font
								(size 1.27 1.27)
							)
						)
					)
					(number "AF1"
						(effects
							(font
								(size 1.27 1.27)
							)
						)
					)
				)
				(pin bidirectional line
					(at 0 -43.18 180)
					(length 5.08)
					(name "IO_L9P_T1_DQS_34"
						(effects
							(font
								(size 1.27 1.27)
							)
						)
					)
					(number "AG4"
						(effects
							(font
								(size 1.27 1.27)
							)
						)
					)
				)
				(pin bidirectional line
					(at 0 -45.72 180)
					(length 5.08)
					(name "IO_L9N_T1_DQS_34"
						(effects
							(font
								(size 1.27 1.27)
							)
						)
					)
					(number "AG3"
						(effects
							(font
								(size 1.27 1.27)
							)
						)
					)
				)
				(pin bidirectional line
					(at 0 -48.26 180)
					(length 5.08)
					(name "IO_L10P_T1_34"
						(effects
							(font
								(size 1.27 1.27)
							)
						)
					)
					(number "AE4"
						(effects
							(font
								(size 1.27 1.27)
							)
						)
					)
				)
				(pin bidirectional line
					(at 0 -50.8 180)
					(length 5.08)
					(name "IO_L10N_T1_34"
						(effects
							(font
								(size 1.27 1.27)
							)
						)
					)
					(number "AE3"
						(effects
							(font
								(size 1.27 1.27)
							)
						)
					)
				)
				(pin bidirectional line
					(at 0 -53.34 180)
					(length 5.08)
					(name "IO_L11P_T1_SRCC_34"
						(effects
							(font
								(size 1.27 1.27)
							)
						)
					)
					(number "AE5"
						(effects
							(font
								(size 1.27 1.27)
							)
						)
					)
				)
				(pin bidirectional line
					(at 0 -55.88 180)
					(length 5.08)
					(name "IO_L11N_T1_SRCC_34"
						(effects
							(font
								(size 1.27 1.27)
							)
						)
					)
					(number "AF5"
						(effects
							(font
								(size 1.27 1.27)
							)
						)
					)
				)
				(pin bidirectional line
					(at 0 -58.42 180)
					(length 5.08)
					(name "IO_L12P_T1_MRCC_34"
						(effects
							(font
								(size 1.27 1.27)
							)
						)
					)
					(number "AF6"
						(effects
							(font
								(size 1.27 1.27)
							)
						)
					)
				)
				(pin bidirectional line
					(at 0 -60.96 180)
					(length 5.08)
					(name "IO_L12N_T1_MRCC_34"
						(effects
							(font
								(size 1.27 1.27)
							)
						)
					)
					(number "AG5"
						(effects
							(font
								(size 1.27 1.27)
							)
						)
					)
				)
				(pin bidirectional line
					(at 0 -63.5 180)
					(length 5.08)
					(name "IO_L13P_T2_MRCC_34"
						(effects
							(font
								(size 1.27 1.27)
							)
						)
					)
					(number "AH4"
						(effects
							(font
								(size 1.27 1.27)
							)
						)
					)
				)
				(pin bidirectional line
					(at 0 -66.04 180)
					(length 5.08)
					(name "IO_L13N_T2_MRCC_34"
						(effects
							(font
								(size 1.27 1.27)
							)
						)
					)
					(number "AJ4"
						(effects
							(font
								(size 1.27 1.27)
							)
						)
					)
				)
				(pin bidirectional line
					(at 0 -68.58 180)
					(length 5.08)
					(name "IO_L14P_T2_SRCC_34"
						(effects
							(font
								(size 1.27 1.27)
							)
						)
					)
					(number "AH6"
						(effects
							(font
								(size 1.27 1.27)
							)
						)
					)
				)
				(pin bidirectional line
					(at 0 -71.12 180)
					(length 5.08)
					(name "IO_L14N_T2_SRCC_34"
						(effects
							(font
								(size 1.27 1.27)
							)
						)
					)
					(number "AH5"
						(effects
							(font
								(size 1.27 1.27)
							)
						)
					)
				)
				(pin bidirectional line
					(at 0 -73.66 180)
					(length 5.08)
					(name "IO_L15P_T2_DQS_34"
						(effects
							(font
								(size 1.27 1.27)
							)
						)
					)
					(number "AG2"
						(effects
							(font
								(size 1.27 1.27)
							)
						)
					)
				)
				(pin bidirectional line
					(at 0 -76.2 180)
					(length 5.08)
					(name "IO_L15N_T2_DQS_34"
						(effects
							(font
								(size 1.27 1.27)
							)
						)
					)
					(number "AH1"
						(effects
							(font
								(size 1.27 1.27)
							)
						)
					)
				)
				(pin bidirectional line
					(at 0 -78.74 180)
					(length 5.08)
					(name "IO_L16P_T2_34"
						(effects
							(font
								(size 1.27 1.27)
							)
						)
					)
					(number "AH2"
						(effects
							(font
								(size 1.27 1.27)
							)
						)
					)
				)
				(pin bidirectional line
					(at 0 -81.28 180)
					(length 5.08)
					(name "IO_L16N_T2_34"
						(effects
							(font
								(size 1.27 1.27)
							)
						)
					)
					(number "AJ2"
						(effects
							(font
								(size 1.27 1.27)
							)
						)
					)
				)
				(pin bidirectional line
					(at 0 -83.82 180)
					(length 5.08)
					(name "IO_L17P_T2_34"
						(effects
							(font
								(size 1.27 1.27)
							)
						)
					)
					(number "AJ1"
						(effects
							(font
								(size 1.27 1.27)
							)
						)
					)
				)
				(pin bidirectional line
					(at 0 -86.36 180)
					(length 5.08)
					(name "IO_L17N_T2_34"
						(effects
							(font
								(size 1.27 1.27)
							)
						)
					)
					(number "AK1"
						(effects
							(font
								(size 1.27 1.27)
							)
						)
					)
				)
				(pin bidirectional line
					(at 0 -88.9 180)
					(length 5.08)
					(name "IO_L18P_T2_34"
						(effects
							(font
								(size 1.27 1.27)
							)
						)
					)
					(number "AJ3"
						(effects
							(font
								(size 1.27 1.27)
							)
						)
					)
				)
				(pin bidirectional line
					(at 0 -91.44 180)
					(length 5.08)
					(name "IO_L18N_T2_34"
						(effects
							(font
								(size 1.27 1.27)
							)
						)
					)
					(number "AK3"
						(effects
							(font
								(size 1.27 1.27)
							)
						)
					)
				)
				(pin bidirectional line
					(at 0 -93.98 180)
					(length 5.08)
					(name "IO_L19P_T3_34"
						(effects
							(font
								(size 1.27 1.27)
							)
						)
					)
					(number "AF8"
						(effects
							(font
								(size 1.27 1.27)
							)
						)
					)
				)
				(pin bidirectional line
					(at 0 -96.52 180)
					(length 5.08)
					(name "IO_L19N_T3_VREF_34"
						(effects
							(font
								(size 1.27 1.27)
							)
						)
					)
					(number "AG8"
						(effects
							(font
								(size 1.27 1.27)
							)
						)
					)
				)
				(pin bidirectional line
					(at 0 -99.06 180)
					(length 5.08)
					(name "IO_L20P_T3_34"
						(effects
							(font
								(size 1.27 1.27)
							)
						)
					)
					(number "AF7"
						(effects
							(font
								(size 1.27 1.27)
							)
						)
					)
				)
				(pin bidirectional line
					(at 0 -101.6 180)
					(length 5.08)
					(name "IO_L20N_T3_34"
						(effects
							(font
								(size 1.27 1.27)
							)
						)
					)
					(number "AG7"
						(effects
							(font
								(size 1.27 1.27)
							)
						)
					)
				)
				(pin bidirectional line
					(at 0 -104.14 180)
					(length 5.08)
					(name "IO_L21P_T3_DQS_34"
						(effects
							(font
								(size 1.27 1.27)
							)
						)
					)
					(number "AH7"
						(effects
							(font
								(size 1.27 1.27)
							)
						)
					)
				)
				(pin bidirectional line
					(at 0 -106.68 180)
					(length 5.08)
					(name "IO_L21N_T3_DQS_34"
						(effects
							(font
								(size 1.27 1.27)
							)
						)
					)
					(number "AJ7"
						(effects
							(font
								(size 1.27 1.27)
							)
						)
					)
				)
				(pin bidirectional line
					(at 0 -109.22 180)
					(length 5.08)
					(name "IO_L22P_T3_34"
						(effects
							(font
								(size 1.27 1.27)
							)
						)
					)
					(number "AJ6"
						(effects
							(font
								(size 1.27 1.27)
							)
						)
					)
				)
				(pin bidirectional line
					(at 0 -111.76 180)
					(length 5.08)
					(name "IO_L22N_T3_34"
						(effects
							(font
								(size 1.27 1.27)
							)
						)
					)
					(number "AK6"
						(effects
							(font
								(size 1.27 1.27)
							)
						)
					)
				)
				(pin bidirectional line
					(at 0 -114.3 180)
					(length 5.08)
					(name "IO_L23P_T3_34"
						(effects
							(font
								(size 1.27 1.27)
							)
						)
					)
					(number "AJ8"
						(effects
							(font
								(size 1.27 1.27)
							)
						)
					)
				)
				(pin bidirectional line
					(at 0 -116.84 180)
					(length 5.08)
					(name "IO_L23N_T3_34"
						(effects
							(font
								(size 1.27 1.27)
							)
						)
					)
					(number "AK8"
						(effects
							(font
								(size 1.27 1.27)
							)
						)
					)
				)
				(pin bidirectional line
					(at 0 -119.38 180)
					(length 5.08)
					(name "IO_L24P_T3_34"
						(effects
							(font
								(size 1.27 1.27)
							)
						)
					)
					(number "AK5"
						(effects
							(font
								(size 1.27 1.27)
							)
						)
					)
				)
				(pin bidirectional line
					(at 0 -121.92 180)
					(length 5.08)
					(name "IO_L24N_T3_34"
						(effects
							(font
								(size 1.27 1.27)
							)
						)
					)
					(number "AK4"
						(effects
							(font
								(size 1.27 1.27)
							)
						)
					)
				)
				(pin bidirectional line
					(at 0 -124.46 180)
					(length 5.08)
					(name "IO_25_VRP_34"
						(effects
							(font
								(size 1.27 1.27)
							)
						)
					)
					(number "AB7"
						(effects
							(font
								(size 1.27 1.27)
							)
						)
					)
				)
			)
		)
	(symbol "XC7K410T-2FFG900I_3"
			(exclude_from_sim no)
			(in_bom yes)
			(on_board yes)
			(property "Reference" "U"
				(at 82.55 -2.54 0)
				(effects
					(font
						(size 1.27 1.27)
						(thickness 0.15)
					)
					(justify left bottom)
				)
			)
			(property "Value" "XC7K410T-2FFG900I"
				(at 82.55 -7.62 0)
				(effects
					(font
						(size 1.27 1.27)
						(thickness 0.15)
					)
					(justify left bottom)
					(hide yes)
				)
			)
			(property "Footprint" "antmicro-footprints:BGA-900_31x31mm_Layout30x30_P1x1mm_FFG900"
				(at 82.55 -10.16 0)
				(effects
					(font
						(size 1.27 1.27)
						(thickness 0.15)
					)
					(justify left bottom)
					(hide yes)
				)
			)
			(property "Datasheet" "https://eu.mouser.com/datasheet/2/903/ds180_7Series_Overview-1591537.pdf"
				(at 82.55 -12.7 0)
				(effects
					(font
						(size 1.27 1.27)
						(thickness 0.15)
					)
					(justify left bottom)
					(hide yes)
				)
			)
			(property "Description" "FPGA, Kintex-7, MMCM, PLL, 350 I/O's, 710 MHz, 406720 Cells, 970 mV to 1.03 V, FCBGA-900"
				(at 0 0 0)
				(effects
					(font
						(size 1.27 1.27)
					)
					(hide yes)
				)
			)
			(property "MPN" "XC7K410T-2FFG900I"
				(at 82.55 -5.08 0)
				(effects
					(font
						(size 1.27 1.27)
						(thickness 0.15)
					)
					(justify left bottom)
				)
			)
			(property "Manufacturer" "AMD-Xilinx"
				(at 82.55 -15.24 0)
				(effects
					(font
						(size 1.27 1.27)
						(thickness 0.15)
					)
					(justify left bottom)
					(hide yes)
				)
			)
			(property "Author" "Antmicro"
				(at 82.55 -17.78 0)
				(effects
					(font
						(size 1.27 1.27)
						(thickness 0.15)
					)
					(justify left bottom)
					(hide yes)
				)
			)
			(property "License" "Apache-2.0"
				(at 82.55 -20.32 0)
				(effects
					(font
						(size 1.27 1.27)
						(thickness 0.15)
					)
					(justify left bottom)
					(hide yes)
				)
			)
			(property "ki_locked" ""
				(at 0 0 0)
				(effects
					(font
						(size 1.27 1.27)
					)
				)
			)
			(property "ki_keywords" "SMT, MICROCONTROLLER, IC, FPGA"
				(at 0 0 0)
				(effects
					(font
						(size 1.27 1.27)
					)
					(hide yes)
				)
			)
			(symbol "XC7K410T-2FFG900I_3_1_1"
				(rectangle
					(start 5.08 5.08)
					(end 50.8 -130.81)
					(stroke
						(width 0.254)
						(type default)
					)
					(fill
						(type background)
					)
				)
				(text "BANK 12"
					(at 15.24 2.54 0)
					(effects
						(font
							(size 1.27 1.27)
							(thickness 0.15)
						)
						(justify left bottom)
					)
				)
				(text "BANK 13"
					(at 31.75 2.54 0)
					(effects
						(font
							(size 1.27 1.27)
							(thickness 0.15)
						)
						(justify left bottom)
					)
				)
				(pin bidirectional line
					(at 0 0 0)
					(length 5.08)
					(name "VCCO_12"
						(effects
							(font
								(size 1.27 1.27)
							)
						)
					)
					(number "AC23"
						(effects
							(font
								(size 1.27 1.27)
							)
						)
					)
				)
				(pin passive line
					(at 0 0 0)
					(length 5.08)
					(hide yes)
					(name "VCCO_12"
						(effects
							(font
								(size 1.27 1.27)
							)
						)
					)
					(number "AD20"
						(effects
							(font
								(size 1.27 1.27)
							)
						)
					)
				)
				(pin passive line
					(at 0 0 0)
					(length 5.08)
					(hide yes)
					(name "VCCO_12"
						(effects
							(font
								(size 1.27 1.27)
							)
						)
					)
					(number "AF24"
						(effects
							(font
								(size 1.27 1.27)
							)
						)
					)
				)
				(pin passive line
					(at 0 0 0)
					(length 5.08)
					(hide yes)
					(name "VCCO_12"
						(effects
							(font
								(size 1.27 1.27)
							)
						)
					)
					(number "AG21"
						(effects
							(font
								(size 1.27 1.27)
							)
						)
					)
				)
				(pin passive line
					(at 0 0 0)
					(length 5.08)
					(hide yes)
					(name "VCCO_12"
						(effects
							(font
								(size 1.27 1.27)
							)
						)
					)
					(number "AK22"
						(effects
							(font
								(size 1.27 1.27)
							)
						)
					)
				)
				(pin passive line
					(at 0 0 0)
					(length 5.08)
					(hide yes)
					(name "VCCO_12"
						(effects
							(font
								(size 1.27 1.27)
							)
						)
					)
					(number "Y22"
						(effects
							(font
								(size 1.27 1.27)
							)
						)
					)
				)
				(pin bidirectional line
					(at 0 -3.81 0)
					(length 5.08)
					(name "IO_0_12"
						(effects
							(font
								(size 1.27 1.27)
							)
						)
					)
					(number "Y20"
						(effects
							(font
								(size 1.27 1.27)
							)
						)
					)
				)
				(pin bidirectional line
					(at 0 -6.35 0)
					(length 5.08)
					(name "IO_L1P_T0_12"
						(effects
							(font
								(size 1.27 1.27)
							)
						)
					)
					(number "Y23"
						(effects
							(font
								(size 1.27 1.27)
							)
						)
					)
				)
				(pin bidirectional line
					(at 0 -8.89 0)
					(length 5.08)
					(name "IO_L1N_T0_12"
						(effects
							(font
								(size 1.27 1.27)
							)
						)
					)
					(number "Y24"
						(effects
							(font
								(size 1.27 1.27)
							)
						)
					)
				)
				(pin bidirectional line
					(at 0 -11.43 0)
					(length 5.08)
					(name "IO_L2P_T0_12"
						(effects
							(font
								(size 1.27 1.27)
							)
						)
					)
					(number "Y21"
						(effects
							(font
								(size 1.27 1.27)
							)
						)
					)
				)
				(pin bidirectional line
					(at 0 -13.97 0)
					(length 5.08)
					(name "IO_L2N_T0_12"
						(effects
							(font
								(size 1.27 1.27)
							)
						)
					)
					(number "AA21"
						(effects
							(font
								(size 1.27 1.27)
							)
						)
					)
				)
				(pin bidirectional line
					(at 0 -16.51 0)
					(length 5.08)
					(name "IO_L3P_T0_DQS_12"
						(effects
							(font
								(size 1.27 1.27)
							)
						)
					)
					(number "AB22"
						(effects
							(font
								(size 1.27 1.27)
							)
						)
					)
				)
				(pin bidirectional line
					(at 0 -19.05 0)
					(length 5.08)
					(name "IO_L3N_T0_DQS_12"
						(effects
							(font
								(size 1.27 1.27)
							)
						)
					)
					(number "AB23"
						(effects
							(font
								(size 1.27 1.27)
							)
						)
					)
				)
				(pin bidirectional line
					(at 0 -21.59 0)
					(length 5.08)
					(name "IO_L4P_T0_12"
						(effects
							(font
								(size 1.27 1.27)
							)
						)
					)
					(number "AA22"
						(effects
							(font
								(size 1.27 1.27)
							)
						)
					)
				)
				(pin bidirectional line
					(at 0 -24.13 0)
					(length 5.08)
					(name "IO_L4N_T0_12"
						(effects
							(font
								(size 1.27 1.27)
							)
						)
					)
					(number "AA23"
						(effects
							(font
								(size 1.27 1.27)
							)
						)
					)
				)
				(pin bidirectional line
					(at 0 -26.67 0)
					(length 5.08)
					(name "IO_L5P_T0_12"
						(effects
							(font
								(size 1.27 1.27)
							)
						)
					)
					(number "AC20"
						(effects
							(font
								(size 1.27 1.27)
							)
						)
					)
				)
				(pin bidirectional line
					(at 0 -29.21 0)
					(length 5.08)
					(name "IO_L5N_T0_12"
						(effects
							(font
								(size 1.27 1.27)
							)
						)
					)
					(number "AC21"
						(effects
							(font
								(size 1.27 1.27)
							)
						)
					)
				)
				(pin bidirectional line
					(at 0 -31.75 0)
					(length 5.08)
					(name "IO_L6P_T0_12"
						(effects
							(font
								(size 1.27 1.27)
							)
						)
					)
					(number "AA20"
						(effects
							(font
								(size 1.27 1.27)
							)
						)
					)
				)
				(pin bidirectional line
					(at 0 -34.29 0)
					(length 5.08)
					(name "IO_L6N_T0_VREF_12"
						(effects
							(font
								(size 1.27 1.27)
							)
						)
					)
					(number "AB20"
						(effects
							(font
								(size 1.27 1.27)
							)
						)
					)
				)
				(pin bidirectional line
					(at 0 -36.83 0)
					(length 5.08)
					(name "IO_L7P_T1_12"
						(effects
							(font
								(size 1.27 1.27)
							)
						)
					)
					(number "AB24"
						(effects
							(font
								(size 1.27 1.27)
							)
						)
					)
				)
				(pin bidirectional line
					(at 0 -39.37 0)
					(length 5.08)
					(name "IO_L7N_T1_12"
						(effects
							(font
								(size 1.27 1.27)
							)
						)
					)
					(number "AC25"
						(effects
							(font
								(size 1.27 1.27)
							)
						)
					)
				)
				(pin bidirectional line
					(at 0 -41.91 0)
					(length 5.08)
					(name "IO_L8P_T1_12"
						(effects
							(font
								(size 1.27 1.27)
							)
						)
					)
					(number "AC22"
						(effects
							(font
								(size 1.27 1.27)
							)
						)
					)
				)
				(pin bidirectional line
					(at 0 -44.45 0)
					(length 5.08)
					(name "IO_L8N_T1_12"
						(effects
							(font
								(size 1.27 1.27)
							)
						)
					)
					(number "AD22"
						(effects
							(font
								(size 1.27 1.27)
							)
						)
					)
				)
				(pin bidirectional line
					(at 0 -46.99 0)
					(length 5.08)
					(name "IO_L9P_T1_DQS_12"
						(effects
							(font
								(size 1.27 1.27)
							)
						)
					)
					(number "AC24"
						(effects
							(font
								(size 1.27 1.27)
							)
						)
					)
				)
				(pin bidirectional line
					(at 0 -49.53 0)
					(length 5.08)
					(name "IO_L9N_T1_DQS_12"
						(effects
							(font
								(size 1.27 1.27)
							)
						)
					)
					(number "AD24"
						(effects
							(font
								(size 1.27 1.27)
							)
						)
					)
				)
				(pin bidirectional line
					(at 0 -52.07 0)
					(length 5.08)
					(name "IO_L10P_T1_12"
						(effects
							(font
								(size 1.27 1.27)
							)
						)
					)
					(number "AD21"
						(effects
							(font
								(size 1.27 1.27)
							)
						)
					)
				)
				(pin bidirectional line
					(at 0 -54.61 0)
					(length 5.08)
					(name "IO_L10N_T1_12"
						(effects
							(font
								(size 1.27 1.27)
							)
						)
					)
					(number "AE21"
						(effects
							(font
								(size 1.27 1.27)
							)
						)
					)
				)
				(pin bidirectional line
					(at 0 -57.15 0)
					(length 5.08)
					(name "IO_L11P_T1_SRCC_12"
						(effects
							(font
								(size 1.27 1.27)
							)
						)
					)
					(number "AE23"
						(effects
							(font
								(size 1.27 1.27)
							)
						)
					)
				)
				(pin bidirectional line
					(at 0 -59.69 0)
					(length 5.08)
					(name "IO_L11N_T1_SRCC_12"
						(effects
							(font
								(size 1.27 1.27)
							)
						)
					)
					(number "AF23"
						(effects
							(font
								(size 1.27 1.27)
							)
						)
					)
				)
				(pin bidirectional line
					(at 0 -62.23 0)
					(length 5.08)
					(name "IO_L12P_T1_MRCC_12"
						(effects
							(font
								(size 1.27 1.27)
							)
						)
					)
					(number "AD23"
						(effects
							(font
								(size 1.27 1.27)
							)
						)
					)
				)
				(pin bidirectional line
					(at 0 -64.77 0)
					(length 5.08)
					(name "IO_L12N_T1_MRCC_12"
						(effects
							(font
								(size 1.27 1.27)
							)
						)
					)
					(number "AE24"
						(effects
							(font
								(size 1.27 1.27)
							)
						)
					)
				)
				(pin bidirectional line
					(at 0 -67.31 0)
					(length 5.08)
					(name "IO_L13P_T2_MRCC_12"
						(effects
							(font
								(size 1.27 1.27)
							)
						)
					)
					(number "AF22"
						(effects
							(font
								(size 1.27 1.27)
							)
						)
					)
				)
				(pin bidirectional line
					(at 0 -69.85 0)
					(length 5.08)
					(name "IO_L13N_T2_MRCC_12"
						(effects
							(font
								(size 1.27 1.27)
							)
						)
					)
					(number "AG23"
						(effects
							(font
								(size 1.27 1.27)
							)
						)
					)
				)
				(pin bidirectional line
					(at 0 -72.39 0)
					(length 5.08)
					(name "IO_L14P_T2_SRCC_12"
						(effects
							(font
								(size 1.27 1.27)
							)
						)
					)
					(number "AG24"
						(effects
							(font
								(size 1.27 1.27)
							)
						)
					)
				)
				(pin bidirectional line
					(at 0 -74.93 0)
					(length 5.08)
					(name "IO_L14N_T2_SRCC_12"
						(effects
							(font
								(size 1.27 1.27)
							)
						)
					)
					(number "AH24"
						(effects
							(font
								(size 1.27 1.27)
							)
						)
					)
				)
				(pin bidirectional line
					(at 0 -77.47 0)
					(length 5.08)
					(name "IO_L15P_T2_DQS_12"
						(effects
							(font
								(size 1.27 1.27)
							)
						)
					)
					(number "AJ24"
						(effects
							(font
								(size 1.27 1.27)
							)
						)
					)
				)
				(pin bidirectional line
					(at 0 -80.01 0)
					(length 5.08)
					(name "IO_L15N_T2_DQS_12"
						(effects
							(font
								(size 1.27 1.27)
							)
						)
					)
					(number "AK25"
						(effects
							(font
								(size 1.27 1.27)
							)
						)
					)
				)
				(pin bidirectional line
					(at 0 -82.55 0)
					(length 5.08)
					(name "IO_L16P_T2_12"
						(effects
							(font
								(size 1.27 1.27)
							)
						)
					)
					(number "AE25"
						(effects
							(font
								(size 1.27 1.27)
							)
						)
					)
				)
				(pin bidirectional line
					(at 0 -85.09 0)
					(length 5.08)
					(name "IO_L16N_T2_12"
						(effects
							(font
								(size 1.27 1.27)
							)
						)
					)
					(number "AF25"
						(effects
							(font
								(size 1.27 1.27)
							)
						)
					)
				)
				(pin bidirectional line
					(at 0 -87.63 0)
					(length 5.08)
					(name "IO_L17P_T2_12"
						(effects
							(font
								(size 1.27 1.27)
							)
						)
					)
					(number "AK23"
						(effects
							(font
								(size 1.27 1.27)
							)
						)
					)
				)
				(pin bidirectional line
					(at 0 -90.17 0)
					(length 5.08)
					(name "IO_L17N_T2_12"
						(effects
							(font
								(size 1.27 1.27)
							)
						)
					)
					(number "AK24"
						(effects
							(font
								(size 1.27 1.27)
							)
						)
					)
				)
				(pin bidirectional line
					(at 0 -92.71 0)
					(length 5.08)
					(name "IO_L18P_T2_12"
						(effects
							(font
								(size 1.27 1.27)
							)
						)
					)
					(number "AG25"
						(effects
							(font
								(size 1.27 1.27)
							)
						)
					)
				)
				(pin bidirectional line
					(at 0 -95.25 0)
					(length 5.08)
					(name "IO_L18N_T2_12"
						(effects
							(font
								(size 1.27 1.27)
							)
						)
					)
					(number "AH25"
						(effects
							(font
								(size 1.27 1.27)
							)
						)
					)
				)
				(pin bidirectional line
					(at 0 -97.79 0)
					(length 5.08)
					(name "IO_L19P_T3_12"
						(effects
							(font
								(size 1.27 1.27)
							)
						)
					)
					(number "AF20"
						(effects
							(font
								(size 1.27 1.27)
							)
						)
					)
				)
				(pin bidirectional line
					(at 0 -100.33 0)
					(length 5.08)
					(name "IO_L19N_T3_VREF_12"
						(effects
							(font
								(size 1.27 1.27)
							)
						)
					)
					(number "AF21"
						(effects
							(font
								(size 1.27 1.27)
							)
						)
					)
				)
				(pin bidirectional line
					(at 0 -102.87 0)
					(length 5.08)
					(name "IO_L20P_T3_12"
						(effects
							(font
								(size 1.27 1.27)
							)
						)
					)
					(number "AG22"
						(effects
							(font
								(size 1.27 1.27)
							)
						)
					)
				)
				(pin bidirectional line
					(at 0 -105.41 0)
					(length 5.08)
					(name "IO_L20N_T3_12"
						(effects
							(font
								(size 1.27 1.27)
							)
						)
					)
					(number "AH22"
						(effects
							(font
								(size 1.27 1.27)
							)
						)
					)
				)
				(pin bidirectional line
					(at 0 -107.95 0)
					(length 5.08)
					(name "IO_L21P_T3_DQS_12"
						(effects
							(font
								(size 1.27 1.27)
							)
						)
					)
					(number "AJ22"
						(effects
							(font
								(size 1.27 1.27)
							)
						)
					)
				)
				(pin bidirectional line
					(at 0 -110.49 0)
					(length 5.08)
					(name "IO_L21N_T3_DQS_12"
						(effects
							(font
								(size 1.27 1.27)
							)
						)
					)
					(number "AJ23"
						(effects
							(font
								(size 1.27 1.27)
							)
						)
					)
				)
				(pin bidirectional line
					(at 0 -113.03 0)
					(length 5.08)
					(name "IO_L22P_T3_12"
						(effects
							(font
								(size 1.27 1.27)
							)
						)
					)
					(number "AG20"
						(effects
							(font
								(size 1.27 1.27)
							)
						)
					)
				)
				(pin bidirectional line
					(at 0 -115.57 0)
					(length 5.08)
					(name "IO_L22N_T3_12"
						(effects
							(font
								(size 1.27 1.27)
							)
						)
					)
					(number "AH20"
						(effects
							(font
								(size 1.27 1.27)
							)
						)
					)
				)
				(pin bidirectional line
					(at 0 -118.11 0)
					(length 5.08)
					(name "IO_L23P_T3_12"
						(effects
							(font
								(size 1.27 1.27)
							)
						)
					)
					(number "AH21"
						(effects
							(font
								(size 1.27 1.27)
							)
						)
					)
				)
				(pin bidirectional line
					(at 0 -120.65 0)
					(length 5.08)
					(name "IO_L23N_T3_12"
						(effects
							(font
								(size 1.27 1.27)
							)
						)
					)
					(number "AJ21"
						(effects
							(font
								(size 1.27 1.27)
							)
						)
					)
				)
				(pin bidirectional line
					(at 0 -123.19 0)
					(length 5.08)
					(name "IO_L24P_T3_12"
						(effects
							(font
								(size 1.27 1.27)
							)
						)
					)
					(number "AK20"
						(effects
							(font
								(size 1.27 1.27)
							)
						)
					)
				)
				(pin bidirectional line
					(at 0 -125.73 0)
					(length 5.08)
					(name "IO_L24N_T3_12"
						(effects
							(font
								(size 1.27 1.27)
							)
						)
					)
					(number "AK21"
						(effects
							(font
								(size 1.27 1.27)
							)
						)
					)
				)
				(pin bidirectional line
					(at 0 -128.27 0)
					(length 5.08)
					(name "IO_25_12"
						(effects
							(font
								(size 1.27 1.27)
							)
						)
					)
					(number "AE20"
						(effects
							(font
								(size 1.27 1.27)
							)
						)
					)
				)
				(pin bidirectional line
					(at 55.88 0 180)
					(length 5.08)
					(name "VCCO_13"
						(effects
							(font
								(size 1.27 1.27)
							)
						)
					)
					(number "AA29"
						(effects
							(font
								(size 1.27 1.27)
							)
						)
					)
				)
				(pin passive line
					(at 55.88 0 180)
					(length 5.08)
					(hide yes)
					(name "VCCO_13"
						(effects
							(font
								(size 1.27 1.27)
							)
						)
					)
					(number "AB26"
						(effects
							(font
								(size 1.27 1.27)
							)
						)
					)
				)
				(pin passive line
					(at 55.88 0 180)
					(length 5.08)
					(hide yes)
					(name "VCCO_13"
						(effects
							(font
								(size 1.27 1.27)
							)
						)
					)
					(number "AD30"
						(effects
							(font
								(size 1.27 1.27)
							)
						)
					)
				)
				(pin passive line
					(at 55.88 0 180)
					(length 5.08)
					(hide yes)
					(name "VCCO_13"
						(effects
							(font
								(size 1.27 1.27)
							)
						)
					)
					(number "AE27"
						(effects
							(font
								(size 1.27 1.27)
							)
						)
					)
				)
				(pin passive line
					(at 55.88 0 180)
					(length 5.08)
					(hide yes)
					(name "VCCO_13"
						(effects
							(font
								(size 1.27 1.27)
							)
						)
					)
					(number "AH28"
						(effects
							(font
								(size 1.27 1.27)
							)
						)
					)
				)
				(pin passive line
					(at 55.88 0 180)
					(length 5.08)
					(hide yes)
					(name "VCCO_13"
						(effects
							(font
								(size 1.27 1.27)
							)
						)
					)
					(number "AJ25"
						(effects
							(font
								(size 1.27 1.27)
							)
						)
					)
				)
				(pin bidirectional line
					(at 55.88 -3.81 180)
					(length 5.08)
					(name "IO_0_13"
						(effects
							(font
								(size 1.27 1.27)
							)
						)
					)
					(number "Y25"
						(effects
							(font
								(size 1.27 1.27)
							)
						)
					)
				)
				(pin bidirectional line
					(at 55.88 -6.35 180)
					(length 5.08)
					(name "IO_L1P_T0_13"
						(effects
							(font
								(size 1.27 1.27)
							)
						)
					)
					(number "Y26"
						(effects
							(font
								(size 1.27 1.27)
							)
						)
					)
				)
				(pin bidirectional line
					(at 55.88 -8.89 180)
					(length 5.08)
					(name "IO_L1N_T0_13"
						(effects
							(font
								(size 1.27 1.27)
							)
						)
					)
					(number "AA26"
						(effects
							(font
								(size 1.27 1.27)
							)
						)
					)
				)
				(pin bidirectional line
					(at 55.88 -11.43 180)
					(length 5.08)
					(name "IO_L2P_T0_13"
						(effects
							(font
								(size 1.27 1.27)
							)
						)
					)
					(number "W27"
						(effects
							(font
								(size 1.27 1.27)
							)
						)
					)
				)
				(pin bidirectional line
					(at 55.88 -13.97 180)
					(length 5.08)
					(name "IO_L2N_T0_13"
						(effects
							(font
								(size 1.27 1.27)
							)
						)
					)
					(number "W28"
						(effects
							(font
								(size 1.27 1.27)
							)
						)
					)
				)
				(pin bidirectional line
					(at 55.88 -16.51 180)
					(length 5.08)
					(name "IO_L3P_T0_DQS_13"
						(effects
							(font
								(size 1.27 1.27)
							)
						)
					)
					(number "Y28"
						(effects
							(font
								(size 1.27 1.27)
							)
						)
					)
				)
				(pin bidirectional line
					(at 55.88 -19.05 180)
					(length 5.08)
					(name "IO_L3N_T0_DQS_13"
						(effects
							(font
								(size 1.27 1.27)
							)
						)
					)
					(number "AA28"
						(effects
							(font
								(size 1.27 1.27)
							)
						)
					)
				)
				(pin bidirectional line
					(at 55.88 -21.59 180)
					(length 5.08)
					(name "IO_L4P_T0_13"
						(effects
							(font
								(size 1.27 1.27)
							)
						)
					)
					(number "W29"
						(effects
							(font
								(size 1.27 1.27)
							)
						)
					)
				)
				(pin bidirectional line
					(at 55.88 -24.13 180)
					(length 5.08)
					(name "IO_L4N_T0_13"
						(effects
							(font
								(size 1.27 1.27)
							)
						)
					)
					(number "Y29"
						(effects
							(font
								(size 1.27 1.27)
							)
						)
					)
				)
				(pin bidirectional line
					(at 55.88 -26.67 180)
					(length 5.08)
					(name "IO_L5P_T0_13"
						(effects
							(font
								(size 1.27 1.27)
							)
						)
					)
					(number "AA27"
						(effects
							(font
								(size 1.27 1.27)
							)
						)
					)
				)
				(pin bidirectional line
					(at 55.88 -29.21 180)
					(length 5.08)
					(name "IO_L5N_T0_13"
						(effects
							(font
								(size 1.27 1.27)
							)
						)
					)
					(number "AB28"
						(effects
							(font
								(size 1.27 1.27)
							)
						)
					)
				)
				(pin bidirectional line
					(at 55.88 -31.75 180)
					(length 5.08)
					(name "IO_L6P_T0_13"
						(effects
							(font
								(size 1.27 1.27)
							)
						)
					)
					(number "AA25"
						(effects
							(font
								(size 1.27 1.27)
							)
						)
					)
				)
				(pin bidirectional line
					(at 55.88 -34.29 180)
					(length 5.08)
					(name "IO_L6N_T0_VREF_13"
						(effects
							(font
								(size 1.27 1.27)
							)
						)
					)
					(number "AB25"
						(effects
							(font
								(size 1.27 1.27)
							)
						)
					)
				)
				(pin bidirectional line
					(at 55.88 -36.83 180)
					(length 5.08)
					(name "IO_L7P_T1_13"
						(effects
							(font
								(size 1.27 1.27)
							)
						)
					)
					(number "AC29"
						(effects
							(font
								(size 1.27 1.27)
							)
						)
					)
				)
				(pin bidirectional line
					(at 55.88 -39.37 180)
					(length 5.08)
					(name "IO_L7N_T1_13"
						(effects
							(font
								(size 1.27 1.27)
							)
						)
					)
					(number "AC30"
						(effects
							(font
								(size 1.27 1.27)
							)
						)
					)
				)
				(pin bidirectional line
					(at 55.88 -41.91 180)
					(length 5.08)
					(name "IO_L8P_T1_13"
						(effects
							(font
								(size 1.27 1.27)
							)
						)
					)
					(number "Y30"
						(effects
							(font
								(size 1.27 1.27)
							)
						)
					)
				)
				(pin bidirectional line
					(at 55.88 -44.45 180)
					(length 5.08)
					(name "IO_L8N_T1_13"
						(effects
							(font
								(size 1.27 1.27)
							)
						)
					)
					(number "AA30"
						(effects
							(font
								(size 1.27 1.27)
							)
						)
					)
				)
				(pin bidirectional line
					(at 55.88 -46.99 180)
					(length 5.08)
					(name "IO_L9P_T1_DQS_13"
						(effects
							(font
								(size 1.27 1.27)
							)
						)
					)
					(number "AD29"
						(effects
							(font
								(size 1.27 1.27)
							)
						)
					)
				)
				(pin bidirectional line
					(at 55.88 -49.53 180)
					(length 5.08)
					(name "IO_L9N_T1_DQS_13"
						(effects
							(font
								(size 1.27 1.27)
							)
						)
					)
					(number "AE29"
						(effects
							(font
								(size 1.27 1.27)
							)
						)
					)
				)
				(pin bidirectional line
					(at 55.88 -52.07 180)
					(length 5.08)
					(name "IO_L10P_T1_13"
						(effects
							(font
								(size 1.27 1.27)
							)
						)
					)
					(number "AB29"
						(effects
							(font
								(size 1.27 1.27)
							)
						)
					)
				)
				(pin bidirectional line
					(at 55.88 -54.61 180)
					(length 5.08)
					(name "IO_L10N_T1_13"
						(effects
							(font
								(size 1.27 1.27)
							)
						)
					)
					(number "AB30"
						(effects
							(font
								(size 1.27 1.27)
							)
						)
					)
				)
				(pin bidirectional line
					(at 55.88 -57.15 180)
					(length 5.08)
					(name "IO_L11P_T1_SRCC_13"
						(effects
							(font
								(size 1.27 1.27)
							)
						)
					)
					(number "AD27"
						(effects
							(font
								(size 1.27 1.27)
							)
						)
					)
				)
				(pin bidirectional line
					(at 55.88 -59.69 180)
					(length 5.08)
					(name "IO_L11N_T1_SRCC_13"
						(effects
							(font
								(size 1.27 1.27)
							)
						)
					)
					(number "AD28"
						(effects
							(font
								(size 1.27 1.27)
							)
						)
					)
				)
				(pin bidirectional line
					(at 55.88 -62.23 180)
					(length 5.08)
					(name "IO_L12P_T1_MRCC_13"
						(effects
							(font
								(size 1.27 1.27)
							)
						)
					)
					(number "AB27"
						(effects
							(font
								(size 1.27 1.27)
							)
						)
					)
				)
				(pin bidirectional line
					(at 55.88 -64.77 180)
					(length 5.08)
					(name "IO_L12N_T1_MRCC_13"
						(effects
							(font
								(size 1.27 1.27)
							)
						)
					)
					(number "AC27"
						(effects
							(font
								(size 1.27 1.27)
							)
						)
					)
				)
				(pin bidirectional line
					(at 55.88 -67.31 180)
					(length 5.08)
					(name "IO_L13P_T2_MRCC_13"
						(effects
							(font
								(size 1.27 1.27)
							)
						)
					)
					(number "AG29"
						(effects
							(font
								(size 1.27 1.27)
							)
						)
					)
				)
				(pin bidirectional line
					(at 55.88 -69.85 180)
					(length 5.08)
					(name "IO_L13N_T2_MRCC_13"
						(effects
							(font
								(size 1.27 1.27)
							)
						)
					)
					(number "AH29"
						(effects
							(font
								(size 1.27 1.27)
							)
						)
					)
				)
				(pin bidirectional line
					(at 55.88 -72.39 180)
					(length 5.08)
					(name "IO_L14P_T2_SRCC_13"
						(effects
							(font
								(size 1.27 1.27)
							)
						)
					)
					(number "AE28"
						(effects
							(font
								(size 1.27 1.27)
							)
						)
					)
				)
				(pin bidirectional line
					(at 55.88 -74.93 180)
					(length 5.08)
					(name "IO_L14N_T2_SRCC_13"
						(effects
							(font
								(size 1.27 1.27)
							)
						)
					)
					(number "AF28"
						(effects
							(font
								(size 1.27 1.27)
							)
						)
					)
				)
				(pin bidirectional line
					(at 55.88 -77.47 180)
					(length 5.08)
					(name "IO_L15P_T2_DQS_13"
						(effects
							(font
								(size 1.27 1.27)
							)
						)
					)
					(number "AK29"
						(effects
							(font
								(size 1.27 1.27)
							)
						)
					)
				)
				(pin bidirectional line
					(at 55.88 -80.01 180)
					(length 5.08)
					(name "IO_L15N_T2_DQS_13"
						(effects
							(font
								(size 1.27 1.27)
							)
						)
					)
					(number "AK30"
						(effects
							(font
								(size 1.27 1.27)
							)
						)
					)
				)
				(pin bidirectional line
					(at 55.88 -82.55 180)
					(length 5.08)
					(name "IO_L16P_T2_13"
						(effects
							(font
								(size 1.27 1.27)
							)
						)
					)
					(number "AE30"
						(effects
							(font
								(size 1.27 1.27)
							)
						)
					)
				)
				(pin bidirectional line
					(at 55.88 -85.09 180)
					(length 5.08)
					(name "IO_L16N_T2_13"
						(effects
							(font
								(size 1.27 1.27)
							)
						)
					)
					(number "AF30"
						(effects
							(font
								(size 1.27 1.27)
							)
						)
					)
				)
				(pin bidirectional line
					(at 55.88 -87.63 180)
					(length 5.08)
					(name "IO_L17P_T2_13"
						(effects
							(font
								(size 1.27 1.27)
							)
						)
					)
					(number "AJ28"
						(effects
							(font
								(size 1.27 1.27)
							)
						)
					)
				)
				(pin bidirectional line
					(at 55.88 -90.17 180)
					(length 5.08)
					(name "IO_L17N_T2_13"
						(effects
							(font
								(size 1.27 1.27)
							)
						)
					)
					(number "AJ29"
						(effects
							(font
								(size 1.27 1.27)
							)
						)
					)
				)
				(pin bidirectional line
					(at 55.88 -92.71 180)
					(length 5.08)
					(name "IO_L18P_T2_13"
						(effects
							(font
								(size 1.27 1.27)
							)
						)
					)
					(number "AG30"
						(effects
							(font
								(size 1.27 1.27)
							)
						)
					)
				)
				(pin bidirectional line
					(at 55.88 -95.25 180)
					(length 5.08)
					(name "IO_L18N_T2_13"
						(effects
							(font
								(size 1.27 1.27)
							)
						)
					)
					(number "AH30"
						(effects
							(font
								(size 1.27 1.27)
							)
						)
					)
				)
				(pin bidirectional line
					(at 55.88 -97.79 180)
					(length 5.08)
					(name "IO_L19P_T3_13"
						(effects
							(font
								(size 1.27 1.27)
							)
						)
					)
					(number "AC26"
						(effects
							(font
								(size 1.27 1.27)
							)
						)
					)
				)
				(pin bidirectional line
					(at 55.88 -100.33 180)
					(length 5.08)
					(name "IO_L19N_T3_VREF_13"
						(effects
							(font
								(size 1.27 1.27)
							)
						)
					)
					(number "AD26"
						(effects
							(font
								(size 1.27 1.27)
							)
						)
					)
				)
				(pin bidirectional line
					(at 55.88 -102.87 180)
					(length 5.08)
					(name "IO_L20P_T3_13"
						(effects
							(font
								(size 1.27 1.27)
							)
						)
					)
					(number "AJ27"
						(effects
							(font
								(size 1.27 1.27)
							)
						)
					)
				)
				(pin bidirectional line
					(at 55.88 -105.41 180)
					(length 5.08)
					(name "IO_L20N_T3_13"
						(effects
							(font
								(size 1.27 1.27)
							)
						)
					)
					(number "AK28"
						(effects
							(font
								(size 1.27 1.27)
							)
						)
					)
				)
				(pin bidirectional line
					(at 55.88 -107.95 180)
					(length 5.08)
					(name "IO_L21P_T3_DQS_13"
						(effects
							(font
								(size 1.27 1.27)
							)
						)
					)
					(number "AG27"
						(effects
							(font
								(size 1.27 1.27)
							)
						)
					)
				)
				(pin bidirectional line
					(at 55.88 -110.49 180)
					(length 5.08)
					(name "IO_L21N_T3_DQS_13"
						(effects
							(font
								(size 1.27 1.27)
							)
						)
					)
					(number "AG28"
						(effects
							(font
								(size 1.27 1.27)
							)
						)
					)
				)
				(pin bidirectional line
					(at 55.88 -113.03 180)
					(length 5.08)
					(name "IO_L22P_T3_13"
						(effects
							(font
								(size 1.27 1.27)
							)
						)
					)
					(number "AH26"
						(effects
							(font
								(size 1.27 1.27)
							)
						)
					)
				)
				(pin bidirectional line
					(at 55.88 -115.57 180)
					(length 5.08)
					(name "IO_L22N_T3_13"
						(effects
							(font
								(size 1.27 1.27)
							)
						)
					)
					(number "AH27"
						(effects
							(font
								(size 1.27 1.27)
							)
						)
					)
				)
				(pin bidirectional line
					(at 55.88 -118.11 180)
					(length 5.08)
					(name "IO_L23P_T3_13"
						(effects
							(font
								(size 1.27 1.27)
							)
						)
					)
					(number "AF26"
						(effects
							(font
								(size 1.27 1.27)
							)
						)
					)
				)
				(pin bidirectional line
					(at 55.88 -120.65 180)
					(length 5.08)
					(name "IO_L23N_T3_13"
						(effects
							(font
								(size 1.27 1.27)
							)
						)
					)
					(number "AF27"
						(effects
							(font
								(size 1.27 1.27)
							)
						)
					)
				)
				(pin bidirectional line
					(at 55.88 -123.19 180)
					(length 5.08)
					(name "IO_L24P_T3_13"
						(effects
							(font
								(size 1.27 1.27)
							)
						)
					)
					(number "AJ26"
						(effects
							(font
								(size 1.27 1.27)
							)
						)
					)
				)
				(pin bidirectional line
					(at 55.88 -125.73 180)
					(length 5.08)
					(name "IO_L24N_T3_13"
						(effects
							(font
								(size 1.27 1.27)
							)
						)
					)
					(number "AK26"
						(effects
							(font
								(size 1.27 1.27)
							)
						)
					)
				)
				(pin bidirectional line
					(at 55.88 -128.27 180)
					(length 5.08)
					(name "IO_25_13"
						(effects
							(font
								(size 1.27 1.27)
							)
						)
					)
					(number "AE26"
						(effects
							(font
								(size 1.27 1.27)
							)
						)
					)
				)
			)
			(symbol "XC7K410T-2FFG900I_3_2_1"
				(rectangle
					(start 5.08 5.08)
					(end 64.77 -130.81)
					(stroke
						(width 0.254)
						(type default)
					)
					(fill
						(type background)
					)
				)
				(text "BANK 14"
					(at 15.24 2.54 0)
					(effects
						(font
							(size 1.27 1.27)
							(thickness 0.15)
						)
						(justify left bottom)
					)
				)
				(text "BANK 15"
					(at 45.72 2.54 0)
					(effects
						(font
							(size 1.27 1.27)
							(thickness 0.15)
						)
						(justify left bottom)
					)
				)
				(pin bidirectional line
					(at 0 0 0)
					(length 5.08)
					(name "VCCO_14"
						(effects
							(font
								(size 1.27 1.27)
							)
						)
					)
					(number "P30"
						(effects
							(font
								(size 1.27 1.27)
							)
						)
					)
				)
				(pin passive line
					(at 0 0 0)
					(length 5.08)
					(hide yes)
					(name "VCCO_14"
						(effects
							(font
								(size 1.27 1.27)
							)
						)
					)
					(number "R27"
						(effects
							(font
								(size 1.27 1.27)
							)
						)
					)
				)
				(pin passive line
					(at 0 0 0)
					(length 5.08)
					(hide yes)
					(name "VCCO_14"
						(effects
							(font
								(size 1.27 1.27)
							)
						)
					)
					(number "T24"
						(effects
							(font
								(size 1.27 1.27)
							)
						)
					)
				)
				(pin passive line
					(at 0 0 0)
					(length 5.08)
					(hide yes)
					(name "VCCO_14"
						(effects
							(font
								(size 1.27 1.27)
							)
						)
					)
					(number "U21"
						(effects
							(font
								(size 1.27 1.27)
							)
						)
					)
				)
				(pin passive line
					(at 0 0 0)
					(length 5.08)
					(hide yes)
					(name "VCCO_14"
						(effects
							(font
								(size 1.27 1.27)
							)
						)
					)
					(number "V28"
						(effects
							(font
								(size 1.27 1.27)
							)
						)
					)
				)
				(pin passive line
					(at 0 0 0)
					(length 5.08)
					(hide yes)
					(name "VCCO_14"
						(effects
							(font
								(size 1.27 1.27)
							)
						)
					)
					(number "W25"
						(effects
							(font
								(size 1.27 1.27)
							)
						)
					)
				)
				(pin bidirectional line
					(at 0 -3.81 0)
					(length 5.08)
					(name "IO_0_14"
						(effects
							(font
								(size 1.27 1.27)
							)
						)
					)
					(number "R19"
						(effects
							(font
								(size 1.27 1.27)
							)
						)
					)
				)
				(pin bidirectional line
					(at 0 -6.35 0)
					(length 5.08)
					(name "IO_L1P_T0_D00_MOSI_14"
						(effects
							(font
								(size 1.27 1.27)
							)
						)
					)
					(number "P24"
						(effects
							(font
								(size 1.27 1.27)
							)
						)
					)
				)
				(pin bidirectional line
					(at 0 -8.89 0)
					(length 5.08)
					(name "IO_L1N_T0_D01_DIN_14"
						(effects
							(font
								(size 1.27 1.27)
							)
						)
					)
					(number "R25"
						(effects
							(font
								(size 1.27 1.27)
							)
						)
					)
				)
				(pin bidirectional line
					(at 0 -11.43 0)
					(length 5.08)
					(name "IO_L2P_T0_D02_14"
						(effects
							(font
								(size 1.27 1.27)
							)
						)
					)
					(number "R20"
						(effects
							(font
								(size 1.27 1.27)
							)
						)
					)
				)
				(pin bidirectional line
					(at 0 -13.97 0)
					(length 5.08)
					(name "IO_L2N_T0_D03_14"
						(effects
							(font
								(size 1.27 1.27)
							)
						)
					)
					(number "R21"
						(effects
							(font
								(size 1.27 1.27)
							)
						)
					)
				)
				(pin bidirectional line
					(at 0 -16.51 0)
					(length 5.08)
					(name "IO_L3P_T0_DQS_PUDC_B_14"
						(effects
							(font
								(size 1.27 1.27)
							)
						)
					)
					(number "R23"
						(effects
							(font
								(size 1.27 1.27)
							)
						)
					)
				)
				(pin bidirectional line
					(at 0 -19.05 0)
					(length 5.08)
					(name "IO_L3N_T0_DQS_EMCCLK_14"
						(effects
							(font
								(size 1.27 1.27)
							)
						)
					)
					(number "R24"
						(effects
							(font
								(size 1.27 1.27)
							)
						)
					)
				)
				(pin bidirectional line
					(at 0 -21.59 0)
					(length 5.08)
					(name "IO_L4P_T0_D04_14"
						(effects
							(font
								(size 1.27 1.27)
							)
						)
					)
					(number "T20"
						(effects
							(font
								(size 1.27 1.27)
							)
						)
					)
				)
				(pin bidirectional line
					(at 0 -24.13 0)
					(length 5.08)
					(name "IO_L4N_T0_D05_14"
						(effects
							(font
								(size 1.27 1.27)
							)
						)
					)
					(number "T21"
						(effects
							(font
								(size 1.27 1.27)
							)
						)
					)
				)
				(pin bidirectional line
					(at 0 -26.67 0)
					(length 5.08)
					(name "IO_L5P_T0_D06_14"
						(effects
							(font
								(size 1.27 1.27)
							)
						)
					)
					(number "T22"
						(effects
							(font
								(size 1.27 1.27)
							)
						)
					)
				)
				(pin bidirectional line
					(at 0 -29.21 0)
					(length 5.08)
					(name "IO_L5N_T0_D07_14"
						(effects
							(font
								(size 1.27 1.27)
							)
						)
					)
					(number "T23"
						(effects
							(font
								(size 1.27 1.27)
							)
						)
					)
				)
				(pin bidirectional line
					(at 0 -31.75 0)
					(length 5.08)
					(name "IO_L6P_T0_FCS_B_14"
						(effects
							(font
								(size 1.27 1.27)
							)
						)
					)
					(number "U19"
						(effects
							(font
								(size 1.27 1.27)
							)
						)
					)
				)
				(pin bidirectional line
					(at 0 -34.29 0)
					(length 5.08)
					(name "IO_L6N_T0_D08_VREF_14"
						(effects
							(font
								(size 1.27 1.27)
							)
						)
					)
					(number "U20"
						(effects
							(font
								(size 1.27 1.27)
							)
						)
					)
				)
				(pin bidirectional line
					(at 0 -36.83 0)
					(length 5.08)
					(name "IO_L7P_T1_D09_14"
						(effects
							(font
								(size 1.27 1.27)
							)
						)
					)
					(number "P29"
						(effects
							(font
								(size 1.27 1.27)
							)
						)
					)
				)
				(pin bidirectional line
					(at 0 -39.37 0)
					(length 5.08)
					(name "IO_L7N_T1_D10_14"
						(effects
							(font
								(size 1.27 1.27)
							)
						)
					)
					(number "R29"
						(effects
							(font
								(size 1.27 1.27)
							)
						)
					)
				)
				(pin bidirectional line
					(at 0 -41.91 0)
					(length 5.08)
					(name "IO_L8P_T1_D11_14"
						(effects
							(font
								(size 1.27 1.27)
							)
						)
					)
					(number "P27"
						(effects
							(font
								(size 1.27 1.27)
							)
						)
					)
				)
				(pin bidirectional line
					(at 0 -44.45 0)
					(length 5.08)
					(name "IO_L8N_T1_D12_14"
						(effects
							(font
								(size 1.27 1.27)
							)
						)
					)
					(number "P28"
						(effects
							(font
								(size 1.27 1.27)
							)
						)
					)
				)
				(pin bidirectional line
					(at 0 -46.99 0)
					(length 5.08)
					(name "IO_L9P_T1_DQS_14"
						(effects
							(font
								(size 1.27 1.27)
							)
						)
					)
					(number "R30"
						(effects
							(font
								(size 1.27 1.27)
							)
						)
					)
				)
				(pin bidirectional line
					(at 0 -49.53 0)
					(length 5.08)
					(name "IO_L9N_T1_DQS_D13_14"
						(effects
							(font
								(size 1.27 1.27)
							)
						)
					)
					(number "T30"
						(effects
							(font
								(size 1.27 1.27)
							)
						)
					)
				)
				(pin bidirectional line
					(at 0 -52.07 0)
					(length 5.08)
					(name "IO_L10P_T1_D14_14"
						(effects
							(font
								(size 1.27 1.27)
							)
						)
					)
					(number "P26"
						(effects
							(font
								(size 1.27 1.27)
							)
						)
					)
				)
				(pin bidirectional line
					(at 0 -54.61 0)
					(length 5.08)
					(name "IO_L10N_T1_D15_14"
						(effects
							(font
								(size 1.27 1.27)
							)
						)
					)
					(number "R26"
						(effects
							(font
								(size 1.27 1.27)
							)
						)
					)
				)
				(pin bidirectional line
					(at 0 -57.15 0)
					(length 5.08)
					(name "IO_L11P_T1_SRCC_14"
						(effects
							(font
								(size 1.27 1.27)
							)
						)
					)
					(number "R28"
						(effects
							(font
								(size 1.27 1.27)
							)
						)
					)
				)
				(pin bidirectional line
					(at 0 -59.69 0)
					(length 5.08)
					(name "IO_L11N_T1_SRCC_14"
						(effects
							(font
								(size 1.27 1.27)
							)
						)
					)
					(number "T28"
						(effects
							(font
								(size 1.27 1.27)
							)
						)
					)
				)
				(pin bidirectional line
					(at 0 -62.23 0)
					(length 5.08)
					(name "IO_L12P_T1_MRCC_14"
						(effects
							(font
								(size 1.27 1.27)
							)
						)
					)
					(number "T26"
						(effects
							(font
								(size 1.27 1.27)
							)
						)
					)
				)
				(pin bidirectional line
					(at 0 -64.77 0)
					(length 5.08)
					(name "IO_L12N_T1_MRCC_14"
						(effects
							(font
								(size 1.27 1.27)
							)
						)
					)
					(number "T27"
						(effects
							(font
								(size 1.27 1.27)
							)
						)
					)
				)
				(pin bidirectional line
					(at 0 -67.31 0)
					(length 5.08)
					(name "IO_L13P_T2_MRCC_14"
						(effects
							(font
								(size 1.27 1.27)
							)
						)
					)
					(number "U27"
						(effects
							(font
								(size 1.27 1.27)
							)
						)
					)
				)
				(pin bidirectional line
					(at 0 -69.85 0)
					(length 5.08)
					(name "IO_L13N_T2_MRCC_14"
						(effects
							(font
								(size 1.27 1.27)
							)
						)
					)
					(number "U28"
						(effects
							(font
								(size 1.27 1.27)
							)
						)
					)
				)
				(pin bidirectional line
					(at 0 -72.39 0)
					(length 5.08)
					(name "IO_L14P_T2_SRCC_14"
						(effects
							(font
								(size 1.27 1.27)
							)
						)
					)
					(number "T25"
						(effects
							(font
								(size 1.27 1.27)
							)
						)
					)
				)
				(pin bidirectional line
					(at 0 -74.93 0)
					(length 5.08)
					(name "IO_L14N_T2_SRCC_14"
						(effects
							(font
								(size 1.27 1.27)
							)
						)
					)
					(number "U25"
						(effects
							(font
								(size 1.27 1.27)
							)
						)
					)
				)
				(pin bidirectional line
					(at 0 -77.47 0)
					(length 5.08)
					(name "IO_L15P_T2_DQS_RDWR_B_14"
						(effects
							(font
								(size 1.27 1.27)
							)
						)
					)
					(number "U29"
						(effects
							(font
								(size 1.27 1.27)
							)
						)
					)
				)
				(pin bidirectional line
					(at 0 -80.01 0)
					(length 5.08)
					(name "IO_L15N_T2_DQS_DOUT_CSO_B_14"
						(effects
							(font
								(size 1.27 1.27)
							)
						)
					)
					(number "U30"
						(effects
							(font
								(size 1.27 1.27)
							)
						)
					)
				)
				(pin bidirectional line
					(at 0 -82.55 0)
					(length 5.08)
					(name "IO_L16P_T2_CSI_B_14"
						(effects
							(font
								(size 1.27 1.27)
							)
						)
					)
					(number "V26"
						(effects
							(font
								(size 1.27 1.27)
							)
						)
					)
				)
				(pin bidirectional line
					(at 0 -85.09 0)
					(length 5.08)
					(name "IO_L16N_T2_A15_D31_14"
						(effects
							(font
								(size 1.27 1.27)
							)
						)
					)
					(number "V27"
						(effects
							(font
								(size 1.27 1.27)
							)
						)
					)
				)
				(pin bidirectional line
					(at 0 -87.63 0)
					(length 5.08)
					(name "IO_L17P_T2_A14_D30_14"
						(effects
							(font
								(size 1.27 1.27)
							)
						)
					)
					(number "V29"
						(effects
							(font
								(size 1.27 1.27)
							)
						)
					)
				)
				(pin bidirectional line
					(at 0 -90.17 0)
					(length 5.08)
					(name "IO_L17N_T2_A13_D29_14"
						(effects
							(font
								(size 1.27 1.27)
							)
						)
					)
					(number "V30"
						(effects
							(font
								(size 1.27 1.27)
							)
						)
					)
				)
				(pin bidirectional line
					(at 0 -92.71 0)
					(length 5.08)
					(name "IO_L18P_T2_A12_D28_14"
						(effects
							(font
								(size 1.27 1.27)
							)
						)
					)
					(number "V25"
						(effects
							(font
								(size 1.27 1.27)
							)
						)
					)
				)
				(pin bidirectional line
					(at 0 -95.25 0)
					(length 5.08)
					(name "IO_L18N_T2_A11_D27_14"
						(effects
							(font
								(size 1.27 1.27)
							)
						)
					)
					(number "W26"
						(effects
							(font
								(size 1.27 1.27)
							)
						)
					)
				)
				(pin bidirectional line
					(at 0 -97.79 0)
					(length 5.08)
					(name "IO_L19P_T3_A10_D26_14"
						(effects
							(font
								(size 1.27 1.27)
							)
						)
					)
					(number "V19"
						(effects
							(font
								(size 1.27 1.27)
							)
						)
					)
				)
				(pin bidirectional line
					(at 0 -100.33 0)
					(length 5.08)
					(name "IO_L19N_T3_A09_D25_VREF_14"
						(effects
							(font
								(size 1.27 1.27)
							)
						)
					)
					(number "V20"
						(effects
							(font
								(size 1.27 1.27)
							)
						)
					)
				)
				(pin bidirectional line
					(at 0 -102.87 0)
					(length 5.08)
					(name "IO_L20P_T3_A08_D24_14"
						(effects
							(font
								(size 1.27 1.27)
							)
						)
					)
					(number "W23"
						(effects
							(font
								(size 1.27 1.27)
							)
						)
					)
				)
				(pin bidirectional line
					(at 0 -105.41 0)
					(length 5.08)
					(name "IO_L20N_T3_A07_D23_14"
						(effects
							(font
								(size 1.27 1.27)
							)
						)
					)
					(number "W24"
						(effects
							(font
								(size 1.27 1.27)
							)
						)
					)
				)
				(pin bidirectional line
					(at 0 -107.95 0)
					(length 5.08)
					(name "IO_L21P_T3_DQS_14"
						(effects
							(font
								(size 1.27 1.27)
							)
						)
					)
					(number "U22"
						(effects
							(font
								(size 1.27 1.27)
							)
						)
					)
				)
				(pin bidirectional line
					(at 0 -110.49 0)
					(length 5.08)
					(name "IO_L21N_T3_DQS_A06_D22_14"
						(effects
							(font
								(size 1.27 1.27)
							)
						)
					)
					(number "U23"
						(effects
							(font
								(size 1.27 1.27)
							)
						)
					)
				)
				(pin bidirectional line
					(at 0 -113.03 0)
					(length 5.08)
					(name "IO_L22P_T3_A05_D21_14"
						(effects
							(font
								(size 1.27 1.27)
							)
						)
					)
					(number "V21"
						(effects
							(font
								(size 1.27 1.27)
							)
						)
					)
				)
				(pin bidirectional line
					(at 0 -115.57 0)
					(length 5.08)
					(name "IO_L22N_T3_A04_D20_14"
						(effects
							(font
								(size 1.27 1.27)
							)
						)
					)
					(number "V22"
						(effects
							(font
								(size 1.27 1.27)
							)
						)
					)
				)
				(pin bidirectional line
					(at 0 -118.11 0)
					(length 5.08)
					(name "IO_L23P_T3_A03_D19_14"
						(effects
							(font
								(size 1.27 1.27)
							)
						)
					)
					(number "U24"
						(effects
							(font
								(size 1.27 1.27)
							)
						)
					)
				)
				(pin bidirectional line
					(at 0 -120.65 0)
					(length 5.08)
					(name "IO_L23N_T3_A02_D18_14"
						(effects
							(font
								(size 1.27 1.27)
							)
						)
					)
					(number "V24"
						(effects
							(font
								(size 1.27 1.27)
							)
						)
					)
				)
				(pin bidirectional line
					(at 0 -123.19 0)
					(length 5.08)
					(name "IO_L24P_T3_A01_D17_14"
						(effects
							(font
								(size 1.27 1.27)
							)
						)
					)
					(number "W21"
						(effects
							(font
								(size 1.27 1.27)
							)
						)
					)
				)
				(pin bidirectional line
					(at 0 -125.73 0)
					(length 5.08)
					(name "IO_L24N_T3_A00_D16_14"
						(effects
							(font
								(size 1.27 1.27)
							)
						)
					)
					(number "W22"
						(effects
							(font
								(size 1.27 1.27)
							)
						)
					)
				)
				(pin bidirectional line
					(at 0 -128.27 0)
					(length 5.08)
					(name "IO_25_14"
						(effects
							(font
								(size 1.27 1.27)
							)
						)
					)
					(number "W19"
						(effects
							(font
								(size 1.27 1.27)
							)
						)
					)
				)
				(pin bidirectional line
					(at 69.85 0 180)
					(length 5.08)
					(name "VCCO_15"
						(effects
							(font
								(size 1.27 1.27)
							)
						)
					)
					(number "J25"
						(effects
							(font
								(size 1.27 1.27)
							)
						)
					)
				)
				(pin passive line
					(at 69.85 0 180)
					(length 5.08)
					(hide yes)
					(name "VCCO_15"
						(effects
							(font
								(size 1.27 1.27)
							)
						)
					)
					(number "K22"
						(effects
							(font
								(size 1.27 1.27)
							)
						)
					)
				)
				(pin passive line
					(at 69.85 0 180)
					(length 5.08)
					(hide yes)
					(name "VCCO_15"
						(effects
							(font
								(size 1.27 1.27)
							)
						)
					)
					(number "L29"
						(effects
							(font
								(size 1.27 1.27)
							)
						)
					)
				)
				(pin passive line
					(at 69.85 0 180)
					(length 5.08)
					(hide yes)
					(name "VCCO_15"
						(effects
							(font
								(size 1.27 1.27)
							)
						)
					)
					(number "M26"
						(effects
							(font
								(size 1.27 1.27)
							)
						)
					)
				)
				(pin passive line
					(at 69.85 0 180)
					(length 5.08)
					(hide yes)
					(name "VCCO_15"
						(effects
							(font
								(size 1.27 1.27)
							)
						)
					)
					(number "N23"
						(effects
							(font
								(size 1.27 1.27)
							)
						)
					)
				)
				(pin passive line
					(at 69.85 0 180)
					(length 5.08)
					(hide yes)
					(name "VCCO_15"
						(effects
							(font
								(size 1.27 1.27)
							)
						)
					)
					(number "P20"
						(effects
							(font
								(size 1.27 1.27)
							)
						)
					)
				)
				(pin bidirectional line
					(at 69.85 -3.81 180)
					(length 5.08)
					(name "IO_0_15"
						(effects
							(font
								(size 1.27 1.27)
							)
						)
					)
					(number "M19"
						(effects
							(font
								(size 1.27 1.27)
							)
						)
					)
				)
				(pin bidirectional line
					(at 69.85 -6.35 180)
					(length 5.08)
					(name "IO_L1P_T0_AD0P_15"
						(effects
							(font
								(size 1.27 1.27)
							)
						)
					)
					(number "J23"
						(effects
							(font
								(size 1.27 1.27)
							)
						)
					)
				)
				(pin bidirectional line
					(at 69.85 -8.89 180)
					(length 5.08)
					(name "IO_L1N_T0_AD0N_15"
						(effects
							(font
								(size 1.27 1.27)
							)
						)
					)
					(number "J24"
						(effects
							(font
								(size 1.27 1.27)
							)
						)
					)
				)
				(pin bidirectional line
					(at 69.85 -11.43 180)
					(length 5.08)
					(name "IO_L2P_T0_AD8P_15"
						(effects
							(font
								(size 1.27 1.27)
							)
						)
					)
					(number "L22"
						(effects
							(font
								(size 1.27 1.27)
							)
						)
					)
				)
				(pin bidirectional line
					(at 69.85 -13.97 180)
					(length 5.08)
					(name "IO_L2N_T0_AD8N_15"
						(effects
							(font
								(size 1.27 1.27)
							)
						)
					)
					(number "L23"
						(effects
							(font
								(size 1.27 1.27)
							)
						)
					)
				)
				(pin bidirectional line
					(at 69.85 -16.51 180)
					(length 5.08)
					(name "IO_L3P_T0_DQS_AD1P_15"
						(effects
							(font
								(size 1.27 1.27)
							)
						)
					)
					(number "K23"
						(effects
							(font
								(size 1.27 1.27)
							)
						)
					)
				)
				(pin bidirectional line
					(at 69.85 -19.05 180)
					(length 5.08)
					(name "IO_L3N_T0_DQS_AD1N_15"
						(effects
							(font
								(size 1.27 1.27)
							)
						)
					)
					(number "K24"
						(effects
							(font
								(size 1.27 1.27)
							)
						)
					)
				)
				(pin bidirectional line
					(at 69.85 -21.59 180)
					(length 5.08)
					(name "IO_L4P_T0_AD9P_15"
						(effects
							(font
								(size 1.27 1.27)
							)
						)
					)
					(number "L21"
						(effects
							(font
								(size 1.27 1.27)
							)
						)
					)
				)
				(pin bidirectional line
					(at 69.85 -24.13 180)
					(length 5.08)
					(name "IO_L4N_T0_AD9N_15"
						(effects
							(font
								(size 1.27 1.27)
							)
						)
					)
					(number "K21"
						(effects
							(font
								(size 1.27 1.27)
							)
						)
					)
				)
				(pin bidirectional line
					(at 69.85 -26.67 180)
					(length 5.08)
					(name "IO_L5P_T0_AD2P_15"
						(effects
							(font
								(size 1.27 1.27)
							)
						)
					)
					(number "J21"
						(effects
							(font
								(size 1.27 1.27)
							)
						)
					)
				)
				(pin bidirectional line
					(at 69.85 -29.21 180)
					(length 5.08)
					(name "IO_L5N_T0_AD2N_15"
						(effects
							(font
								(size 1.27 1.27)
							)
						)
					)
					(number "J22"
						(effects
							(font
								(size 1.27 1.27)
							)
						)
					)
				)
				(pin bidirectional line
					(at 69.85 -31.75 180)
					(length 5.08)
					(name "IO_L6P_T0_15"
						(effects
							(font
								(size 1.27 1.27)
							)
						)
					)
					(number "M20"
						(effects
							(font
								(size 1.27 1.27)
							)
						)
					)
				)
				(pin bidirectional line
					(at 69.85 -34.29 180)
					(length 5.08)
					(name "IO_L6N_T0_VREF_15"
						(effects
							(font
								(size 1.27 1.27)
							)
						)
					)
					(number "L20"
						(effects
							(font
								(size 1.27 1.27)
							)
						)
					)
				)
				(pin bidirectional line
					(at 69.85 -36.83 180)
					(length 5.08)
					(name "IO_L7P_T1_AD10P_15"
						(effects
							(font
								(size 1.27 1.27)
							)
						)
					)
					(number "J29"
						(effects
							(font
								(size 1.27 1.27)
							)
						)
					)
				)
				(pin bidirectional line
					(at 69.85 -39.37 180)
					(length 5.08)
					(name "IO_L7N_T1_AD10N_15"
						(effects
							(font
								(size 1.27 1.27)
							)
						)
					)
					(number "H29"
						(effects
							(font
								(size 1.27 1.27)
							)
						)
					)
				)
				(pin bidirectional line
					(at 69.85 -41.91 180)
					(length 5.08)
					(name "IO_L8P_T1_AD3P_15"
						(effects
							(font
								(size 1.27 1.27)
							)
						)
					)
					(number "J27"
						(effects
							(font
								(size 1.27 1.27)
							)
						)
					)
				)
				(pin bidirectional line
					(at 69.85 -44.45 180)
					(length 5.08)
					(name "IO_L8N_T1_AD3N_15"
						(effects
							(font
								(size 1.27 1.27)
							)
						)
					)
					(number "J28"
						(effects
							(font
								(size 1.27 1.27)
							)
						)
					)
				)
				(pin bidirectional line
					(at 69.85 -46.99 180)
					(length 5.08)
					(name "IO_L9P_T1_DQS_AD11P_15"
						(effects
							(font
								(size 1.27 1.27)
							)
						)
					)
					(number "L30"
						(effects
							(font
								(size 1.27 1.27)
							)
						)
					)
				)
				(pin bidirectional line
					(at 69.85 -49.53 180)
					(length 5.08)
					(name "IO_L9N_T1_DQS_AD11N_15"
						(effects
							(font
								(size 1.27 1.27)
							)
						)
					)
					(number "K30"
						(effects
							(font
								(size 1.27 1.27)
							)
						)
					)
				)
				(pin bidirectional line
					(at 69.85 -52.07 180)
					(length 5.08)
					(name "IO_L10P_T1_AD4P_15"
						(effects
							(font
								(size 1.27 1.27)
							)
						)
					)
					(number "K26"
						(effects
							(font
								(size 1.27 1.27)
							)
						)
					)
				)
				(pin bidirectional line
					(at 69.85 -54.61 180)
					(length 5.08)
					(name "IO_L10N_T1_AD4N_15"
						(effects
							(font
								(size 1.27 1.27)
							)
						)
					)
					(number "J26"
						(effects
							(font
								(size 1.27 1.27)
							)
						)
					)
				)
				(pin bidirectional line
					(at 69.85 -57.15 180)
					(length 5.08)
					(name "IO_L11P_T1_SRCC_AD12P_15"
						(effects
							(font
								(size 1.27 1.27)
							)
						)
					)
					(number "L26"
						(effects
							(font
								(size 1.27 1.27)
							)
						)
					)
				)
				(pin bidirectional line
					(at 69.85 -59.69 180)
					(length 5.08)
					(name "IO_L11N_T1_SRCC_AD12N_15"
						(effects
							(font
								(size 1.27 1.27)
							)
						)
					)
					(number "L27"
						(effects
							(font
								(size 1.27 1.27)
							)
						)
					)
				)
				(pin bidirectional line
					(at 69.85 -62.23 180)
					(length 5.08)
					(name "IO_L12P_T1_MRCC_AD5P_15"
						(effects
							(font
								(size 1.27 1.27)
							)
						)
					)
					(number "L25"
						(effects
							(font
								(size 1.27 1.27)
							)
						)
					)
				)
				(pin bidirectional line
					(at 69.85 -64.77 180)
					(length 5.08)
					(name "IO_L12N_T1_MRCC_AD5N_15"
						(effects
							(font
								(size 1.27 1.27)
							)
						)
					)
					(number "K25"
						(effects
							(font
								(size 1.27 1.27)
							)
						)
					)
				)
				(pin bidirectional line
					(at 69.85 -67.31 180)
					(length 5.08)
					(name "IO_L13P_T2_MRCC_15"
						(effects
							(font
								(size 1.27 1.27)
							)
						)
					)
					(number "K28"
						(effects
							(font
								(size 1.27 1.27)
							)
						)
					)
				)
				(pin bidirectional line
					(at 69.85 -69.85 180)
					(length 5.08)
					(name "IO_L13N_T2_MRCC_15"
						(effects
							(font
								(size 1.27 1.27)
							)
						)
					)
					(number "K29"
						(effects
							(font
								(size 1.27 1.27)
							)
						)
					)
				)
				(pin bidirectional line
					(at 69.85 -72.39 180)
					(length 5.08)
					(name "IO_L14P_T2_SRCC_15"
						(effects
							(font
								(size 1.27 1.27)
							)
						)
					)
					(number "M28"
						(effects
							(font
								(size 1.27 1.27)
							)
						)
					)
				)
				(pin bidirectional line
					(at 69.85 -74.93 180)
					(length 5.08)
					(name "IO_L14N_T2_SRCC_15"
						(effects
							(font
								(size 1.27 1.27)
							)
						)
					)
					(number "L28"
						(effects
							(font
								(size 1.27 1.27)
							)
						)
					)
				)
				(pin bidirectional line
					(at 69.85 -77.47 180)
					(length 5.08)
					(name "IO_L15P_T2_DQS_15"
						(effects
							(font
								(size 1.27 1.27)
							)
						)
					)
					(number "M29"
						(effects
							(font
								(size 1.27 1.27)
							)
						)
					)
				)
				(pin bidirectional line
					(at 69.85 -80.01 180)
					(length 5.08)
					(name "IO_L15N_T2_DQS_ADV_B_15"
						(effects
							(font
								(size 1.27 1.27)
							)
						)
					)
					(number "M30"
						(effects
							(font
								(size 1.27 1.27)
							)
						)
					)
				)
				(pin bidirectional line
					(at 69.85 -82.55 180)
					(length 5.08)
					(name "IO_L16P_T2_A28_15"
						(effects
							(font
								(size 1.27 1.27)
							)
						)
					)
					(number "N27"
						(effects
							(font
								(size 1.27 1.27)
							)
						)
					)
				)
				(pin bidirectional line
					(at 69.85 -85.09 180)
					(length 5.08)
					(name "IO_L16N_T2_A27_15"
						(effects
							(font
								(size 1.27 1.27)
							)
						)
					)
					(number "M27"
						(effects
							(font
								(size 1.27 1.27)
							)
						)
					)
				)
				(pin bidirectional line
					(at 69.85 -87.63 180)
					(length 5.08)
					(name "IO_L17P_T2_A26_15"
						(effects
							(font
								(size 1.27 1.27)
							)
						)
					)
					(number "N29"
						(effects
							(font
								(size 1.27 1.27)
							)
						)
					)
				)
				(pin bidirectional line
					(at 69.85 -90.17 180)
					(length 5.08)
					(name "IO_L17N_T2_A25_15"
						(effects
							(font
								(size 1.27 1.27)
							)
						)
					)
					(number "N30"
						(effects
							(font
								(size 1.27 1.27)
							)
						)
					)
				)
				(pin bidirectional line
					(at 69.85 -92.71 180)
					(length 5.08)
					(name "IO_L18P_T2_A24_15"
						(effects
							(font
								(size 1.27 1.27)
							)
						)
					)
					(number "N25"
						(effects
							(font
								(size 1.27 1.27)
							)
						)
					)
				)
				(pin bidirectional line
					(at 69.85 -95.25 180)
					(length 5.08)
					(name "IO_L18N_T2_A23_15"
						(effects
							(font
								(size 1.27 1.27)
							)
						)
					)
					(number "N26"
						(effects
							(font
								(size 1.27 1.27)
							)
						)
					)
				)
				(pin bidirectional line
					(at 69.85 -97.79 180)
					(length 5.08)
					(name "IO_L19P_T3_A22_15"
						(effects
							(font
								(size 1.27 1.27)
							)
						)
					)
					(number "N19"
						(effects
							(font
								(size 1.27 1.27)
							)
						)
					)
				)
				(pin bidirectional line
					(at 69.85 -100.33 180)
					(length 5.08)
					(name "IO_L19N_T3_A21_VREF_15"
						(effects
							(font
								(size 1.27 1.27)
							)
						)
					)
					(number "N20"
						(effects
							(font
								(size 1.27 1.27)
							)
						)
					)
				)
				(pin bidirectional line
					(at 69.85 -102.87 180)
					(length 5.08)
					(name "IO_L20P_T3_A20_15"
						(effects
							(font
								(size 1.27 1.27)
							)
						)
					)
					(number "N21"
						(effects
							(font
								(size 1.27 1.27)
							)
						)
					)
				)
				(pin bidirectional line
					(at 69.85 -105.41 180)
					(length 5.08)
					(name "IO_L20N_T3_A19_15"
						(effects
							(font
								(size 1.27 1.27)
							)
						)
					)
					(number "N22"
						(effects
							(font
								(size 1.27 1.27)
							)
						)
					)
				)
				(pin bidirectional line
					(at 69.85 -107.95 180)
					(length 5.08)
					(name "IO_L21P_T3_DQS_15"
						(effects
							(font
								(size 1.27 1.27)
							)
						)
					)
					(number "P23"
						(effects
							(font
								(size 1.27 1.27)
							)
						)
					)
				)
				(pin bidirectional line
					(at 69.85 -110.49 180)
					(length 5.08)
					(name "IO_L21N_T3_DQS_A18_15"
						(effects
							(font
								(size 1.27 1.27)
							)
						)
					)
					(number "N24"
						(effects
							(font
								(size 1.27 1.27)
							)
						)
					)
				)
				(pin bidirectional line
					(at 69.85 -113.03 180)
					(length 5.08)
					(name "IO_L22P_T3_A17_15"
						(effects
							(font
								(size 1.27 1.27)
							)
						)
					)
					(number "P21"
						(effects
							(font
								(size 1.27 1.27)
							)
						)
					)
				)
				(pin bidirectional line
					(at 69.85 -115.57 180)
					(length 5.08)
					(name "IO_L22N_T3_A16_15"
						(effects
							(font
								(size 1.27 1.27)
							)
						)
					)
					(number "P22"
						(effects
							(font
								(size 1.27 1.27)
							)
						)
					)
				)
				(pin bidirectional line
					(at 69.85 -118.11 180)
					(length 5.08)
					(name "IO_L23P_T3_FOE_B_15"
						(effects
							(font
								(size 1.27 1.27)
							)
						)
					)
					(number "M24"
						(effects
							(font
								(size 1.27 1.27)
							)
						)
					)
				)
				(pin bidirectional line
					(at 69.85 -120.65 180)
					(length 5.08)
					(name "IO_L23N_T3_FWE_B_15"
						(effects
							(font
								(size 1.27 1.27)
							)
						)
					)
					(number "M25"
						(effects
							(font
								(size 1.27 1.27)
							)
						)
					)
				)
				(pin bidirectional line
					(at 69.85 -123.19 180)
					(length 5.08)
					(name "IO_L24P_T3_RS1_15"
						(effects
							(font
								(size 1.27 1.27)
							)
						)
					)
					(number "M22"
						(effects
							(font
								(size 1.27 1.27)
							)
						)
					)
				)
				(pin bidirectional line
					(at 69.85 -125.73 180)
					(length 5.08)
					(name "IO_L24N_T3_RS0_15"
						(effects
							(font
								(size 1.27 1.27)
							)
						)
					)
					(number "M23"
						(effects
							(font
								(size 1.27 1.27)
							)
						)
					)
				)
				(pin bidirectional line
					(at 69.85 -128.27 180)
					(length 5.08)
					(name "IO_25_15"
						(effects
							(font
								(size 1.27 1.27)
							)
						)
					)
					(number "P19"
						(effects
							(font
								(size 1.27 1.27)
							)
						)
					)
				)
			)
			(symbol "XC7K410T-2FFG900I_3_3_1"
				(rectangle
					(start 5.08 5.08)
					(end 49.53 -130.81)
					(stroke
						(width 0.254)
						(type default)
					)
					(fill
						(type background)
					)
				)
				(text "BANK 16"
					(at 15.24 2.54 0)
					(effects
						(font
							(size 1.27 1.27)
							(thickness 0.15)
						)
						(justify left bottom)
					)
				)
				(text "BANK 17"
					(at 30.48 2.54 0)
					(effects
						(font
							(size 1.27 1.27)
							(thickness 0.15)
						)
						(justify left bottom)
					)
				)
				(pin bidirectional line
					(at 0 0 0)
					(length 5.08)
					(name "VCCO_16"
						(effects
							(font
								(size 1.27 1.27)
							)
						)
					)
					(number "A29"
						(effects
							(font
								(size 1.27 1.27)
							)
						)
					)
				)
				(pin passive line
					(at 0 0 0)
					(length 5.08)
					(hide yes)
					(name "VCCO_16"
						(effects
							(font
								(size 1.27 1.27)
							)
						)
					)
					(number "B26"
						(effects
							(font
								(size 1.27 1.27)
							)
						)
					)
				)
				(pin passive line
					(at 0 0 0)
					(length 5.08)
					(hide yes)
					(name "VCCO_16"
						(effects
							(font
								(size 1.27 1.27)
							)
						)
					)
					(number "C23"
						(effects
							(font
								(size 1.27 1.27)
							)
						)
					)
				)
				(pin passive line
					(at 0 0 0)
					(length 5.08)
					(hide yes)
					(name "VCCO_16"
						(effects
							(font
								(size 1.27 1.27)
							)
						)
					)
					(number "D30"
						(effects
							(font
								(size 1.27 1.27)
							)
						)
					)
				)
				(pin passive line
					(at 0 0 0)
					(length 5.08)
					(hide yes)
					(name "VCCO_16"
						(effects
							(font
								(size 1.27 1.27)
							)
						)
					)
					(number "E27"
						(effects
							(font
								(size 1.27 1.27)
							)
						)
					)
				)
				(pin passive line
					(at 0 0 0)
					(length 5.08)
					(hide yes)
					(name "VCCO_16"
						(effects
							(font
								(size 1.27 1.27)
							)
						)
					)
					(number "F24"
						(effects
							(font
								(size 1.27 1.27)
							)
						)
					)
				)
				(pin passive line
					(at 0 0 0)
					(length 5.08)
					(hide yes)
					(name "VCCO_16"
						(effects
							(font
								(size 1.27 1.27)
							)
						)
					)
					(number "H28"
						(effects
							(font
								(size 1.27 1.27)
							)
						)
					)
				)
				(pin bidirectional line
					(at 0 -3.81 0)
					(length 5.08)
					(name "IO_0_16"
						(effects
							(font
								(size 1.27 1.27)
							)
						)
					)
					(number "F23"
						(effects
							(font
								(size 1.27 1.27)
							)
						)
					)
				)
				(pin bidirectional line
					(at 0 -6.35 0)
					(length 5.08)
					(name "IO_L1P_T0_16"
						(effects
							(font
								(size 1.27 1.27)
							)
						)
					)
					(number "B23"
						(effects
							(font
								(size 1.27 1.27)
							)
						)
					)
				)
				(pin bidirectional line
					(at 0 -8.89 0)
					(length 5.08)
					(name "IO_L1N_T0_16"
						(effects
							(font
								(size 1.27 1.27)
							)
						)
					)
					(number "A23"
						(effects
							(font
								(size 1.27 1.27)
							)
						)
					)
				)
				(pin bidirectional line
					(at 0 -11.43 0)
					(length 5.08)
					(name "IO_L2P_T0_16"
						(effects
							(font
								(size 1.27 1.27)
							)
						)
					)
					(number "E23"
						(effects
							(font
								(size 1.27 1.27)
							)
						)
					)
				)
				(pin bidirectional line
					(at 0 -13.97 0)
					(length 5.08)
					(name "IO_L2N_T0_16"
						(effects
							(font
								(size 1.27 1.27)
							)
						)
					)
					(number "D23"
						(effects
							(font
								(size 1.27 1.27)
							)
						)
					)
				)
				(pin bidirectional line
					(at 0 -16.51 0)
					(length 5.08)
					(name "IO_L3P_T0_DQS_16"
						(effects
							(font
								(size 1.27 1.27)
							)
						)
					)
					(number "F25"
						(effects
							(font
								(size 1.27 1.27)
							)
						)
					)
				)
				(pin bidirectional line
					(at 0 -19.05 0)
					(length 5.08)
					(name "IO_L3N_T0_DQS_16"
						(effects
							(font
								(size 1.27 1.27)
							)
						)
					)
					(number "E25"
						(effects
							(font
								(size 1.27 1.27)
							)
						)
					)
				)
				(pin bidirectional line
					(at 0 -21.59 0)
					(length 5.08)
					(name "IO_L4P_T0_16"
						(effects
							(font
								(size 1.27 1.27)
							)
						)
					)
					(number "E24"
						(effects
							(font
								(size 1.27 1.27)
							)
						)
					)
				)
				(pin bidirectional line
					(at 0 -24.13 0)
					(length 5.08)
					(name "IO_L4N_T0_16"
						(effects
							(font
								(size 1.27 1.27)
							)
						)
					)
					(number "D24"
						(effects
							(font
								(size 1.27 1.27)
							)
						)
					)
				)
				(pin bidirectional line
					(at 0 -26.67 0)
					(length 5.08)
					(name "IO_L5P_T0_16"
						(effects
							(font
								(size 1.27 1.27)
							)
						)
					)
					(number "F26"
						(effects
							(font
								(size 1.27 1.27)
							)
						)
					)
				)
				(pin bidirectional line
					(at 0 -29.21 0)
					(length 5.08)
					(name "IO_L5N_T0_16"
						(effects
							(font
								(size 1.27 1.27)
							)
						)
					)
					(number "E26"
						(effects
							(font
								(size 1.27 1.27)
							)
						)
					)
				)
				(pin bidirectional line
					(at 0 -31.75 0)
					(length 5.08)
					(name "IO_L6P_T0_16"
						(effects
							(font
								(size 1.27 1.27)
							)
						)
					)
					(number "G23"
						(effects
							(font
								(size 1.27 1.27)
							)
						)
					)
				)
				(pin bidirectional line
					(at 0 -34.29 0)
					(length 5.08)
					(name "IO_L6N_T0_VREF_16"
						(effects
							(font
								(size 1.27 1.27)
							)
						)
					)
					(number "G24"
						(effects
							(font
								(size 1.27 1.27)
							)
						)
					)
				)
				(pin bidirectional line
					(at 0 -36.83 0)
					(length 5.08)
					(name "IO_L7P_T1_16"
						(effects
							(font
								(size 1.27 1.27)
							)
						)
					)
					(number "B27"
						(effects
							(font
								(size 1.27 1.27)
							)
						)
					)
				)
				(pin bidirectional line
					(at 0 -39.37 0)
					(length 5.08)
					(name "IO_L7N_T1_16"
						(effects
							(font
								(size 1.27 1.27)
							)
						)
					)
					(number "A27"
						(effects
							(font
								(size 1.27 1.27)
							)
						)
					)
				)
				(pin bidirectional line
					(at 0 -41.91 0)
					(length 5.08)
					(name "IO_L8P_T1_16"
						(effects
							(font
								(size 1.27 1.27)
							)
						)
					)
					(number "C24"
						(effects
							(font
								(size 1.27 1.27)
							)
						)
					)
				)
				(pin bidirectional line
					(at 0 -44.45 0)
					(length 5.08)
					(name "IO_L8N_T1_16"
						(effects
							(font
								(size 1.27 1.27)
							)
						)
					)
					(number "B24"
						(effects
							(font
								(size 1.27 1.27)
							)
						)
					)
				)
				(pin bidirectional line
					(at 0 -46.99 0)
					(length 5.08)
					(name "IO_L9P_T1_DQS_16"
						(effects
							(font
								(size 1.27 1.27)
							)
						)
					)
					(number "B28"
						(effects
							(font
								(size 1.27 1.27)
							)
						)
					)
				)
				(pin bidirectional line
					(at 0 -49.53 0)
					(length 5.08)
					(name "IO_L9N_T1_DQS_16"
						(effects
							(font
								(size 1.27 1.27)
							)
						)
					)
					(number "A28"
						(effects
							(font
								(size 1.27 1.27)
							)
						)
					)
				)
				(pin bidirectional line
					(at 0 -52.07 0)
					(length 5.08)
					(name "IO_L10P_T1_16"
						(effects
							(font
								(size 1.27 1.27)
							)
						)
					)
					(number "A25"
						(effects
							(font
								(size 1.27 1.27)
							)
						)
					)
				)
				(pin bidirectional line
					(at 0 -54.61 0)
					(length 5.08)
					(name "IO_L10N_T1_16"
						(effects
							(font
								(size 1.27 1.27)
							)
						)
					)
					(number "A26"
						(effects
							(font
								(size 1.27 1.27)
							)
						)
					)
				)
				(pin bidirectional line
					(at 0 -57.15 0)
					(length 5.08)
					(name "IO_L11P_T1_SRCC_16"
						(effects
							(font
								(size 1.27 1.27)
							)
						)
					)
					(number "D26"
						(effects
							(font
								(size 1.27 1.27)
							)
						)
					)
				)
				(pin bidirectional line
					(at 0 -59.69 0)
					(length 5.08)
					(name "IO_L11N_T1_SRCC_16"
						(effects
							(font
								(size 1.27 1.27)
							)
						)
					)
					(number "C26"
						(effects
							(font
								(size 1.27 1.27)
							)
						)
					)
				)
				(pin bidirectional line
					(at 0 -62.23 0)
					(length 5.08)
					(name "IO_L12P_T1_MRCC_16"
						(effects
							(font
								(size 1.27 1.27)
							)
						)
					)
					(number "C25"
						(effects
							(font
								(size 1.27 1.27)
							)
						)
					)
				)
				(pin bidirectional line
					(at 0 -64.77 0)
					(length 5.08)
					(name "IO_L12N_T1_MRCC_16"
						(effects
							(font
								(size 1.27 1.27)
							)
						)
					)
					(number "B25"
						(effects
							(font
								(size 1.27 1.27)
							)
						)
					)
				)
				(pin bidirectional line
					(at 0 -67.31 0)
					(length 5.08)
					(name "IO_L13P_T2_MRCC_16"
						(effects
							(font
								(size 1.27 1.27)
							)
						)
					)
					(number "D27"
						(effects
							(font
								(size 1.27 1.27)
							)
						)
					)
				)
				(pin bidirectional line
					(at 0 -69.85 0)
					(length 5.08)
					(name "IO_L13N_T2_MRCC_16"
						(effects
							(font
								(size 1.27 1.27)
							)
						)
					)
					(number "C27"
						(effects
							(font
								(size 1.27 1.27)
							)
						)
					)
				)
				(pin bidirectional line
					(at 0 -72.39 0)
					(length 5.08)
					(name "IO_L14P_T2_SRCC_16"
						(effects
							(font
								(size 1.27 1.27)
							)
						)
					)
					(number "E28"
						(effects
							(font
								(size 1.27 1.27)
							)
						)
					)
				)
				(pin bidirectional line
					(at 0 -74.93 0)
					(length 5.08)
					(name "IO_L14N_T2_SRCC_16"
						(effects
							(font
								(size 1.27 1.27)
							)
						)
					)
					(number "D28"
						(effects
							(font
								(size 1.27 1.27)
							)
						)
					)
				)
				(pin bidirectional line
					(at 0 -77.47 0)
					(length 5.08)
					(name "IO_L15P_T2_DQS_16"
						(effects
							(font
								(size 1.27 1.27)
							)
						)
					)
					(number "C29"
						(effects
							(font
								(size 1.27 1.27)
							)
						)
					)
				)
				(pin bidirectional line
					(at 0 -80.01 0)
					(length 5.08)
					(name "IO_L15N_T2_DQS_16"
						(effects
							(font
								(size 1.27 1.27)
							)
						)
					)
					(number "B29"
						(effects
							(font
								(size 1.27 1.27)
							)
						)
					)
				)
				(pin bidirectional line
					(at 0 -82.55 0)
					(length 5.08)
					(name "IO_L16P_T2_16"
						(effects
							(font
								(size 1.27 1.27)
							)
						)
					)
					(number "D29"
						(effects
							(font
								(size 1.27 1.27)
							)
						)
					)
				)
				(pin bidirectional line
					(at 0 -85.09 0)
					(length 5.08)
					(name "IO_L16N_T2_16"
						(effects
							(font
								(size 1.27 1.27)
							)
						)
					)
					(number "C30"
						(effects
							(font
								(size 1.27 1.27)
							)
						)
					)
				)
				(pin bidirectional line
					(at 0 -87.63 0)
					(length 5.08)
					(name "IO_L17P_T2_16"
						(effects
							(font
								(size 1.27 1.27)
							)
						)
					)
					(number "B30"
						(effects
							(font
								(size 1.27 1.27)
							)
						)
					)
				)
				(pin bidirectional line
					(at 0 -90.17 0)
					(length 5.08)
					(name "IO_L17N_T2_16"
						(effects
							(font
								(size 1.27 1.27)
							)
						)
					)
					(number "A30"
						(effects
							(font
								(size 1.27 1.27)
							)
						)
					)
				)
				(pin bidirectional line
					(at 0 -92.71 0)
					(length 5.08)
					(name "IO_L18P_T2_16"
						(effects
							(font
								(size 1.27 1.27)
							)
						)
					)
					(number "E29"
						(effects
							(font
								(size 1.27 1.27)
							)
						)
					)
				)
				(pin bidirectional line
					(at 0 -95.25 0)
					(length 5.08)
					(name "IO_L18N_T2_16"
						(effects
							(font
								(size 1.27 1.27)
							)
						)
					)
					(number "E30"
						(effects
							(font
								(size 1.27 1.27)
							)
						)
					)
				)
				(pin bidirectional line
					(at 0 -97.79 0)
					(length 5.08)
					(name "IO_L19P_T3_16"
						(effects
							(font
								(size 1.27 1.27)
							)
						)
					)
					(number "H24"
						(effects
							(font
								(size 1.27 1.27)
							)
						)
					)
				)
				(pin bidirectional line
					(at 0 -100.33 0)
					(length 5.08)
					(name "IO_L19N_T3_VREF_16"
						(effects
							(font
								(size 1.27 1.27)
							)
						)
					)
					(number "H25"
						(effects
							(font
								(size 1.27 1.27)
							)
						)
					)
				)
				(pin bidirectional line
					(at 0 -102.87 0)
					(length 5.08)
					(name "IO_L20P_T3_16"
						(effects
							(font
								(size 1.27 1.27)
							)
						)
					)
					(number "G28"
						(effects
							(font
								(size 1.27 1.27)
							)
						)
					)
				)
				(pin bidirectional line
					(at 0 -105.41 0)
					(length 5.08)
					(name "IO_L20N_T3_16"
						(effects
							(font
								(size 1.27 1.27)
							)
						)
					)
					(number "F28"
						(effects
							(font
								(size 1.27 1.27)
							)
						)
					)
				)
				(pin bidirectional line
					(at 0 -107.95 0)
					(length 5.08)
					(name "IO_L21P_T3_DQS_16"
						(effects
							(font
								(size 1.27 1.27)
							)
						)
					)
					(number "G27"
						(effects
							(font
								(size 1.27 1.27)
							)
						)
					)
				)
				(pin bidirectional line
					(at 0 -110.49 0)
					(length 5.08)
					(name "IO_L21N_T3_DQS_16"
						(effects
							(font
								(size 1.27 1.27)
							)
						)
					)
					(number "F27"
						(effects
							(font
								(size 1.27 1.27)
							)
						)
					)
				)
				(pin bidirectional line
					(at 0 -113.03 0)
					(length 5.08)
					(name "IO_L22P_T3_16"
						(effects
							(font
								(size 1.27 1.27)
							)
						)
					)
					(number "G29"
						(effects
							(font
								(size 1.27 1.27)
							)
						)
					)
				)
				(pin bidirectional line
					(at 0 -115.57 0)
					(length 5.08)
					(name "IO_L22N_T3_16"
						(effects
							(font
								(size 1.27 1.27)
							)
						)
					)
					(number "F30"
						(effects
							(font
								(size 1.27 1.27)
							)
						)
					)
				)
				(pin bidirectional line
					(at 0 -118.11 0)
					(length 5.08)
					(name "IO_L23P_T3_16"
						(effects
							(font
								(size 1.27 1.27)
							)
						)
					)
					(number "H26"
						(effects
							(font
								(size 1.27 1.27)
							)
						)
					)
				)
				(pin bidirectional line
					(at 0 -120.65 0)
					(length 5.08)
					(name "IO_L23N_T3_16"
						(effects
							(font
								(size 1.27 1.27)
							)
						)
					)
					(number "H27"
						(effects
							(font
								(size 1.27 1.27)
							)
						)
					)
				)
				(pin bidirectional line
					(at 0 -123.19 0)
					(length 5.08)
					(name "IO_L24P_T3_16"
						(effects
							(font
								(size 1.27 1.27)
							)
						)
					)
					(number "H30"
						(effects
							(font
								(size 1.27 1.27)
							)
						)
					)
				)
				(pin bidirectional line
					(at 0 -125.73 0)
					(length 5.08)
					(name "IO_L24N_T3_16"
						(effects
							(font
								(size 1.27 1.27)
							)
						)
					)
					(number "G30"
						(effects
							(font
								(size 1.27 1.27)
							)
						)
					)
				)
				(pin bidirectional line
					(at 0 -128.27 0)
					(length 5.08)
					(name "IO_25_16"
						(effects
							(font
								(size 1.27 1.27)
							)
						)
					)
					(number "G25"
						(effects
							(font
								(size 1.27 1.27)
							)
						)
					)
				)
				(pin bidirectional line
					(at 54.61 0 180)
					(length 5.08)
					(name "VCCO_17"
						(effects
							(font
								(size 1.27 1.27)
							)
						)
					)
					(number "A19"
						(effects
							(font
								(size 1.27 1.27)
							)
						)
					)
				)
				(pin passive line
					(at 54.61 0 180)
					(length 5.08)
					(hide yes)
					(name "VCCO_17"
						(effects
							(font
								(size 1.27 1.27)
							)
						)
					)
					(number "B16"
						(effects
							(font
								(size 1.27 1.27)
							)
						)
					)
				)
				(pin passive line
					(at 54.61 0 180)
					(length 5.08)
					(hide yes)
					(name "VCCO_17"
						(effects
							(font
								(size 1.27 1.27)
							)
						)
					)
					(number "D20"
						(effects
							(font
								(size 1.27 1.27)
							)
						)
					)
				)
				(pin passive line
					(at 54.61 0 180)
					(length 5.08)
					(hide yes)
					(name "VCCO_17"
						(effects
							(font
								(size 1.27 1.27)
							)
						)
					)
					(number "E17"
						(effects
							(font
								(size 1.27 1.27)
							)
						)
					)
				)
				(pin passive line
					(at 54.61 0 180)
					(length 5.08)
					(hide yes)
					(name "VCCO_17"
						(effects
							(font
								(size 1.27 1.27)
							)
						)
					)
					(number "G21"
						(effects
							(font
								(size 1.27 1.27)
							)
						)
					)
				)
				(pin passive line
					(at 54.61 0 180)
					(length 5.08)
					(hide yes)
					(name "VCCO_17"
						(effects
							(font
								(size 1.27 1.27)
							)
						)
					)
					(number "H18"
						(effects
							(font
								(size 1.27 1.27)
							)
						)
					)
				)
				(pin passive line
					(at 54.61 0 180)
					(length 5.08)
					(hide yes)
					(name "VCCO_17"
						(effects
							(font
								(size 1.27 1.27)
							)
						)
					)
					(number "L19"
						(effects
							(font
								(size 1.27 1.27)
							)
						)
					)
				)
				(pin bidirectional line
					(at 54.61 -3.81 180)
					(length 5.08)
					(name "IO_0_17"
						(effects
							(font
								(size 1.27 1.27)
							)
						)
					)
					(number "G19"
						(effects
							(font
								(size 1.27 1.27)
							)
						)
					)
				)
				(pin bidirectional line
					(at 54.61 -6.35 180)
					(length 5.08)
					(name "IO_L1P_T0_17"
						(effects
							(font
								(size 1.27 1.27)
							)
						)
					)
					(number "K18"
						(effects
							(font
								(size 1.27 1.27)
							)
						)
					)
				)
				(pin bidirectional line
					(at 54.61 -8.89 180)
					(length 5.08)
					(name "IO_L1N_T0_17"
						(effects
							(font
								(size 1.27 1.27)
							)
						)
					)
					(number "J18"
						(effects
							(font
								(size 1.27 1.27)
							)
						)
					)
				)
				(pin bidirectional line
					(at 54.61 -11.43 180)
					(length 5.08)
					(name "IO_L2P_T0_17"
						(effects
							(font
								(size 1.27 1.27)
							)
						)
					)
					(number "H20"
						(effects
							(font
								(size 1.27 1.27)
							)
						)
					)
				)
				(pin bidirectional line
					(at 54.61 -13.97 180)
					(length 5.08)
					(name "IO_L2N_T0_17"
						(effects
							(font
								(size 1.27 1.27)
							)
						)
					)
					(number "G20"
						(effects
							(font
								(size 1.27 1.27)
							)
						)
					)
				)
				(pin bidirectional line
					(at 54.61 -16.51 180)
					(length 5.08)
					(name "IO_L3P_T0_DQS_17"
						(effects
							(font
								(size 1.27 1.27)
							)
						)
					)
					(number "J17"
						(effects
							(font
								(size 1.27 1.27)
							)
						)
					)
				)
				(pin bidirectional line
					(at 54.61 -19.05 180)
					(length 5.08)
					(name "IO_L3N_T0_DQS_17"
						(effects
							(font
								(size 1.27 1.27)
							)
						)
					)
					(number "H17"
						(effects
							(font
								(size 1.27 1.27)
							)
						)
					)
				)
				(pin bidirectional line
					(at 54.61 -21.59 180)
					(length 5.08)
					(name "IO_L4P_T0_17"
						(effects
							(font
								(size 1.27 1.27)
							)
						)
					)
					(number "J19"
						(effects
							(font
								(size 1.27 1.27)
							)
						)
					)
				)
				(pin bidirectional line
					(at 54.61 -24.13 180)
					(length 5.08)
					(name "IO_L4N_T0_17"
						(effects
							(font
								(size 1.27 1.27)
							)
						)
					)
					(number "H19"
						(effects
							(font
								(size 1.27 1.27)
							)
						)
					)
				)
				(pin bidirectional line
					(at 54.61 -26.67 180)
					(length 5.08)
					(name "IO_L5P_T0_17"
						(effects
							(font
								(size 1.27 1.27)
							)
						)
					)
					(number "L17"
						(effects
							(font
								(size 1.27 1.27)
							)
						)
					)
				)
				(pin bidirectional line
					(at 54.61 -29.21 180)
					(length 5.08)
					(name "IO_L5N_T0_17"
						(effects
							(font
								(size 1.27 1.27)
							)
						)
					)
					(number "L18"
						(effects
							(font
								(size 1.27 1.27)
							)
						)
					)
				)
				(pin bidirectional line
					(at 54.61 -31.75 180)
					(length 5.08)
					(name "IO_L6P_T0_17"
						(effects
							(font
								(size 1.27 1.27)
							)
						)
					)
					(number "K19"
						(effects
							(font
								(size 1.27 1.27)
							)
						)
					)
				)
				(pin bidirectional line
					(at 54.61 -34.29 180)
					(length 5.08)
					(name "IO_L6N_T0_VREF_17"
						(effects
							(font
								(size 1.27 1.27)
							)
						)
					)
					(number "K20"
						(effects
							(font
								(size 1.27 1.27)
							)
						)
					)
				)
				(pin bidirectional line
					(at 54.61 -36.83 180)
					(length 5.08)
					(name "IO_L7P_T1_17"
						(effects
							(font
								(size 1.27 1.27)
							)
						)
					)
					(number "H21"
						(effects
							(font
								(size 1.27 1.27)
							)
						)
					)
				)
				(pin bidirectional line
					(at 54.61 -39.37 180)
					(length 5.08)
					(name "IO_L7N_T1_17"
						(effects
							(font
								(size 1.27 1.27)
							)
						)
					)
					(number "H22"
						(effects
							(font
								(size 1.27 1.27)
							)
						)
					)
				)
				(pin bidirectional line
					(at 54.61 -41.91 180)
					(length 5.08)
					(name "IO_L8P_T1_17"
						(effects
							(font
								(size 1.27 1.27)
							)
						)
					)
					(number "D21"
						(effects
							(font
								(size 1.27 1.27)
							)
						)
					)
				)
				(pin bidirectional line
					(at 54.61 -44.45 180)
					(length 5.08)
					(name "IO_L8N_T1_17"
						(effects
							(font
								(size 1.27 1.27)
							)
						)
					)
					(number "C21"
						(effects
							(font
								(size 1.27 1.27)
							)
						)
					)
				)
				(pin bidirectional line
					(at 54.61 -46.99 180)
					(length 5.08)
					(name "IO_L9P_T1_DQS_17"
						(effects
							(font
								(size 1.27 1.27)
							)
						)
					)
					(number "G22"
						(effects
							(font
								(size 1.27 1.27)
							)
						)
					)
				)
				(pin bidirectional line
					(at 54.61 -49.53 180)
					(length 5.08)
					(name "IO_L9N_T1_DQS_17"
						(effects
							(font
								(size 1.27 1.27)
							)
						)
					)
					(number "F22"
						(effects
							(font
								(size 1.27 1.27)
							)
						)
					)
				)
				(pin bidirectional line
					(at 54.61 -52.07 180)
					(length 5.08)
					(name "IO_L10P_T1_17"
						(effects
							(font
								(size 1.27 1.27)
							)
						)
					)
					(number "D22"
						(effects
							(font
								(size 1.27 1.27)
							)
						)
					)
				)
				(pin bidirectional line
					(at 54.61 -54.61 180)
					(length 5.08)
					(name "IO_L10N_T1_17"
						(effects
							(font
								(size 1.27 1.27)
							)
						)
					)
					(number "C22"
						(effects
							(font
								(size 1.27 1.27)
							)
						)
					)
				)
				(pin bidirectional line
					(at 54.61 -57.15 180)
					(length 5.08)
					(name "IO_L11P_T1_SRCC_17"
						(effects
							(font
								(size 1.27 1.27)
							)
						)
					)
					(number "F21"
						(effects
							(font
								(size 1.27 1.27)
							)
						)
					)
				)
				(pin bidirectional line
					(at 54.61 -59.69 180)
					(length 5.08)
					(name "IO_L11N_T1_SRCC_17"
						(effects
							(font
								(size 1.27 1.27)
							)
						)
					)
					(number "E21"
						(effects
							(font
								(size 1.27 1.27)
							)
						)
					)
				)
				(pin bidirectional line
					(at 54.61 -62.23 180)
					(length 5.08)
					(name "IO_L12P_T1_MRCC_17"
						(effects
							(font
								(size 1.27 1.27)
							)
						)
					)
					(number "F20"
						(effects
							(font
								(size 1.27 1.27)
							)
						)
					)
				)
				(pin bidirectional line
					(at 54.61 -64.77 180)
					(length 5.08)
					(name "IO_L12N_T1_MRCC_17"
						(effects
							(font
								(size 1.27 1.27)
							)
						)
					)
					(number "E20"
						(effects
							(font
								(size 1.27 1.27)
							)
						)
					)
				)
				(pin bidirectional line
					(at 54.61 -67.31 180)
					(length 5.08)
					(name "IO_L13P_T2_MRCC_17"
						(effects
							(font
								(size 1.27 1.27)
							)
						)
					)
					(number "D17"
						(effects
							(font
								(size 1.27 1.27)
							)
						)
					)
				)
				(pin bidirectional line
					(at 54.61 -69.85 180)
					(length 5.08)
					(name "IO_L13N_T2_MRCC_17"
						(effects
							(font
								(size 1.27 1.27)
							)
						)
					)
					(number "D18"
						(effects
							(font
								(size 1.27 1.27)
							)
						)
					)
				)
				(pin bidirectional line
					(at 54.61 -72.39 180)
					(length 5.08)
					(name "IO_L14P_T2_SRCC_17"
						(effects
							(font
								(size 1.27 1.27)
							)
						)
					)
					(number "E19"
						(effects
							(font
								(size 1.27 1.27)
							)
						)
					)
				)
				(pin bidirectional line
					(at 54.61 -74.93 180)
					(length 5.08)
					(name "IO_L14N_T2_SRCC_17"
						(effects
							(font
								(size 1.27 1.27)
							)
						)
					)
					(number "D19"
						(effects
							(font
								(size 1.27 1.27)
							)
						)
					)
				)
				(pin bidirectional line
					(at 54.61 -77.47 180)
					(length 5.08)
					(name "IO_L15P_T2_DQS_17"
						(effects
							(font
								(size 1.27 1.27)
							)
						)
					)
					(number "D16"
						(effects
							(font
								(size 1.27 1.27)
							)
						)
					)
				)
				(pin bidirectional line
					(at 54.61 -80.01 180)
					(length 5.08)
					(name "IO_L15N_T2_DQS_17"
						(effects
							(font
								(size 1.27 1.27)
							)
						)
					)
					(number "C16"
						(effects
							(font
								(size 1.27 1.27)
							)
						)
					)
				)
				(pin bidirectional line
					(at 54.61 -82.55 180)
					(length 5.08)
					(name "IO_L16P_T2_17"
						(effects
							(font
								(size 1.27 1.27)
							)
						)
					)
					(number "G18"
						(effects
							(font
								(size 1.27 1.27)
							)
						)
					)
				)
				(pin bidirectional line
					(at 54.61 -85.09 180)
					(length 5.08)
					(name "IO_L16N_T2_17"
						(effects
							(font
								(size 1.27 1.27)
							)
						)
					)
					(number "F18"
						(effects
							(font
								(size 1.27 1.27)
							)
						)
					)
				)
				(pin bidirectional line
					(at 54.61 -87.63 180)
					(length 5.08)
					(name "IO_L17P_T2_17"
						(effects
							(font
								(size 1.27 1.27)
							)
						)
					)
					(number "C17"
						(effects
							(font
								(size 1.27 1.27)
							)
						)
					)
				)
				(pin bidirectional line
					(at 54.61 -90.17 180)
					(length 5.08)
					(name "IO_L17N_T2_17"
						(effects
							(font
								(size 1.27 1.27)
							)
						)
					)
					(number "B17"
						(effects
							(font
								(size 1.27 1.27)
							)
						)
					)
				)
				(pin bidirectional line
					(at 54.61 -92.71 180)
					(length 5.08)
					(name "IO_L18P_T2_17"
						(effects
							(font
								(size 1.27 1.27)
							)
						)
					)
					(number "G17"
						(effects
							(font
								(size 1.27 1.27)
							)
						)
					)
				)
				(pin bidirectional line
					(at 54.61 -95.25 180)
					(length 5.08)
					(name "IO_L18N_T2_17"
						(effects
							(font
								(size 1.27 1.27)
							)
						)
					)
					(number "F17"
						(effects
							(font
								(size 1.27 1.27)
							)
						)
					)
				)
				(pin bidirectional line
					(at 54.61 -97.79 180)
					(length 5.08)
					(name "IO_L19P_T3_17"
						(effects
							(font
								(size 1.27 1.27)
							)
						)
					)
					(number "C20"
						(effects
							(font
								(size 1.27 1.27)
							)
						)
					)
				)
				(pin bidirectional line
					(at 54.61 -100.33 180)
					(length 5.08)
					(name "IO_L19N_T3_VREF_17"
						(effects
							(font
								(size 1.27 1.27)
							)
						)
					)
					(number "B20"
						(effects
							(font
								(size 1.27 1.27)
							)
						)
					)
				)
				(pin bidirectional line
					(at 54.61 -102.87 180)
					(length 5.08)
					(name "IO_L20P_T3_17"
						(effects
							(font
								(size 1.27 1.27)
							)
						)
					)
					(number "A16"
						(effects
							(font
								(size 1.27 1.27)
							)
						)
					)
				)
				(pin bidirectional line
					(at 54.61 -105.41 180)
					(length 5.08)
					(name "IO_L20N_T3_17"
						(effects
							(font
								(size 1.27 1.27)
							)
						)
					)
					(number "A17"
						(effects
							(font
								(size 1.27 1.27)
							)
						)
					)
				)
				(pin bidirectional line
					(at 54.61 -107.95 180)
					(length 5.08)
					(name "IO_L21P_T3_DQS_17"
						(effects
							(font
								(size 1.27 1.27)
							)
						)
					)
					(number "A20"
						(effects
							(font
								(size 1.27 1.27)
							)
						)
					)
				)
				(pin bidirectional line
					(at 54.61 -110.49 180)
					(length 5.08)
					(name "IO_L21N_T3_DQS_17"
						(effects
							(font
								(size 1.27 1.27)
							)
						)
					)
					(number "A21"
						(effects
							(font
								(size 1.27 1.27)
							)
						)
					)
				)
				(pin bidirectional line
					(at 54.61 -113.03 180)
					(length 5.08)
					(name "IO_L22P_T3_17"
						(effects
							(font
								(size 1.27 1.27)
							)
						)
					)
					(number "B18"
						(effects
							(font
								(size 1.27 1.27)
							)
						)
					)
				)
				(pin bidirectional line
					(at 54.61 -115.57 180)
					(length 5.08)
					(name "IO_L22N_T3_17"
						(effects
							(font
								(size 1.27 1.27)
							)
						)
					)
					(number "A18"
						(effects
							(font
								(size 1.27 1.27)
							)
						)
					)
				)
				(pin bidirectional line
					(at 54.61 -118.11 180)
					(length 5.08)
					(name "IO_L23P_T3_17"
						(effects
							(font
								(size 1.27 1.27)
							)
						)
					)
					(number "B22"
						(effects
							(font
								(size 1.27 1.27)
							)
						)
					)
				)
				(pin bidirectional line
					(at 54.61 -120.65 180)
					(length 5.08)
					(name "IO_L23N_T3_17"
						(effects
							(font
								(size 1.27 1.27)
							)
						)
					)
					(number "A22"
						(effects
							(font
								(size 1.27 1.27)
							)
						)
					)
				)
				(pin bidirectional line
					(at 54.61 -123.19 180)
					(length 5.08)
					(name "IO_L24P_T3_17"
						(effects
							(font
								(size 1.27 1.27)
							)
						)
					)
					(number "C19"
						(effects
							(font
								(size 1.27 1.27)
							)
						)
					)
				)
				(pin bidirectional line
					(at 54.61 -125.73 180)
					(length 5.08)
					(name "IO_L24N_T3_17"
						(effects
							(font
								(size 1.27 1.27)
							)
						)
					)
					(number "B19"
						(effects
							(font
								(size 1.27 1.27)
							)
						)
					)
				)
				(pin bidirectional line
					(at 54.61 -128.27 180)
					(length 5.08)
					(name "IO_25_17"
						(effects
							(font
								(size 1.27 1.27)
							)
						)
					)
					(number "E18"
						(effects
							(font
								(size 1.27 1.27)
							)
						)
					)
				)
			)
			(symbol "XC7K410T-2FFG900I_3_4_1"
				(rectangle
					(start 5.08 5.08)
					(end 48.26 -130.81)
					(stroke
						(width 0.254)
						(type default)
					)
					(fill
						(type background)
					)
				)
				(text "BANK 18"
					(at 17.78 2.54 0)
					(effects
						(font
							(size 1.27 1.27)
							(thickness 0.15)
						)
						(justify left bottom)
					)
				)
				(text "BANK 32"
					(at 29.21 2.54 0)
					(effects
						(font
							(size 1.27 1.27)
							(thickness 0.15)
						)
						(justify left bottom)
					)
				)
				(pin bidirectional line
					(at 0 0 0)
					(length 5.08)
					(name "VCCO_18"
						(effects
							(font
								(size 1.27 1.27)
							)
						)
					)
					(number "C13"
						(effects
							(font
								(size 1.27 1.27)
							)
						)
					)
				)
				(pin passive line
					(at 0 0 0)
					(length 5.08)
					(hide yes)
					(name "VCCO_18"
						(effects
							(font
								(size 1.27 1.27)
							)
						)
					)
					(number "D10"
						(effects
							(font
								(size 1.27 1.27)
							)
						)
					)
				)
				(pin passive line
					(at 0 0 0)
					(length 5.08)
					(hide yes)
					(name "VCCO_18"
						(effects
							(font
								(size 1.27 1.27)
							)
						)
					)
					(number "F14"
						(effects
							(font
								(size 1.27 1.27)
							)
						)
					)
				)
				(pin passive line
					(at 0 0 0)
					(length 5.08)
					(hide yes)
					(name "VCCO_18"
						(effects
							(font
								(size 1.27 1.27)
							)
						)
					)
					(number "G11"
						(effects
							(font
								(size 1.27 1.27)
							)
						)
					)
				)
				(pin passive line
					(at 0 0 0)
					(length 5.08)
					(hide yes)
					(name "VCCO_18"
						(effects
							(font
								(size 1.27 1.27)
							)
						)
					)
					(number "J15"
						(effects
							(font
								(size 1.27 1.27)
							)
						)
					)
				)
				(pin passive line
					(at 0 0 0)
					(length 5.08)
					(hide yes)
					(name "VCCO_18"
						(effects
							(font
								(size 1.27 1.27)
							)
						)
					)
					(number "K12"
						(effects
							(font
								(size 1.27 1.27)
							)
						)
					)
				)
				(pin bidirectional line
					(at 0 -3.81 0)
					(length 5.08)
					(name "IO_0_18"
						(effects
							(font
								(size 1.27 1.27)
							)
						)
					)
					(number "G12"
						(effects
							(font
								(size 1.27 1.27)
							)
						)
					)
				)
				(pin bidirectional line
					(at 0 -6.35 0)
					(length 5.08)
					(name "IO_L1P_T0_18"
						(effects
							(font
								(size 1.27 1.27)
							)
						)
					)
					(number "L16"
						(effects
							(font
								(size 1.27 1.27)
							)
						)
					)
				)
				(pin bidirectional line
					(at 0 -8.89 0)
					(length 5.08)
					(name "IO_L1N_T0_18"
						(effects
							(font
								(size 1.27 1.27)
							)
						)
					)
					(number "K16"
						(effects
							(font
								(size 1.27 1.27)
							)
						)
					)
				)
				(pin bidirectional line
					(at 0 -11.43 0)
					(length 5.08)
					(name "IO_L2P_T0_18"
						(effects
							(font
								(size 1.27 1.27)
							)
						)
					)
					(number "L15"
						(effects
							(font
								(size 1.27 1.27)
							)
						)
					)
				)
				(pin bidirectional line
					(at 0 -13.97 0)
					(length 5.08)
					(name "IO_L2N_T0_18"
						(effects
							(font
								(size 1.27 1.27)
							)
						)
					)
					(number "K15"
						(effects
							(font
								(size 1.27 1.27)
							)
						)
					)
				)
				(pin bidirectional line
					(at 0 -16.51 0)
					(length 5.08)
					(name "IO_L3P_T0_DQS_18"
						(effects
							(font
								(size 1.27 1.27)
							)
						)
					)
					(number "L12"
						(effects
							(font
								(size 1.27 1.27)
							)
						)
					)
				)
				(pin bidirectional line
					(at 0 -19.05 0)
					(length 5.08)
					(name "IO_L3N_T0_DQS_18"
						(effects
							(font
								(size 1.27 1.27)
							)
						)
					)
					(number "L13"
						(effects
							(font
								(size 1.27 1.27)
							)
						)
					)
				)
				(pin bidirectional line
					(at 0 -21.59 0)
					(length 5.08)
					(name "IO_L4P_T0_18"
						(effects
							(font
								(size 1.27 1.27)
							)
						)
					)
					(number "K13"
						(effects
							(font
								(size 1.27 1.27)
							)
						)
					)
				)
				(pin bidirectional line
					(at 0 -24.13 0)
					(length 5.08)
					(name "IO_L4N_T0_18"
						(effects
							(font
								(size 1.27 1.27)
							)
						)
					)
					(number "J13"
						(effects
							(font
								(size 1.27 1.27)
							)
						)
					)
				)
				(pin bidirectional line
					(at 0 -26.67 0)
					(length 5.08)
					(name "IO_L5P_T0_18"
						(effects
							(font
								(size 1.27 1.27)
							)
						)
					)
					(number "K14"
						(effects
							(font
								(size 1.27 1.27)
							)
						)
					)
				)
				(pin bidirectional line
					(at 0 -29.21 0)
					(length 5.08)
					(name "IO_L5N_T0_18"
						(effects
							(font
								(size 1.27 1.27)
							)
						)
					)
					(number "J14"
						(effects
							(font
								(size 1.27 1.27)
							)
						)
					)
				)
				(pin bidirectional line
					(at 0 -31.75 0)
					(length 5.08)
					(name "IO_L6P_T0_18"
						(effects
							(font
								(size 1.27 1.27)
							)
						)
					)
					(number "L11"
						(effects
							(font
								(size 1.27 1.27)
							)
						)
					)
				)
				(pin bidirectional line
					(at 0 -34.29 0)
					(length 5.08)
					(name "IO_L6N_T0_VREF_18"
						(effects
							(font
								(size 1.27 1.27)
							)
						)
					)
					(number "K11"
						(effects
							(font
								(size 1.27 1.27)
							)
						)
					)
				)
				(pin bidirectional line
					(at 0 -36.83 0)
					(length 5.08)
					(name "IO_L7P_T1_18"
						(effects
							(font
								(size 1.27 1.27)
							)
						)
					)
					(number "H15"
						(effects
							(font
								(size 1.27 1.27)
							)
						)
					)
				)
				(pin bidirectional line
					(at 0 -39.37 0)
					(length 5.08)
					(name "IO_L7N_T1_18"
						(effects
							(font
								(size 1.27 1.27)
							)
						)
					)
					(number "G15"
						(effects
							(font
								(size 1.27 1.27)
							)
						)
					)
				)
				(pin bidirectional line
					(at 0 -41.91 0)
					(length 5.08)
					(name "IO_L8P_T1_18"
						(effects
							(font
								(size 1.27 1.27)
							)
						)
					)
					(number "J11"
						(effects
							(font
								(size 1.27 1.27)
							)
						)
					)
				)
				(pin bidirectional line
					(at 0 -44.45 0)
					(length 5.08)
					(name "IO_L8N_T1_18"
						(effects
							(font
								(size 1.27 1.27)
							)
						)
					)
					(number "J12"
						(effects
							(font
								(size 1.27 1.27)
							)
						)
					)
				)
				(pin bidirectional line
					(at 0 -46.99 0)
					(length 5.08)
					(name "IO_L9P_T1_DQS_18"
						(effects
							(font
								(size 1.27 1.27)
							)
						)
					)
					(number "J16"
						(effects
							(font
								(size 1.27 1.27)
							)
						)
					)
				)
				(pin bidirectional line
					(at 0 -49.53 0)
					(length 5.08)
					(name "IO_L9N_T1_DQS_18"
						(effects
							(font
								(size 1.27 1.27)
							)
						)
					)
					(number "H16"
						(effects
							(font
								(size 1.27 1.27)
							)
						)
					)
				)
				(pin bidirectional line
					(at 0 -52.07 0)
					(length 5.08)
					(name "IO_L10P_T1_18"
						(effects
							(font
								(size 1.27 1.27)
							)
						)
					)
					(number "H11"
						(effects
							(font
								(size 1.27 1.27)
							)
						)
					)
				)
				(pin bidirectional line
					(at 0 -54.61 0)
					(length 5.08)
					(name "IO_L10N_T1_18"
						(effects
							(font
								(size 1.27 1.27)
							)
						)
					)
					(number "H12"
						(effects
							(font
								(size 1.27 1.27)
							)
						)
					)
				)
				(pin bidirectional line
					(at 0 -57.15 0)
					(length 5.08)
					(name "IO_L11P_T1_SRCC_18"
						(effects
							(font
								(size 1.27 1.27)
							)
						)
					)
					(number "H14"
						(effects
							(font
								(size 1.27 1.27)
							)
						)
					)
				)
				(pin bidirectional line
					(at 0 -59.69 0)
					(length 5.08)
					(name "IO_L11N_T1_SRCC_18"
						(effects
							(font
								(size 1.27 1.27)
							)
						)
					)
					(number "G14"
						(effects
							(font
								(size 1.27 1.27)
							)
						)
					)
				)
				(pin bidirectional line
					(at 0 -62.23 0)
					(length 5.08)
					(name "IO_L12P_T1_MRCC_18"
						(effects
							(font
								(size 1.27 1.27)
							)
						)
					)
					(number "G13"
						(effects
							(font
								(size 1.27 1.27)
							)
						)
					)
				)
				(pin bidirectional line
					(at 0 -64.77 0)
					(length 5.08)
					(name "IO_L12N_T1_MRCC_18"
						(effects
							(font
								(size 1.27 1.27)
							)
						)
					)
					(number "F13"
						(effects
							(font
								(size 1.27 1.27)
							)
						)
					)
				)
				(pin bidirectional line
					(at 0 -67.31 0)
					(length 5.08)
					(name "IO_L13P_T2_MRCC_18"
						(effects
							(font
								(size 1.27 1.27)
							)
						)
					)
					(number "D12"
						(effects
							(font
								(size 1.27 1.27)
							)
						)
					)
				)
				(pin bidirectional line
					(at 0 -69.85 0)
					(length 5.08)
					(name "IO_L13N_T2_MRCC_18"
						(effects
							(font
								(size 1.27 1.27)
							)
						)
					)
					(number "D13"
						(effects
							(font
								(size 1.27 1.27)
							)
						)
					)
				)
				(pin bidirectional line
					(at 0 -72.39 0)
					(length 5.08)
					(name "IO_L14P_T2_SRCC_18"
						(effects
							(font
								(size 1.27 1.27)
							)
						)
					)
					(number "F12"
						(effects
							(font
								(size 1.27 1.27)
							)
						)
					)
				)
				(pin bidirectional line
					(at 0 -74.93 0)
					(length 5.08)
					(name "IO_L14N_T2_SRCC_18"
						(effects
							(font
								(size 1.27 1.27)
							)
						)
					)
					(number "E13"
						(effects
							(font
								(size 1.27 1.27)
							)
						)
					)
				)
				(pin bidirectional line
					(at 0 -77.47 0)
					(length 5.08)
					(name "IO_L15P_T2_DQS_18"
						(effects
							(font
								(size 1.27 1.27)
							)
						)
					)
					(number "C12"
						(effects
							(font
								(size 1.27 1.27)
							)
						)
					)
				)
				(pin bidirectional line
					(at 0 -80.01 0)
					(length 5.08)
					(name "IO_L15N_T2_DQS_18"
						(effects
							(font
								(size 1.27 1.27)
							)
						)
					)
					(number "B12"
						(effects
							(font
								(size 1.27 1.27)
							)
						)
					)
				)
				(pin bidirectional line
					(at 0 -82.55 0)
					(length 5.08)
					(name "IO_L16P_T2_18"
						(effects
							(font
								(size 1.27 1.27)
							)
						)
					)
					(number "F11"
						(effects
							(font
								(size 1.27 1.27)
							)
						)
					)
				)
				(pin bidirectional line
					(at 0 -85.09 0)
					(length 5.08)
					(name "IO_L16N_T2_18"
						(effects
							(font
								(size 1.27 1.27)
							)
						)
					)
					(number "E11"
						(effects
							(font
								(size 1.27 1.27)
							)
						)
					)
				)
				(pin bidirectional line
					(at 0 -87.63 0)
					(length 5.08)
					(name "IO_L17P_T2_18"
						(effects
							(font
								(size 1.27 1.27)
							)
						)
					)
					(number "A11"
						(effects
							(font
								(size 1.27 1.27)
							)
						)
					)
				)
				(pin bidirectional line
					(at 0 -90.17 0)
					(length 5.08)
					(name "IO_L17N_T2_18"
						(effects
							(font
								(size 1.27 1.27)
							)
						)
					)
					(number "A12"
						(effects
							(font
								(size 1.27 1.27)
							)
						)
					)
				)
				(pin bidirectional line
					(at 0 -92.71 0)
					(length 5.08)
					(name "IO_L18P_T2_18"
						(effects
							(font
								(size 1.27 1.27)
							)
						)
					)
					(number "D11"
						(effects
							(font
								(size 1.27 1.27)
							)
						)
					)
				)
				(pin bidirectional line
					(at 0 -95.25 0)
					(length 5.08)
					(name "IO_L18N_T2_18"
						(effects
							(font
								(size 1.27 1.27)
							)
						)
					)
					(number "C11"
						(effects
							(font
								(size 1.27 1.27)
							)
						)
					)
				)
				(pin bidirectional line
					(at 0 -97.79 0)
					(length 5.08)
					(name "IO_L19P_T3_18"
						(effects
							(font
								(size 1.27 1.27)
							)
						)
					)
					(number "F15"
						(effects
							(font
								(size 1.27 1.27)
							)
						)
					)
				)
				(pin bidirectional line
					(at 0 -100.33 0)
					(length 5.08)
					(name "IO_L19N_T3_VREF_18"
						(effects
							(font
								(size 1.27 1.27)
							)
						)
					)
					(number "E16"
						(effects
							(font
								(size 1.27 1.27)
							)
						)
					)
				)
				(pin bidirectional line
					(at 0 -102.87 0)
					(length 5.08)
					(name "IO_L20P_T3_18"
						(effects
							(font
								(size 1.27 1.27)
							)
						)
					)
					(number "E14"
						(effects
							(font
								(size 1.27 1.27)
							)
						)
					)
				)
				(pin bidirectional line
					(at 0 -105.41 0)
					(length 5.08)
					(name "IO_L20N_T3_18"
						(effects
							(font
								(size 1.27 1.27)
							)
						)
					)
					(number "E15"
						(effects
							(font
								(size 1.27 1.27)
							)
						)
					)
				)
				(pin bidirectional line
					(at 0 -107.95 0)
					(length 5.08)
					(name "IO_L21P_T3_DQS_18"
						(effects
							(font
								(size 1.27 1.27)
							)
						)
					)
					(number "D14"
						(effects
							(font
								(size 1.27 1.27)
							)
						)
					)
				)
				(pin bidirectional line
					(at 0 -110.49 0)
					(length 5.08)
					(name "IO_L21N_T3_DQS_18"
						(effects
							(font
								(size 1.27 1.27)
							)
						)
					)
					(number "C14"
						(effects
							(font
								(size 1.27 1.27)
							)
						)
					)
				)
				(pin bidirectional line
					(at 0 -113.03 0)
					(length 5.08)
					(name "IO_L22P_T3_18"
						(effects
							(font
								(size 1.27 1.27)
							)
						)
					)
					(number "B13"
						(effects
							(font
								(size 1.27 1.27)
							)
						)
					)
				)
				(pin bidirectional line
					(at 0 -115.57 0)
					(length 5.08)
					(name "IO_L22N_T3_18"
						(effects
							(font
								(size 1.27 1.27)
							)
						)
					)
					(number "A13"
						(effects
							(font
								(size 1.27 1.27)
							)
						)
					)
				)
				(pin bidirectional line
					(at 0 -118.11 0)
					(length 5.08)
					(name "IO_L23P_T3_18"
						(effects
							(font
								(size 1.27 1.27)
							)
						)
					)
					(number "C15"
						(effects
							(font
								(size 1.27 1.27)
							)
						)
					)
				)
				(pin bidirectional line
					(at 0 -120.65 0)
					(length 5.08)
					(name "IO_L23N_T3_18"
						(effects
							(font
								(size 1.27 1.27)
							)
						)
					)
					(number "B15"
						(effects
							(font
								(size 1.27 1.27)
							)
						)
					)
				)
				(pin bidirectional line
					(at 0 -123.19 0)
					(length 5.08)
					(name "IO_L24P_T3_18"
						(effects
							(font
								(size 1.27 1.27)
							)
						)
					)
					(number "B14"
						(effects
							(font
								(size 1.27 1.27)
							)
						)
					)
				)
				(pin bidirectional line
					(at 0 -125.73 0)
					(length 5.08)
					(name "IO_L24N_T3_18"
						(effects
							(font
								(size 1.27 1.27)
							)
						)
					)
					(number "A15"
						(effects
							(font
								(size 1.27 1.27)
							)
						)
					)
				)
				(pin bidirectional line
					(at 0 -128.27 0)
					(length 5.08)
					(name "IO_25_18"
						(effects
							(font
								(size 1.27 1.27)
							)
						)
					)
					(number "F16"
						(effects
							(font
								(size 1.27 1.27)
							)
						)
					)
				)
				(pin bidirectional line
					(at 53.34 0 180)
					(length 5.08)
					(name "VCCO_32"
						(effects
							(font
								(size 1.27 1.27)
							)
						)
					)
					(number "AA19"
						(effects
							(font
								(size 1.27 1.27)
							)
						)
					)
				)
				(pin passive line
					(at 53.34 0 180)
					(length 5.08)
					(hide yes)
					(name "VCCO_32"
						(effects
							(font
								(size 1.27 1.27)
							)
						)
					)
					(number "AB16"
						(effects
							(font
								(size 1.27 1.27)
							)
						)
					)
				)
				(pin passive line
					(at 53.34 0 180)
					(length 5.08)
					(hide yes)
					(name "VCCO_32"
						(effects
							(font
								(size 1.27 1.27)
							)
						)
					)
					(number "AE17"
						(effects
							(font
								(size 1.27 1.27)
							)
						)
					)
				)
				(pin passive line
					(at 53.34 0 180)
					(length 5.08)
					(hide yes)
					(name "VCCO_32"
						(effects
							(font
								(size 1.27 1.27)
							)
						)
					)
					(number "AF14"
						(effects
							(font
								(size 1.27 1.27)
							)
						)
					)
				)
				(pin passive line
					(at 53.34 0 180)
					(length 5.08)
					(hide yes)
					(name "VCCO_32"
						(effects
							(font
								(size 1.27 1.27)
							)
						)
					)
					(number "AH18"
						(effects
							(font
								(size 1.27 1.27)
							)
						)
					)
				)
				(pin passive line
					(at 53.34 0 180)
					(length 5.08)
					(hide yes)
					(name "VCCO_32"
						(effects
							(font
								(size 1.27 1.27)
							)
						)
					)
					(number "AJ15"
						(effects
							(font
								(size 1.27 1.27)
							)
						)
					)
				)
				(pin bidirectional line
					(at 53.34 -3.81 180)
					(length 5.08)
					(name "IO_0_VRN_32"
						(effects
							(font
								(size 1.27 1.27)
							)
						)
					)
					(number "Y14"
						(effects
							(font
								(size 1.27 1.27)
							)
						)
					)
				)
				(pin bidirectional line
					(at 53.34 -6.35 180)
					(length 5.08)
					(name "IO_L1P_T0_32"
						(effects
							(font
								(size 1.27 1.27)
							)
						)
					)
					(number "AK16"
						(effects
							(font
								(size 1.27 1.27)
							)
						)
					)
				)
				(pin bidirectional line
					(at 53.34 -8.89 180)
					(length 5.08)
					(name "IO_L1N_T0_32"
						(effects
							(font
								(size 1.27 1.27)
							)
						)
					)
					(number "AK15"
						(effects
							(font
								(size 1.27 1.27)
							)
						)
					)
				)
				(pin bidirectional line
					(at 53.34 -11.43 180)
					(length 5.08)
					(name "IO_L2P_T0_32"
						(effects
							(font
								(size 1.27 1.27)
							)
						)
					)
					(number "AG15"
						(effects
							(font
								(size 1.27 1.27)
							)
						)
					)
				)
				(pin bidirectional line
					(at 53.34 -13.97 180)
					(length 5.08)
					(name "IO_L2N_T0_32"
						(effects
							(font
								(size 1.27 1.27)
							)
						)
					)
					(number "AH15"
						(effects
							(font
								(size 1.27 1.27)
							)
						)
					)
				)
				(pin bidirectional line
					(at 53.34 -16.51 180)
					(length 5.08)
					(name "IO_L3P_T0_DQS_32"
						(effects
							(font
								(size 1.27 1.27)
							)
						)
					)
					(number "AH16"
						(effects
							(font
								(size 1.27 1.27)
							)
						)
					)
				)
				(pin bidirectional line
					(at 53.34 -19.05 180)
					(length 5.08)
					(name "IO_L3N_T0_DQS_32"
						(effects
							(font
								(size 1.27 1.27)
							)
						)
					)
					(number "AJ16"
						(effects
							(font
								(size 1.27 1.27)
							)
						)
					)
				)
				(pin bidirectional line
					(at 53.34 -21.59 180)
					(length 5.08)
					(name "IO_L4P_T0_32"
						(effects
							(font
								(size 1.27 1.27)
							)
						)
					)
					(number "AF15"
						(effects
							(font
								(size 1.27 1.27)
							)
						)
					)
				)
				(pin bidirectional line
					(at 53.34 -24.13 180)
					(length 5.08)
					(name "IO_L4N_T0_32"
						(effects
							(font
								(size 1.27 1.27)
							)
						)
					)
					(number "AG14"
						(effects
							(font
								(size 1.27 1.27)
							)
						)
					)
				)
				(pin bidirectional line
					(at 53.34 -26.67 180)
					(length 5.08)
					(name "IO_L5P_T0_32"
						(effects
							(font
								(size 1.27 1.27)
							)
						)
					)
					(number "AH17"
						(effects
							(font
								(size 1.27 1.27)
							)
						)
					)
				)
				(pin bidirectional line
					(at 53.34 -29.21 180)
					(length 5.08)
					(name "IO_L5N_T0_32"
						(effects
							(font
								(size 1.27 1.27)
							)
						)
					)
					(number "AJ17"
						(effects
							(font
								(size 1.27 1.27)
							)
						)
					)
				)
				(pin bidirectional line
					(at 53.34 -31.75 180)
					(length 5.08)
					(name "IO_L6P_T0_32"
						(effects
							(font
								(size 1.27 1.27)
							)
						)
					)
					(number "AE16"
						(effects
							(font
								(size 1.27 1.27)
							)
						)
					)
				)
				(pin bidirectional line
					(at 53.34 -34.29 180)
					(length 5.08)
					(name "IO_L6N_T0_VREF_32"
						(effects
							(font
								(size 1.27 1.27)
							)
						)
					)
					(number "AF16"
						(effects
							(font
								(size 1.27 1.27)
							)
						)
					)
				)
				(pin bidirectional line
					(at 53.34 -36.83 180)
					(length 5.08)
					(name "IO_L7P_T1_32"
						(effects
							(font
								(size 1.27 1.27)
							)
						)
					)
					(number "AJ19"
						(effects
							(font
								(size 1.27 1.27)
							)
						)
					)
				)
				(pin bidirectional line
					(at 53.34 -39.37 180)
					(length 5.08)
					(name "IO_L7N_T1_32"
						(effects
							(font
								(size 1.27 1.27)
							)
						)
					)
					(number "AK19"
						(effects
							(font
								(size 1.27 1.27)
							)
						)
					)
				)
				(pin bidirectional line
					(at 53.34 -41.91 180)
					(length 5.08)
					(name "IO_L8P_T1_32"
						(effects
							(font
								(size 1.27 1.27)
							)
						)
					)
					(number "AG19"
						(effects
							(font
								(size 1.27 1.27)
							)
						)
					)
				)
				(pin bidirectional line
					(at 53.34 -44.45 180)
					(length 5.08)
					(name "IO_L8N_T1_32"
						(effects
							(font
								(size 1.27 1.27)
							)
						)
					)
					(number "AH19"
						(effects
							(font
								(size 1.27 1.27)
							)
						)
					)
				)
				(pin bidirectional line
					(at 53.34 -46.99 180)
					(length 5.08)
					(name "IO_L9P_T1_DQS_32"
						(effects
							(font
								(size 1.27 1.27)
							)
						)
					)
					(number "AJ18"
						(effects
							(font
								(size 1.27 1.27)
							)
						)
					)
				)
				(pin bidirectional line
					(at 53.34 -49.53 180)
					(length 5.08)
					(name "IO_L9N_T1_DQS_32"
						(effects
							(font
								(size 1.27 1.27)
							)
						)
					)
					(number "AK18"
						(effects
							(font
								(size 1.27 1.27)
							)
						)
					)
				)
				(pin bidirectional line
					(at 53.34 -52.07 180)
					(length 5.08)
					(name "IO_L10P_T1_32"
						(effects
							(font
								(size 1.27 1.27)
							)
						)
					)
					(number "AD19"
						(effects
							(font
								(size 1.27 1.27)
							)
						)
					)
				)
				(pin bidirectional line
					(at 53.34 -54.61 180)
					(length 5.08)
					(name "IO_L10N_T1_32"
						(effects
							(font
								(size 1.27 1.27)
							)
						)
					)
					(number "AE19"
						(effects
							(font
								(size 1.27 1.27)
							)
						)
					)
				)
				(pin bidirectional line
					(at 53.34 -57.15 180)
					(length 5.08)
					(name "IO_L11P_T1_SRCC_32"
						(effects
							(font
								(size 1.27 1.27)
							)
						)
					)
					(number "AF18"
						(effects
							(font
								(size 1.27 1.27)
							)
						)
					)
				)
				(pin bidirectional line
					(at 53.34 -59.69 180)
					(length 5.08)
					(name "IO_L11N_T1_SRCC_32"
						(effects
							(font
								(size 1.27 1.27)
							)
						)
					)
					(number "AG18"
						(effects
							(font
								(size 1.27 1.27)
							)
						)
					)
				)
				(pin bidirectional line
					(at 53.34 -62.23 180)
					(length 5.08)
					(name "IO_L12P_T1_MRCC_32"
						(effects
							(font
								(size 1.27 1.27)
							)
						)
					)
					(number "AF17"
						(effects
							(font
								(size 1.27 1.27)
							)
						)
					)
				)
				(pin bidirectional line
					(at 53.34 -64.77 180)
					(length 5.08)
					(name "IO_L12N_T1_MRCC_32"
						(effects
							(font
								(size 1.27 1.27)
							)
						)
					)
					(number "AG17"
						(effects
							(font
								(size 1.27 1.27)
							)
						)
					)
				)
				(pin bidirectional line
					(at 53.34 -67.31 180)
					(length 5.08)
					(name "IO_L13P_T2_MRCC_32"
						(effects
							(font
								(size 1.27 1.27)
							)
						)
					)
					(number "AD18"
						(effects
							(font
								(size 1.27 1.27)
							)
						)
					)
				)
				(pin bidirectional line
					(at 53.34 -69.85 180)
					(length 5.08)
					(name "IO_L13N_T2_MRCC_32"
						(effects
							(font
								(size 1.27 1.27)
							)
						)
					)
					(number "AE18"
						(effects
							(font
								(size 1.27 1.27)
							)
						)
					)
				)
				(pin bidirectional line
					(at 53.34 -72.39 180)
					(length 5.08)
					(name "IO_L14P_T2_SRCC_32"
						(effects
							(font
								(size 1.27 1.27)
							)
						)
					)
					(number "AD17"
						(effects
							(font
								(size 1.27 1.27)
							)
						)
					)
				)
				(pin bidirectional line
					(at 53.34 -74.93 180)
					(length 5.08)
					(name "IO_L14N_T2_SRCC_32"
						(effects
							(font
								(size 1.27 1.27)
							)
						)
					)
					(number "AD16"
						(effects
							(font
								(size 1.27 1.27)
							)
						)
					)
				)
				(pin bidirectional line
					(at 53.34 -77.47 180)
					(length 5.08)
					(name "IO_L15P_T2_DQS_32"
						(effects
							(font
								(size 1.27 1.27)
							)
						)
					)
					(number "Y19"
						(effects
							(font
								(size 1.27 1.27)
							)
						)
					)
				)
				(pin bidirectional line
					(at 53.34 -80.01 180)
					(length 5.08)
					(name "IO_L15N_T2_DQS_32"
						(effects
							(font
								(size 1.27 1.27)
							)
						)
					)
					(number "Y18"
						(effects
							(font
								(size 1.27 1.27)
							)
						)
					)
				)
				(pin bidirectional line
					(at 53.34 -82.55 180)
					(length 5.08)
					(name "IO_L16P_T2_32"
						(effects
							(font
								(size 1.27 1.27)
							)
						)
					)
					(number "AA18"
						(effects
							(font
								(size 1.27 1.27)
							)
						)
					)
				)
				(pin bidirectional line
					(at 53.34 -85.09 180)
					(length 5.08)
					(name "IO_L16N_T2_32"
						(effects
							(font
								(size 1.27 1.27)
							)
						)
					)
					(number "AB18"
						(effects
							(font
								(size 1.27 1.27)
							)
						)
					)
				)
				(pin bidirectional line
					(at 53.34 -87.63 180)
					(length 5.08)
					(name "IO_L17P_T2_32"
						(effects
							(font
								(size 1.27 1.27)
							)
						)
					)
					(number "AB19"
						(effects
							(font
								(size 1.27 1.27)
							)
						)
					)
				)
				(pin bidirectional line
					(at 53.34 -90.17 180)
					(length 5.08)
					(name "IO_L17N_T2_32"
						(effects
							(font
								(size 1.27 1.27)
							)
						)
					)
					(number "AC19"
						(effects
							(font
								(size 1.27 1.27)
							)
						)
					)
				)
				(pin bidirectional line
					(at 53.34 -92.71 180)
					(length 5.08)
					(name "IO_L18P_T2_32"
						(effects
							(font
								(size 1.27 1.27)
							)
						)
					)
					(number "AB17"
						(effects
							(font
								(size 1.27 1.27)
							)
						)
					)
				)
				(pin bidirectional line
					(at 53.34 -95.25 180)
					(length 5.08)
					(name "IO_L18N_T2_32"
						(effects
							(font
								(size 1.27 1.27)
							)
						)
					)
					(number "AC17"
						(effects
							(font
								(size 1.27 1.27)
							)
						)
					)
				)
				(pin bidirectional line
					(at 53.34 -97.79 180)
					(length 5.08)
					(name "IO_L19P_T3_32"
						(effects
							(font
								(size 1.27 1.27)
							)
						)
					)
					(number "AE15"
						(effects
							(font
								(size 1.27 1.27)
							)
						)
					)
				)
				(pin bidirectional line
					(at 53.34 -100.33 180)
					(length 5.08)
					(name "IO_L19N_T3_VREF_32"
						(effects
							(font
								(size 1.27 1.27)
							)
						)
					)
					(number "AE14"
						(effects
							(font
								(size 1.27 1.27)
							)
						)
					)
				)
				(pin bidirectional line
					(at 53.34 -102.87 180)
					(length 5.08)
					(name "IO_L20P_T3_32"
						(effects
							(font
								(size 1.27 1.27)
							)
						)
					)
					(number "AA15"
						(effects
							(font
								(size 1.27 1.27)
							)
						)
					)
				)
				(pin bidirectional line
					(at 53.34 -105.41 180)
					(length 5.08)
					(name "IO_L20N_T3_32"
						(effects
							(font
								(size 1.27 1.27)
							)
						)
					)
					(number "AB15"
						(effects
							(font
								(size 1.27 1.27)
							)
						)
					)
				)
				(pin bidirectional line
					(at 53.34 -107.95 180)
					(length 5.08)
					(name "IO_L21P_T3_DQS_32"
						(effects
							(font
								(size 1.27 1.27)
							)
						)
					)
					(number "AC16"
						(effects
							(font
								(size 1.27 1.27)
							)
						)
					)
				)
				(pin bidirectional line
					(at 53.34 -110.49 180)
					(length 5.08)
					(name "IO_L21N_T3_DQS_32"
						(effects
							(font
								(size 1.27 1.27)
							)
						)
					)
					(number "AC15"
						(effects
							(font
								(size 1.27 1.27)
							)
						)
					)
				)
				(pin bidirectional line
					(at 53.34 -113.03 180)
					(length 5.08)
					(name "IO_L22P_T3_32"
						(effects
							(font
								(size 1.27 1.27)
							)
						)
					)
					(number "AC14"
						(effects
							(font
								(size 1.27 1.27)
							)
						)
					)
				)
				(pin bidirectional line
					(at 53.34 -115.57 180)
					(length 5.08)
					(name "IO_L22N_T3_32"
						(effects
							(font
								(size 1.27 1.27)
							)
						)
					)
					(number "AD14"
						(effects
							(font
								(size 1.27 1.27)
							)
						)
					)
				)
				(pin bidirectional line
					(at 53.34 -118.11 180)
					(length 5.08)
					(name "IO_L23P_T3_32"
						(effects
							(font
								(size 1.27 1.27)
							)
						)
					)
					(number "AA17"
						(effects
							(font
								(size 1.27 1.27)
							)
						)
					)
				)
				(pin bidirectional line
					(at 53.34 -120.65 180)
					(length 5.08)
					(name "IO_L23N_T3_32"
						(effects
							(font
								(size 1.27 1.27)
							)
						)
					)
					(number "AA16"
						(effects
							(font
								(size 1.27 1.27)
							)
						)
					)
				)
				(pin bidirectional line
					(at 53.34 -123.19 180)
					(length 5.08)
					(name "IO_L24P_T3_32"
						(effects
							(font
								(size 1.27 1.27)
							)
						)
					)
					(number "Y16"
						(effects
							(font
								(size 1.27 1.27)
							)
						)
					)
				)
				(pin bidirectional line
					(at 53.34 -125.73 180)
					(length 5.08)
					(name "IO_L24N_T3_32"
						(effects
							(font
								(size 1.27 1.27)
							)
						)
					)
					(number "Y15"
						(effects
							(font
								(size 1.27 1.27)
							)
						)
					)
				)
				(pin bidirectional line
					(at 53.34 -128.27 180)
					(length 5.08)
					(name "IO_25_VRP_32"
						(effects
							(font
								(size 1.27 1.27)
							)
						)
					)
					(number "AB14"
						(effects
							(font
								(size 1.27 1.27)
							)
						)
					)
				)
			)
			(symbol "XC7K410T-2FFG900I_3_5_1"
				(rectangle
					(start 5.08 5.08)
					(end 49.53 -130.81)
					(stroke
						(width 0.254)
						(type default)
					)
					(fill
						(type background)
					)
				)
				(text "BANK 33"
					(at 17.78 2.54 0)
					(effects
						(font
							(size 1.27 1.27)
							(thickness 0.15)
						)
						(justify left bottom)
					)
				)
				(text "BANK 34"
					(at 30.48 2.54 0)
					(effects
						(font
							(size 1.27 1.27)
							(thickness 0.15)
						)
						(justify left bottom)
					)
				)
				(pin bidirectional line
					(at 0 0 0)
					(length 5.08)
					(name "VCCO_33"
						(effects
							(font
								(size 1.27 1.27)
							)
						)
					)
					(number "AA9"
						(effects
							(font
								(size 1.27 1.27)
							)
						)
					)
				)
				(pin passive line
					(at 0 0 0)
					(length 5.08)
					(hide yes)
					(name "VCCO_33"
						(effects
							(font
								(size 1.27 1.27)
							)
						)
					)
					(number "AC13"
						(effects
							(font
								(size 1.27 1.27)
							)
						)
					)
				)
				(pin passive line
					(at 0 0 0)
					(length 5.08)
					(hide yes)
					(name "VCCO_33"
						(effects
							(font
								(size 1.27 1.27)
							)
						)
					)
					(number "AD10"
						(effects
							(font
								(size 1.27 1.27)
							)
						)
					)
				)
				(pin passive line
					(at 0 0 0)
					(length 5.08)
					(hide yes)
					(name "VCCO_33"
						(effects
							(font
								(size 1.27 1.27)
							)
						)
					)
					(number "AG11"
						(effects
							(font
								(size 1.27 1.27)
							)
						)
					)
				)
				(pin passive line
					(at 0 0 0)
					(length 5.08)
					(hide yes)
					(name "VCCO_33"
						(effects
							(font
								(size 1.27 1.27)
							)
						)
					)
					(number "AK12"
						(effects
							(font
								(size 1.27 1.27)
							)
						)
					)
				)
				(pin passive line
					(at 0 0 0)
					(length 5.08)
					(hide yes)
					(name "VCCO_33"
						(effects
							(font
								(size 1.27 1.27)
							)
						)
					)
					(number "Y12"
						(effects
							(font
								(size 1.27 1.27)
							)
						)
					)
				)
				(pin bidirectional line
					(at 0 -3.81 0)
					(length 5.08)
					(name "IO_0_VRN_33"
						(effects
							(font
								(size 1.27 1.27)
							)
						)
					)
					(number "Y13"
						(effects
							(font
								(size 1.27 1.27)
							)
						)
					)
				)
				(pin bidirectional line
					(at 0 -6.35 0)
					(length 5.08)
					(name "IO_L1P_T0_33"
						(effects
							(font
								(size 1.27 1.27)
							)
						)
					)
					(number "AA12"
						(effects
							(font
								(size 1.27 1.27)
							)
						)
					)
				)
				(pin bidirectional line
					(at 0 -8.89 0)
					(length 5.08)
					(name "IO_L1N_T0_33"
						(effects
							(font
								(size 1.27 1.27)
							)
						)
					)
					(number "AB12"
						(effects
							(font
								(size 1.27 1.27)
							)
						)
					)
				)
				(pin bidirectional line
					(at 0 -11.43 0)
					(length 5.08)
					(name "IO_L2P_T0_33"
						(effects
							(font
								(size 1.27 1.27)
							)
						)
					)
					(number "AA8"
						(effects
							(font
								(size 1.27 1.27)
							)
						)
					)
				)
				(pin bidirectional line
					(at 0 -13.97 0)
					(length 5.08)
					(name "IO_L2N_T0_33"
						(effects
							(font
								(size 1.27 1.27)
							)
						)
					)
					(number "AB8"
						(effects
							(font
								(size 1.27 1.27)
							)
						)
					)
				)
				(pin bidirectional line
					(at 0 -16.51 0)
					(length 5.08)
					(name "IO_L3P_T0_DQS_33"
						(effects
							(font
								(size 1.27 1.27)
							)
						)
					)
					(number "AB9"
						(effects
							(font
								(size 1.27 1.27)
							)
						)
					)
				)
				(pin bidirectional line
					(at 0 -19.05 0)
					(length 5.08)
					(name "IO_L3N_T0_DQS_33"
						(effects
							(font
								(size 1.27 1.27)
							)
						)
					)
					(number "AC9"
						(effects
							(font
								(size 1.27 1.27)
							)
						)
					)
				)
				(pin bidirectional line
					(at 0 -21.59 0)
					(length 5.08)
					(name "IO_L4P_T0_33"
						(effects
							(font
								(size 1.27 1.27)
							)
						)
					)
					(number "Y11"
						(effects
							(font
								(size 1.27 1.27)
							)
						)
					)
				)
				(pin bidirectional line
					(at 0 -24.13 0)
					(length 5.08)
					(name "IO_L4N_T0_33"
						(effects
							(font
								(size 1.27 1.27)
							)
						)
					)
					(number "Y10"
						(effects
							(font
								(size 1.27 1.27)
							)
						)
					)
				)
				(pin bidirectional line
					(at 0 -26.67 0)
					(length 5.08)
					(name "IO_L5P_T0_33"
						(effects
							(font
								(size 1.27 1.27)
							)
						)
					)
					(number "AA11"
						(effects
							(font
								(size 1.27 1.27)
							)
						)
					)
				)
				(pin bidirectional line
					(at 0 -29.21 0)
					(length 5.08)
					(name "IO_L5N_T0_33"
						(effects
							(font
								(size 1.27 1.27)
							)
						)
					)
					(number "AA10"
						(effects
							(font
								(size 1.27 1.27)
							)
						)
					)
				)
				(pin bidirectional line
					(at 0 -31.75 0)
					(length 5.08)
					(name "IO_L6P_T0_33"
						(effects
							(font
								(size 1.27 1.27)
							)
						)
					)
					(number "AA13"
						(effects
							(font
								(size 1.27 1.27)
							)
						)
					)
				)
				(pin bidirectional line
					(at 0 -34.29 0)
					(length 5.08)
					(name "IO_L6N_T0_VREF_33"
						(effects
							(font
								(size 1.27 1.27)
							)
						)
					)
					(number "AB13"
						(effects
							(font
								(size 1.27 1.27)
							)
						)
					)
				)
				(pin bidirectional line
					(at 0 -36.83 0)
					(length 5.08)
					(name "IO_L7P_T1_33"
						(effects
							(font
								(size 1.27 1.27)
							)
						)
					)
					(number "AB10"
						(effects
							(font
								(size 1.27 1.27)
							)
						)
					)
				)
				(pin bidirectional line
					(at 0 -39.37 0)
					(length 5.08)
					(name "IO_L7N_T1_33"
						(effects
							(font
								(size 1.27 1.27)
							)
						)
					)
					(number "AC10"
						(effects
							(font
								(size 1.27 1.27)
							)
						)
					)
				)
				(pin bidirectional line
					(at 0 -41.91 0)
					(length 5.08)
					(name "IO_L8P_T1_33"
						(effects
							(font
								(size 1.27 1.27)
							)
						)
					)
					(number "AD8"
						(effects
							(font
								(size 1.27 1.27)
							)
						)
					)
				)
				(pin bidirectional line
					(at 0 -44.45 0)
					(length 5.08)
					(name "IO_L8N_T1_33"
						(effects
							(font
								(size 1.27 1.27)
							)
						)
					)
					(number "AE8"
						(effects
							(font
								(size 1.27 1.27)
							)
						)
					)
				)
				(pin bidirectional line
					(at 0 -46.99 0)
					(length 5.08)
					(name "IO_L9P_T1_DQS_33"
						(effects
							(font
								(size 1.27 1.27)
							)
						)
					)
					(number "AC12"
						(effects
							(font
								(size 1.27 1.27)
							)
						)
					)
				)
				(pin bidirectional line
					(at 0 -49.53 0)
					(length 5.08)
					(name "IO_L9N_T1_DQS_33"
						(effects
							(font
								(size 1.27 1.27)
							)
						)
					)
					(number "AC11"
						(effects
							(font
								(size 1.27 1.27)
							)
						)
					)
				)
				(pin bidirectional line
					(at 0 -52.07 0)
					(length 5.08)
					(name "IO_L10P_T1_33"
						(effects
							(font
								(size 1.27 1.27)
							)
						)
					)
					(number "AD9"
						(effects
							(font
								(size 1.27 1.27)
							)
						)
					)
				)
				(pin bidirectional line
					(at 0 -54.61 0)
					(length 5.08)
					(name "IO_L10N_T1_33"
						(effects
							(font
								(size 1.27 1.27)
							)
						)
					)
					(number "AE9"
						(effects
							(font
								(size 1.27 1.27)
							)
						)
					)
				)
				(pin bidirectional line
					(at 0 -57.15 0)
					(length 5.08)
					(name "IO_L11P_T1_SRCC_33"
						(effects
							(font
								(size 1.27 1.27)
							)
						)
					)
					(number "AE11"
						(effects
							(font
								(size 1.27 1.27)
							)
						)
					)
				)
				(pin bidirectional line
					(at 0 -59.69 0)
					(length 5.08)
					(name "IO_L11N_T1_SRCC_33"
						(effects
							(font
								(size 1.27 1.27)
							)
						)
					)
					(number "AF11"
						(effects
							(font
								(size 1.27 1.27)
							)
						)
					)
				)
				(pin bidirectional line
					(at 0 -62.23 0)
					(length 5.08)
					(name "IO_L12P_T1_MRCC_33"
						(effects
							(font
								(size 1.27 1.27)
							)
						)
					)
					(number "AD12"
						(effects
							(font
								(size 1.27 1.27)
							)
						)
					)
				)
				(pin bidirectional line
					(at 0 -64.77 0)
					(length 5.08)
					(name "IO_L12N_T1_MRCC_33"
						(effects
							(font
								(size 1.27 1.27)
							)
						)
					)
					(number "AD11"
						(effects
							(font
								(size 1.27 1.27)
							)
						)
					)
				)
				(pin bidirectional line
					(at 0 -67.31 0)
					(length 5.08)
					(name "IO_L13P_T2_MRCC_33"
						(effects
							(font
								(size 1.27 1.27)
							)
						)
					)
					(number "AG10"
						(effects
							(font
								(size 1.27 1.27)
							)
						)
					)
				)
				(pin bidirectional line
					(at 0 -69.85 0)
					(length 5.08)
					(name "IO_L13N_T2_MRCC_33"
						(effects
							(font
								(size 1.27 1.27)
							)
						)
					)
					(number "AH10"
						(effects
							(font
								(size 1.27 1.27)
							)
						)
					)
				)
				(pin bidirectional line
					(at 0 -72.39 0)
					(length 5.08)
					(name "IO_L14P_T2_SRCC_33"
						(effects
							(font
								(size 1.27 1.27)
							)
						)
					)
					(number "AE10"
						(effects
							(font
								(size 1.27 1.27)
							)
						)
					)
				)
				(pin bidirectional line
					(at 0 -74.93 0)
					(length 5.08)
					(name "IO_L14N_T2_SRCC_33"
						(effects
							(font
								(size 1.27 1.27)
							)
						)
					)
					(number "AF10"
						(effects
							(font
								(size 1.27 1.27)
							)
						)
					)
				)
				(pin bidirectional line
					(at 0 -77.47 0)
					(length 5.08)
					(name "IO_L15P_T2_DQS_33"
						(effects
							(font
								(size 1.27 1.27)
							)
						)
					)
					(number "AJ9"
						(effects
							(font
								(size 1.27 1.27)
							)
						)
					)
				)
				(pin bidirectional line
					(at 0 -80.01 0)
					(length 5.08)
					(name "IO_L15N_T2_DQS_33"
						(effects
							(font
								(size 1.27 1.27)
							)
						)
					)
					(number "AK9"
						(effects
							(font
								(size 1.27 1.27)
							)
						)
					)
				)
				(pin bidirectional line
					(at 0 -82.55 0)
					(length 5.08)
					(name "IO_L16P_T2_33"
						(effects
							(font
								(size 1.27 1.27)
							)
						)
					)
					(number "AG9"
						(effects
							(font
								(size 1.27 1.27)
							)
						)
					)
				)
				(pin bidirectional line
					(at 0 -85.09 0)
					(length 5.08)
					(name "IO_L16N_T2_33"
						(effects
							(font
								(size 1.27 1.27)
							)
						)
					)
					(number "AH9"
						(effects
							(font
								(size 1.27 1.27)
							)
						)
					)
				)
				(pin bidirectional line
					(at 0 -87.63 0)
					(length 5.08)
					(name "IO_L17P_T2_33"
						(effects
							(font
								(size 1.27 1.27)
							)
						)
					)
					(number "AK11"
						(effects
							(font
								(size 1.27 1.27)
							)
						)
					)
				)
				(pin bidirectional line
					(at 0 -90.17 0)
					(length 5.08)
					(name "IO_L17N_T2_33"
						(effects
							(font
								(size 1.27 1.27)
							)
						)
					)
					(number "AK10"
						(effects
							(font
								(size 1.27 1.27)
							)
						)
					)
				)
				(pin bidirectional line
					(at 0 -92.71 0)
					(length 5.08)
					(name "IO_L18P_T2_33"
						(effects
							(font
								(size 1.27 1.27)
							)
						)
					)
					(number "AH11"
						(effects
							(font
								(size 1.27 1.27)
							)
						)
					)
				)
				(pin bidirectional line
					(at 0 -95.25 0)
					(length 5.08)
					(name "IO_L18N_T2_33"
						(effects
							(font
								(size 1.27 1.27)
							)
						)
					)
					(number "AJ11"
						(effects
							(font
								(size 1.27 1.27)
							)
						)
					)
				)
				(pin bidirectional line
					(at 0 -97.79 0)
					(length 5.08)
					(name "IO_L19P_T3_33"
						(effects
							(font
								(size 1.27 1.27)
							)
						)
					)
					(number "AE13"
						(effects
							(font
								(size 1.27 1.27)
							)
						)
					)
				)
				(pin bidirectional line
					(at 0 -100.33 0)
					(length 5.08)
					(name "IO_L19N_T3_VREF_33"
						(effects
							(font
								(size 1.27 1.27)
							)
						)
					)
					(number "AF13"
						(effects
							(font
								(size 1.27 1.27)
							)
						)
					)
				)
				(pin bidirectional line
					(at 0 -102.87 0)
					(length 5.08)
					(name "IO_L20P_T3_33"
						(effects
							(font
								(size 1.27 1.27)
							)
						)
					)
					(number "AK14"
						(effects
							(font
								(size 1.27 1.27)
							)
						)
					)
				)
				(pin bidirectional line
					(at 0 -105.41 0)
					(length 5.08)
					(name "IO_L20N_T3_33"
						(effects
							(font
								(size 1.27 1.27)
							)
						)
					)
					(number "AK13"
						(effects
							(font
								(size 1.27 1.27)
							)
						)
					)
				)
				(pin bidirectional line
					(at 0 -107.95 0)
					(length 5.08)
					(name "IO_L21P_T3_DQS_33"
						(effects
							(font
								(size 1.27 1.27)
							)
						)
					)
					(number "AH14"
						(effects
							(font
								(size 1.27 1.27)
							)
						)
					)
				)
				(pin bidirectional line
					(at 0 -110.49 0)
					(length 5.08)
					(name "IO_L21N_T3_DQS_33"
						(effects
							(font
								(size 1.27 1.27)
							)
						)
					)
					(number "AJ14"
						(effects
							(font
								(size 1.27 1.27)
							)
						)
					)
				)
				(pin bidirectional line
					(at 0 -113.03 0)
					(length 5.08)
					(name "IO_L22P_T3_33"
						(effects
							(font
								(size 1.27 1.27)
							)
						)
					)
					(number "AJ13"
						(effects
							(font
								(size 1.27 1.27)
							)
						)
					)
				)
				(pin bidirectional line
					(at 0 -115.57 0)
					(length 5.08)
					(name "IO_L22N_T3_33"
						(effects
							(font
								(size 1.27 1.27)
							)
						)
					)
					(number "AJ12"
						(effects
							(font
								(size 1.27 1.27)
							)
						)
					)
				)
				(pin bidirectional line
					(at 0 -118.11 0)
					(length 5.08)
					(name "IO_L23P_T3_33"
						(effects
							(font
								(size 1.27 1.27)
							)
						)
					)
					(number "AF12"
						(effects
							(font
								(size 1.27 1.27)
							)
						)
					)
				)
				(pin bidirectional line
					(at 0 -120.65 0)
					(length 5.08)
					(name "IO_L23N_T3_33"
						(effects
							(font
								(size 1.27 1.27)
							)
						)
					)
					(number "AG12"
						(effects
							(font
								(size 1.27 1.27)
							)
						)
					)
				)
				(pin bidirectional line
					(at 0 -123.19 0)
					(length 5.08)
					(name "IO_L24P_T3_33"
						(effects
							(font
								(size 1.27 1.27)
							)
						)
					)
					(number "AG13"
						(effects
							(font
								(size 1.27 1.27)
							)
						)
					)
				)
				(pin bidirectional line
					(at 0 -125.73 0)
					(length 5.08)
					(name "IO_L24N_T3_33"
						(effects
							(font
								(size 1.27 1.27)
							)
						)
					)
					(number "AH12"
						(effects
							(font
								(size 1.27 1.27)
							)
						)
					)
				)
				(pin bidirectional line
					(at 0 -128.27 0)
					(length 5.08)
					(name "IO_25_VRP_33"
						(effects
							(font
								(size 1.27 1.27)
							)
						)
					)
					(number "AD13"
						(effects
							(font
								(size 1.27 1.27)
							)
						)
					)
				)
				(pin bidirectional line
					(at 54.61 0 180)
					(length 5.08)
					(name "VCCO_34"
						(effects
							(font
								(size 1.27 1.27)
							)
						)
					)
					(number "AC3"
						(effects
							(font
								(size 1.27 1.27)
							)
						)
					)
				)
				(pin passive line
					(at 54.61 0 180)
					(length 5.08)
					(hide yes)
					(name "VCCO_34"
						(effects
							(font
								(size 1.27 1.27)
							)
						)
					)
					(number "AE7"
						(effects
							(font
								(size 1.27 1.27)
							)
						)
					)
				)
				(pin passive line
					(at 54.61 0 180)
					(length 5.08)
					(hide yes)
					(name "VCCO_34"
						(effects
							(font
								(size 1.27 1.27)
							)
						)
					)
					(number "AF4"
						(effects
							(font
								(size 1.27 1.27)
							)
						)
					)
				)
				(pin passive line
					(at 54.61 0 180)
					(length 5.08)
					(hide yes)
					(name "VCCO_34"
						(effects
							(font
								(size 1.27 1.27)
							)
						)
					)
					(number "AG1"
						(effects
							(font
								(size 1.27 1.27)
							)
						)
					)
				)
				(pin passive line
					(at 54.61 0 180)
					(length 5.08)
					(hide yes)
					(name "VCCO_34"
						(effects
							(font
								(size 1.27 1.27)
							)
						)
					)
					(number "AH8"
						(effects
							(font
								(size 1.27 1.27)
							)
						)
					)
				)
				(pin passive line
					(at 54.61 0 180)
					(length 5.08)
					(hide yes)
					(name "VCCO_34"
						(effects
							(font
								(size 1.27 1.27)
							)
						)
					)
					(number "AJ5"
						(effects
							(font
								(size 1.27 1.27)
							)
						)
					)
				)
				(pin passive line
					(at 54.61 0 180)
					(length 5.08)
					(hide yes)
					(name "VCCO_34"
						(effects
							(font
								(size 1.27 1.27)
							)
						)
					)
					(number "AK2"
						(effects
							(font
								(size 1.27 1.27)
							)
						)
					)
				)
				(pin bidirectional line
					(at 54.61 -3.81 180)
					(length 5.08)
					(name "IO_0_VRN_34"
						(effects
							(font
								(size 1.27 1.27)
							)
						)
					)
					(number "AC6"
						(effects
							(font
								(size 1.27 1.27)
							)
						)
					)
				)
				(pin bidirectional line
					(at 54.61 -6.35 180)
					(length 5.08)
					(name "IO_L1P_T0_34"
						(effects
							(font
								(size 1.27 1.27)
							)
						)
					)
					(number "AD4"
						(effects
							(font
								(size 1.27 1.27)
							)
						)
					)
				)
				(pin bidirectional line
					(at 54.61 -8.89 180)
					(length 5.08)
					(name "IO_L1N_T0_34"
						(effects
							(font
								(size 1.27 1.27)
							)
						)
					)
					(number "AD3"
						(effects
							(font
								(size 1.27 1.27)
							)
						)
					)
				)
				(pin bidirectional line
					(at 54.61 -11.43 180)
					(length 5.08)
					(name "IO_L2P_T0_34"
						(effects
							(font
								(size 1.27 1.27)
							)
						)
					)
					(number "AC2"
						(effects
							(font
								(size 1.27 1.27)
							)
						)
					)
				)
				(pin bidirectional line
					(at 54.61 -13.97 180)
					(length 5.08)
					(name "IO_L2N_T0_34"
						(effects
							(font
								(size 1.27 1.27)
							)
						)
					)
					(number "AC1"
						(effects
							(font
								(size 1.27 1.27)
							)
						)
					)
				)
				(pin bidirectional line
					(at 54.61 -16.51 180)
					(length 5.08)
					(name "IO_L3P_T0_DQS_34"
						(effects
							(font
								(size 1.27 1.27)
							)
						)
					)
					(number "AD2"
						(effects
							(font
								(size 1.27 1.27)
							)
						)
					)
				)
				(pin bidirectional line
					(at 54.61 -19.05 180)
					(length 5.08)
					(name "IO_L3N_T0_DQS_34"
						(effects
							(font
								(size 1.27 1.27)
							)
						)
					)
					(number "AD1"
						(effects
							(font
								(size 1.27 1.27)
							)
						)
					)
				)
				(pin bidirectional line
					(at 54.61 -21.59 180)
					(length 5.08)
					(name "IO_L4P_T0_34"
						(effects
							(font
								(size 1.27 1.27)
							)
						)
					)
					(number "AC5"
						(effects
							(font
								(size 1.27 1.27)
							)
						)
					)
				)
				(pin bidirectional line
					(at 54.61 -24.13 180)
					(length 5.08)
					(name "IO_L4N_T0_34"
						(effects
							(font
								(size 1.27 1.27)
							)
						)
					)
					(number "AC4"
						(effects
							(font
								(size 1.27 1.27)
							)
						)
					)
				)
				(pin bidirectional line
					(at 54.61 -26.67 180)
					(length 5.08)
					(name "IO_L5P_T0_34"
						(effects
							(font
								(size 1.27 1.27)
							)
						)
					)
					(number "AD6"
						(effects
							(font
								(size 1.27 1.27)
							)
						)
					)
				)
				(pin bidirectional line
					(at 54.61 -29.21 180)
					(length 5.08)
					(name "IO_L5N_T0_34"
						(effects
							(font
								(size 1.27 1.27)
							)
						)
					)
					(number "AE6"
						(effects
							(font
								(size 1.27 1.27)
							)
						)
					)
				)
				(pin bidirectional line
					(at 54.61 -31.75 180)
					(length 5.08)
					(name "IO_L6P_T0_34"
						(effects
							(font
								(size 1.27 1.27)
							)
						)
					)
					(number "AC7"
						(effects
							(font
								(size 1.27 1.27)
							)
						)
					)
				)
				(pin bidirectional line
					(at 54.61 -34.29 180)
					(length 5.08)
					(name "IO_L6N_T0_VREF_34"
						(effects
							(font
								(size 1.27 1.27)
							)
						)
					)
					(number "AD7"
						(effects
							(font
								(size 1.27 1.27)
							)
						)
					)
				)
				(pin bidirectional line
					(at 54.61 -36.83 180)
					(length 5.08)
					(name "IO_L7P_T1_34"
						(effects
							(font
								(size 1.27 1.27)
							)
						)
					)
					(number "AF3"
						(effects
							(font
								(size 1.27 1.27)
							)
						)
					)
				)
				(pin bidirectional line
					(at 54.61 -39.37 180)
					(length 5.08)
					(name "IO_L7N_T1_34"
						(effects
							(font
								(size 1.27 1.27)
							)
						)
					)
					(number "AF2"
						(effects
							(font
								(size 1.27 1.27)
							)
						)
					)
				)
				(pin bidirectional line
					(at 54.61 -41.91 180)
					(length 5.08)
					(name "IO_L8P_T1_34"
						(effects
							(font
								(size 1.27 1.27)
							)
						)
					)
					(number "AE1"
						(effects
							(font
								(size 1.27 1.27)
							)
						)
					)
				)
				(pin bidirectional line
					(at 54.61 -44.45 180)
					(length 5.08)
					(name "IO_L8N_T1_34"
						(effects
							(font
								(size 1.27 1.27)
							)
						)
					)
					(number "AF1"
						(effects
							(font
								(size 1.27 1.27)
							)
						)
					)
				)
				(pin bidirectional line
					(at 54.61 -46.99 180)
					(length 5.08)
					(name "IO_L9P_T1_DQS_34"
						(effects
							(font
								(size 1.27 1.27)
							)
						)
					)
					(number "AG4"
						(effects
							(font
								(size 1.27 1.27)
							)
						)
					)
				)
				(pin bidirectional line
					(at 54.61 -49.53 180)
					(length 5.08)
					(name "IO_L9N_T1_DQS_34"
						(effects
							(font
								(size 1.27 1.27)
							)
						)
					)
					(number "AG3"
						(effects
							(font
								(size 1.27 1.27)
							)
						)
					)
				)
				(pin bidirectional line
					(at 54.61 -52.07 180)
					(length 5.08)
					(name "IO_L10P_T1_34"
						(effects
							(font
								(size 1.27 1.27)
							)
						)
					)
					(number "AE4"
						(effects
							(font
								(size 1.27 1.27)
							)
						)
					)
				)
				(pin bidirectional line
					(at 54.61 -54.61 180)
					(length 5.08)
					(name "IO_L10N_T1_34"
						(effects
							(font
								(size 1.27 1.27)
							)
						)
					)
					(number "AE3"
						(effects
							(font
								(size 1.27 1.27)
							)
						)
					)
				)
				(pin bidirectional line
					(at 54.61 -57.15 180)
					(length 5.08)
					(name "IO_L11P_T1_SRCC_34"
						(effects
							(font
								(size 1.27 1.27)
							)
						)
					)
					(number "AE5"
						(effects
							(font
								(size 1.27 1.27)
							)
						)
					)
				)
				(pin bidirectional line
					(at 54.61 -59.69 180)
					(length 5.08)
					(name "IO_L11N_T1_SRCC_34"
						(effects
							(font
								(size 1.27 1.27)
							)
						)
					)
					(number "AF5"
						(effects
							(font
								(size 1.27 1.27)
							)
						)
					)
				)
				(pin bidirectional line
					(at 54.61 -62.23 180)
					(length 5.08)
					(name "IO_L12P_T1_MRCC_34"
						(effects
							(font
								(size 1.27 1.27)
							)
						)
					)
					(number "AF6"
						(effects
							(font
								(size 1.27 1.27)
							)
						)
					)
				)
				(pin bidirectional line
					(at 54.61 -64.77 180)
					(length 5.08)
					(name "IO_L12N_T1_MRCC_34"
						(effects
							(font
								(size 1.27 1.27)
							)
						)
					)
					(number "AG5"
						(effects
							(font
								(size 1.27 1.27)
							)
						)
					)
				)
				(pin bidirectional line
					(at 54.61 -67.31 180)
					(length 5.08)
					(name "IO_L13P_T2_MRCC_34"
						(effects
							(font
								(size 1.27 1.27)
							)
						)
					)
					(number "AH4"
						(effects
							(font
								(size 1.27 1.27)
							)
						)
					)
				)
				(pin bidirectional line
					(at 54.61 -69.85 180)
					(length 5.08)
					(name "IO_L13N_T2_MRCC_34"
						(effects
							(font
								(size 1.27 1.27)
							)
						)
					)
					(number "AJ4"
						(effects
							(font
								(size 1.27 1.27)
							)
						)
					)
				)
				(pin bidirectional line
					(at 54.61 -72.39 180)
					(length 5.08)
					(name "IO_L14P_T2_SRCC_34"
						(effects
							(font
								(size 1.27 1.27)
							)
						)
					)
					(number "AH6"
						(effects
							(font
								(size 1.27 1.27)
							)
						)
					)
				)
				(pin bidirectional line
					(at 54.61 -74.93 180)
					(length 5.08)
					(name "IO_L14N_T2_SRCC_34"
						(effects
							(font
								(size 1.27 1.27)
							)
						)
					)
					(number "AH5"
						(effects
							(font
								(size 1.27 1.27)
							)
						)
					)
				)
				(pin bidirectional line
					(at 54.61 -77.47 180)
					(length 5.08)
					(name "IO_L15P_T2_DQS_34"
						(effects
							(font
								(size 1.27 1.27)
							)
						)
					)
					(number "AG2"
						(effects
							(font
								(size 1.27 1.27)
							)
						)
					)
				)
				(pin bidirectional line
					(at 54.61 -80.01 180)
					(length 5.08)
					(name "IO_L15N_T2_DQS_34"
						(effects
							(font
								(size 1.27 1.27)
							)
						)
					)
					(number "AH1"
						(effects
							(font
								(size 1.27 1.27)
							)
						)
					)
				)
				(pin bidirectional line
					(at 54.61 -82.55 180)
					(length 5.08)
					(name "IO_L16P_T2_34"
						(effects
							(font
								(size 1.27 1.27)
							)
						)
					)
					(number "AH2"
						(effects
							(font
								(size 1.27 1.27)
							)
						)
					)
				)
				(pin bidirectional line
					(at 54.61 -85.09 180)
					(length 5.08)
					(name "IO_L16N_T2_34"
						(effects
							(font
								(size 1.27 1.27)
							)
						)
					)
					(number "AJ2"
						(effects
							(font
								(size 1.27 1.27)
							)
						)
					)
				)
				(pin bidirectional line
					(at 54.61 -87.63 180)
					(length 5.08)
					(name "IO_L17P_T2_34"
						(effects
							(font
								(size 1.27 1.27)
							)
						)
					)
					(number "AJ1"
						(effects
							(font
								(size 1.27 1.27)
							)
						)
					)
				)
				(pin bidirectional line
					(at 54.61 -90.17 180)
					(length 5.08)
					(name "IO_L17N_T2_34"
						(effects
							(font
								(size 1.27 1.27)
							)
						)
					)
					(number "AK1"
						(effects
							(font
								(size 1.27 1.27)
							)
						)
					)
				)
				(pin bidirectional line
					(at 54.61 -92.71 180)
					(length 5.08)
					(name "IO_L18P_T2_34"
						(effects
							(font
								(size 1.27 1.27)
							)
						)
					)
					(number "AJ3"
						(effects
							(font
								(size 1.27 1.27)
							)
						)
					)
				)
				(pin bidirectional line
					(at 54.61 -95.25 180)
					(length 5.08)
					(name "IO_L18N_T2_34"
						(effects
							(font
								(size 1.27 1.27)
							)
						)
					)
					(number "AK3"
						(effects
							(font
								(size 1.27 1.27)
							)
						)
					)
				)
				(pin bidirectional line
					(at 54.61 -97.79 180)
					(length 5.08)
					(name "IO_L19P_T3_34"
						(effects
							(font
								(size 1.27 1.27)
							)
						)
					)
					(number "AF8"
						(effects
							(font
								(size 1.27 1.27)
							)
						)
					)
				)
				(pin bidirectional line
					(at 54.61 -100.33 180)
					(length 5.08)
					(name "IO_L19N_T3_VREF_34"
						(effects
							(font
								(size 1.27 1.27)
							)
						)
					)
					(number "AG8"
						(effects
							(font
								(size 1.27 1.27)
							)
						)
					)
				)
				(pin bidirectional line
					(at 54.61 -102.87 180)
					(length 5.08)
					(name "IO_L20P_T3_34"
						(effects
							(font
								(size 1.27 1.27)
							)
						)
					)
					(number "AF7"
						(effects
							(font
								(size 1.27 1.27)
							)
						)
					)
				)
				(pin bidirectional line
					(at 54.61 -105.41 180)
					(length 5.08)
					(name "IO_L20N_T3_34"
						(effects
							(font
								(size 1.27 1.27)
							)
						)
					)
					(number "AG7"
						(effects
							(font
								(size 1.27 1.27)
							)
						)
					)
				)
				(pin bidirectional line
					(at 54.61 -107.95 180)
					(length 5.08)
					(name "IO_L21P_T3_DQS_34"
						(effects
							(font
								(size 1.27 1.27)
							)
						)
					)
					(number "AH7"
						(effects
							(font
								(size 1.27 1.27)
							)
						)
					)
				)
				(pin bidirectional line
					(at 54.61 -110.49 180)
					(length 5.08)
					(name "IO_L21N_T3_DQS_34"
						(effects
							(font
								(size 1.27 1.27)
							)
						)
					)
					(number "AJ7"
						(effects
							(font
								(size 1.27 1.27)
							)
						)
					)
				)
				(pin bidirectional line
					(at 54.61 -113.03 180)
					(length 5.08)
					(name "IO_L22P_T3_34"
						(effects
							(font
								(size 1.27 1.27)
							)
						)
					)
					(number "AJ6"
						(effects
							(font
								(size 1.27 1.27)
							)
						)
					)
				)
				(pin bidirectional line
					(at 54.61 -115.57 180)
					(length 5.08)
					(name "IO_L22N_T3_34"
						(effects
							(font
								(size 1.27 1.27)
							)
						)
					)
					(number "AK6"
						(effects
							(font
								(size 1.27 1.27)
							)
						)
					)
				)
				(pin bidirectional line
					(at 54.61 -118.11 180)
					(length 5.08)
					(name "IO_L23P_T3_34"
						(effects
							(font
								(size 1.27 1.27)
							)
						)
					)
					(number "AJ8"
						(effects
							(font
								(size 1.27 1.27)
							)
						)
					)
				)
				(pin bidirectional line
					(at 54.61 -120.65 180)
					(length 5.08)
					(name "IO_L23N_T3_34"
						(effects
							(font
								(size 1.27 1.27)
							)
						)
					)
					(number "AK8"
						(effects
							(font
								(size 1.27 1.27)
							)
						)
					)
				)
				(pin bidirectional line
					(at 54.61 -123.19 180)
					(length 5.08)
					(name "IO_L24P_T3_34"
						(effects
							(font
								(size 1.27 1.27)
							)
						)
					)
					(number "AK5"
						(effects
							(font
								(size 1.27 1.27)
							)
						)
					)
				)
				(pin bidirectional line
					(at 54.61 -125.73 180)
					(length 5.08)
					(name "IO_L24N_T3_34"
						(effects
							(font
								(size 1.27 1.27)
							)
						)
					)
					(number "AK4"
						(effects
							(font
								(size 1.27 1.27)
							)
						)
					)
				)
				(pin bidirectional line
					(at 54.61 -128.27 180)
					(length 5.08)
					(name "IO_25_VRP_34"
						(effects
							(font
								(size 1.27 1.27)
							)
						)
					)
					(number "AB7"
						(effects
							(font
								(size 1.27 1.27)
							)
						)
					)
				)
			)
			(symbol "XC7K410T-2FFG900I_3_6_1"
				(rectangle
					(start 5.08 5.08)
					(end 43.18 -53.34)
					(stroke
						(width 0.254)
						(type default)
					)
					(fill
						(type background)
					)
				)
				(text "GTX 115"
					(at 8.89 2.54 0)
					(effects
						(font
							(size 1.27 1.27)
							(thickness 0.15)
						)
						(justify left bottom)
					)
				)
				(text "GTX 116"
					(at 29.21 2.54 0)
					(effects
						(font
							(size 1.27 1.27)
							(thickness 0.15)
						)
						(justify left bottom)
					)
				)
				(pin bidirectional line
					(at 0 0 0)
					(length 5.08)
					(name "MGTXTXP0_115"
						(effects
							(font
								(size 1.27 1.27)
							)
						)
					)
					(number "Y2"
						(effects
							(font
								(size 1.27 1.27)
							)
						)
					)
				)
				(pin bidirectional line
					(at 0 -2.54 0)
					(length 5.08)
					(name "MGTXTXN0_115"
						(effects
							(font
								(size 1.27 1.27)
							)
						)
					)
					(number "Y1"
						(effects
							(font
								(size 1.27 1.27)
							)
						)
					)
				)
				(pin bidirectional line
					(at 0 -5.08 0)
					(length 5.08)
					(name "MGTXTXP1_115"
						(effects
							(font
								(size 1.27 1.27)
							)
						)
					)
					(number "V2"
						(effects
							(font
								(size 1.27 1.27)
							)
						)
					)
				)
				(pin bidirectional line
					(at 0 -7.62 0)
					(length 5.08)
					(name "MGTXTXN1_115"
						(effects
							(font
								(size 1.27 1.27)
							)
						)
					)
					(number "V1"
						(effects
							(font
								(size 1.27 1.27)
							)
						)
					)
				)
				(pin bidirectional line
					(at 0 -10.16 0)
					(length 5.08)
					(name "MGTXTXP2_115"
						(effects
							(font
								(size 1.27 1.27)
							)
						)
					)
					(number "U4"
						(effects
							(font
								(size 1.27 1.27)
							)
						)
					)
				)
				(pin bidirectional line
					(at 0 -12.7 0)
					(length 5.08)
					(name "MGTXTXN2_115"
						(effects
							(font
								(size 1.27 1.27)
							)
						)
					)
					(number "U3"
						(effects
							(font
								(size 1.27 1.27)
							)
						)
					)
				)
				(pin bidirectional line
					(at 0 -15.24 0)
					(length 5.08)
					(name "MGTXTXP3_115"
						(effects
							(font
								(size 1.27 1.27)
							)
						)
					)
					(number "T2"
						(effects
							(font
								(size 1.27 1.27)
							)
						)
					)
				)
				(pin bidirectional line
					(at 0 -17.78 0)
					(length 5.08)
					(name "MGTXTXN3_115"
						(effects
							(font
								(size 1.27 1.27)
							)
						)
					)
					(number "T1"
						(effects
							(font
								(size 1.27 1.27)
							)
						)
					)
				)
				(pin bidirectional line
					(at 0 -21.59 0)
					(length 5.08)
					(name "MGTXRXP0_115"
						(effects
							(font
								(size 1.27 1.27)
							)
						)
					)
					(number "AA4"
						(effects
							(font
								(size 1.27 1.27)
							)
						)
					)
				)
				(pin bidirectional line
					(at 0 -24.13 0)
					(length 5.08)
					(name "MGTXRXN0_115"
						(effects
							(font
								(size 1.27 1.27)
							)
						)
					)
					(number "AA3"
						(effects
							(font
								(size 1.27 1.27)
							)
						)
					)
				)
				(pin bidirectional line
					(at 0 -26.67 0)
					(length 5.08)
					(name "MGTXRXP1_115"
						(effects
							(font
								(size 1.27 1.27)
							)
						)
					)
					(number "Y6"
						(effects
							(font
								(size 1.27 1.27)
							)
						)
					)
				)
				(pin bidirectional line
					(at 0 -29.21 0)
					(length 5.08)
					(name "MGTXRXN1_115"
						(effects
							(font
								(size 1.27 1.27)
							)
						)
					)
					(number "Y5"
						(effects
							(font
								(size 1.27 1.27)
							)
						)
					)
				)
				(pin bidirectional line
					(at 0 -31.75 0)
					(length 5.08)
					(name "MGTXRXP2_115"
						(effects
							(font
								(size 1.27 1.27)
							)
						)
					)
					(number "W4"
						(effects
							(font
								(size 1.27 1.27)
							)
						)
					)
				)
				(pin bidirectional line
					(at 0 -34.29 0)
					(length 5.08)
					(name "MGTXRXN2_115"
						(effects
							(font
								(size 1.27 1.27)
							)
						)
					)
					(number "W3"
						(effects
							(font
								(size 1.27 1.27)
							)
						)
					)
				)
				(pin bidirectional line
					(at 0 -36.83 0)
					(length 5.08)
					(name "MGTXRXP3_115"
						(effects
							(font
								(size 1.27 1.27)
							)
						)
					)
					(number "V6"
						(effects
							(font
								(size 1.27 1.27)
							)
						)
					)
				)
				(pin bidirectional line
					(at 0 -39.37 0)
					(length 5.08)
					(name "MGTXRXN3_115"
						(effects
							(font
								(size 1.27 1.27)
							)
						)
					)
					(number "V5"
						(effects
							(font
								(size 1.27 1.27)
							)
						)
					)
				)
				(pin bidirectional line
					(at 0 -43.18 0)
					(length 5.08)
					(name "MGTREFCLK0P_115"
						(effects
							(font
								(size 1.27 1.27)
							)
						)
					)
					(number "R8"
						(effects
							(font
								(size 1.27 1.27)
							)
						)
					)
				)
				(pin bidirectional line
					(at 0 -45.72 0)
					(length 5.08)
					(name "MGTREFCLK0N_115"
						(effects
							(font
								(size 1.27 1.27)
							)
						)
					)
					(number "R7"
						(effects
							(font
								(size 1.27 1.27)
							)
						)
					)
				)
				(pin bidirectional line
					(at 0 -48.26 0)
					(length 5.08)
					(name "MGTREFCLK1P_115"
						(effects
							(font
								(size 1.27 1.27)
							)
						)
					)
					(number "U8"
						(effects
							(font
								(size 1.27 1.27)
							)
						)
					)
				)
				(pin bidirectional line
					(at 0 -50.8 0)
					(length 5.08)
					(name "MGTREFCLK1N_115"
						(effects
							(font
								(size 1.27 1.27)
							)
						)
					)
					(number "U7"
						(effects
							(font
								(size 1.27 1.27)
							)
						)
					)
				)
				(pin bidirectional line
					(at 48.26 0 180)
					(length 5.08)
					(name "MGTXTXP0_116"
						(effects
							(font
								(size 1.27 1.27)
							)
						)
					)
					(number "P2"
						(effects
							(font
								(size 1.27 1.27)
							)
						)
					)
				)
				(pin bidirectional line
					(at 48.26 -2.54 180)
					(length 5.08)
					(name "MGTXTXN0_116"
						(effects
							(font
								(size 1.27 1.27)
							)
						)
					)
					(number "P1"
						(effects
							(font
								(size 1.27 1.27)
							)
						)
					)
				)
				(pin bidirectional line
					(at 48.26 -5.08 180)
					(length 5.08)
					(name "MGTXTXP1_116"
						(effects
							(font
								(size 1.27 1.27)
							)
						)
					)
					(number "N4"
						(effects
							(font
								(size 1.27 1.27)
							)
						)
					)
				)
				(pin bidirectional line
					(at 48.26 -7.62 180)
					(length 5.08)
					(name "MGTXTXN1_116"
						(effects
							(font
								(size 1.27 1.27)
							)
						)
					)
					(number "N3"
						(effects
							(font
								(size 1.27 1.27)
							)
						)
					)
				)
				(pin bidirectional line
					(at 48.26 -10.16 180)
					(length 5.08)
					(name "MGTXTXP2_116"
						(effects
							(font
								(size 1.27 1.27)
							)
						)
					)
					(number "M2"
						(effects
							(font
								(size 1.27 1.27)
							)
						)
					)
				)
				(pin bidirectional line
					(at 48.26 -12.7 180)
					(length 5.08)
					(name "MGTXTXN2_116"
						(effects
							(font
								(size 1.27 1.27)
							)
						)
					)
					(number "M1"
						(effects
							(font
								(size 1.27 1.27)
							)
						)
					)
				)
				(pin bidirectional line
					(at 48.26 -15.24 180)
					(length 5.08)
					(name "MGTXTXP3_116"
						(effects
							(font
								(size 1.27 1.27)
							)
						)
					)
					(number "L4"
						(effects
							(font
								(size 1.27 1.27)
							)
						)
					)
				)
				(pin bidirectional line
					(at 48.26 -17.78 180)
					(length 5.08)
					(name "MGTXTXN3_116"
						(effects
							(font
								(size 1.27 1.27)
							)
						)
					)
					(number "L3"
						(effects
							(font
								(size 1.27 1.27)
							)
						)
					)
				)
				(pin bidirectional line
					(at 48.26 -21.59 180)
					(length 5.08)
					(name "MGTXRXP0_116"
						(effects
							(font
								(size 1.27 1.27)
							)
						)
					)
					(number "T6"
						(effects
							(font
								(size 1.27 1.27)
							)
						)
					)
				)
				(pin bidirectional line
					(at 48.26 -24.13 180)
					(length 5.08)
					(name "MGTXRXN0_116"
						(effects
							(font
								(size 1.27 1.27)
							)
						)
					)
					(number "T5"
						(effects
							(font
								(size 1.27 1.27)
							)
						)
					)
				)
				(pin bidirectional line
					(at 48.26 -26.67 180)
					(length 5.08)
					(name "MGTXRXP1_116"
						(effects
							(font
								(size 1.27 1.27)
							)
						)
					)
					(number "R4"
						(effects
							(font
								(size 1.27 1.27)
							)
						)
					)
				)
				(pin bidirectional line
					(at 48.26 -29.21 180)
					(length 5.08)
					(name "MGTXRXN1_116"
						(effects
							(font
								(size 1.27 1.27)
							)
						)
					)
					(number "R3"
						(effects
							(font
								(size 1.27 1.27)
							)
						)
					)
				)
				(pin bidirectional line
					(at 48.26 -31.75 180)
					(length 5.08)
					(name "MGTXRXP2_116"
						(effects
							(font
								(size 1.27 1.27)
							)
						)
					)
					(number "P6"
						(effects
							(font
								(size 1.27 1.27)
							)
						)
					)
				)
				(pin bidirectional line
					(at 48.26 -34.29 180)
					(length 5.08)
					(name "MGTXRXN2_116"
						(effects
							(font
								(size 1.27 1.27)
							)
						)
					)
					(number "P5"
						(effects
							(font
								(size 1.27 1.27)
							)
						)
					)
				)
				(pin bidirectional line
					(at 48.26 -36.83 180)
					(length 5.08)
					(name "MGTXRXP3_116"
						(effects
							(font
								(size 1.27 1.27)
							)
						)
					)
					(number "M6"
						(effects
							(font
								(size 1.27 1.27)
							)
						)
					)
				)
				(pin bidirectional line
					(at 48.26 -39.37 180)
					(length 5.08)
					(name "MGTXRXN3_116"
						(effects
							(font
								(size 1.27 1.27)
							)
						)
					)
					(number "M5"
						(effects
							(font
								(size 1.27 1.27)
							)
						)
					)
				)
				(pin bidirectional line
					(at 48.26 -43.18 180)
					(length 5.08)
					(name "MGTREFCLK0P_116"
						(effects
							(font
								(size 1.27 1.27)
							)
						)
					)
					(number "L8"
						(effects
							(font
								(size 1.27 1.27)
							)
						)
					)
				)
				(pin bidirectional line
					(at 48.26 -45.72 180)
					(length 5.08)
					(name "MGTREFCLK0N_116"
						(effects
							(font
								(size 1.27 1.27)
							)
						)
					)
					(number "L7"
						(effects
							(font
								(size 1.27 1.27)
							)
						)
					)
				)
				(pin bidirectional line
					(at 48.26 -48.26 180)
					(length 5.08)
					(name "MGTREFCLK1P_116"
						(effects
							(font
								(size 1.27 1.27)
							)
						)
					)
					(number "N8"
						(effects
							(font
								(size 1.27 1.27)
							)
						)
					)
				)
				(pin bidirectional line
					(at 48.26 -50.8 180)
					(length 5.08)
					(name "MGTREFCLK1N_116"
						(effects
							(font
								(size 1.27 1.27)
							)
						)
					)
					(number "N7"
						(effects
							(font
								(size 1.27 1.27)
							)
						)
					)
				)
			)
			(symbol "XC7K410T-2FFG900I_3_7_1"
				(rectangle
					(start 5.08 5.08)
					(end 43.18 -53.34)
					(stroke
						(width 0.254)
						(type default)
					)
					(fill
						(type background)
					)
				)
				(text "GTX 117"
					(at 8.89 2.54 0)
					(effects
						(font
							(size 1.27 1.27)
							(thickness 0.15)
						)
						(justify left bottom)
					)
				)
				(text "GTX 118"
					(at 29.21 2.54 0)
					(effects
						(font
							(size 1.27 1.27)
							(thickness 0.15)
						)
						(justify left bottom)
					)
				)
				(pin bidirectional line
					(at 0 0 0)
					(length 5.08)
					(name "MGTXTXP0_117"
						(effects
							(font
								(size 1.27 1.27)
							)
						)
					)
					(number "K2"
						(effects
							(font
								(size 1.27 1.27)
							)
						)
					)
				)
				(pin bidirectional line
					(at 0 -2.54 0)
					(length 5.08)
					(name "MGTXTXN0_117"
						(effects
							(font
								(size 1.27 1.27)
							)
						)
					)
					(number "K1"
						(effects
							(font
								(size 1.27 1.27)
							)
						)
					)
				)
				(pin bidirectional line
					(at 0 -5.08 0)
					(length 5.08)
					(name "MGTXTXP1_117"
						(effects
							(font
								(size 1.27 1.27)
							)
						)
					)
					(number "J4"
						(effects
							(font
								(size 1.27 1.27)
							)
						)
					)
				)
				(pin bidirectional line
					(at 0 -7.62 0)
					(length 5.08)
					(name "MGTXTXN1_117"
						(effects
							(font
								(size 1.27 1.27)
							)
						)
					)
					(number "J3"
						(effects
							(font
								(size 1.27 1.27)
							)
						)
					)
				)
				(pin bidirectional line
					(at 0 -10.16 0)
					(length 5.08)
					(name "MGTXTXP2_117"
						(effects
							(font
								(size 1.27 1.27)
							)
						)
					)
					(number "H2"
						(effects
							(font
								(size 1.27 1.27)
							)
						)
					)
				)
				(pin bidirectional line
					(at 0 -12.7 0)
					(length 5.08)
					(name "MGTXTXN2_117"
						(effects
							(font
								(size 1.27 1.27)
							)
						)
					)
					(number "H1"
						(effects
							(font
								(size 1.27 1.27)
							)
						)
					)
				)
				(pin bidirectional line
					(at 0 -15.24 0)
					(length 5.08)
					(name "MGTXTXP3_117"
						(effects
							(font
								(size 1.27 1.27)
							)
						)
					)
					(number "F2"
						(effects
							(font
								(size 1.27 1.27)
							)
						)
					)
				)
				(pin bidirectional line
					(at 0 -17.78 0)
					(length 5.08)
					(name "MGTXTXN3_117"
						(effects
							(font
								(size 1.27 1.27)
							)
						)
					)
					(number "F1"
						(effects
							(font
								(size 1.27 1.27)
							)
						)
					)
				)
				(pin bidirectional line
					(at 0 -21.59 0)
					(length 5.08)
					(name "MGTXRXP0_117"
						(effects
							(font
								(size 1.27 1.27)
							)
						)
					)
					(number "K6"
						(effects
							(font
								(size 1.27 1.27)
							)
						)
					)
				)
				(pin bidirectional line
					(at 0 -24.13 0)
					(length 5.08)
					(name "MGTXRXN0_117"
						(effects
							(font
								(size 1.27 1.27)
							)
						)
					)
					(number "K5"
						(effects
							(font
								(size 1.27 1.27)
							)
						)
					)
				)
				(pin bidirectional line
					(at 0 -26.67 0)
					(length 5.08)
					(name "MGTXRXP1_117"
						(effects
							(font
								(size 1.27 1.27)
							)
						)
					)
					(number "H6"
						(effects
							(font
								(size 1.27 1.27)
							)
						)
					)
				)
				(pin bidirectional line
					(at 0 -29.21 0)
					(length 5.08)
					(name "MGTXRXN1_117"
						(effects
							(font
								(size 1.27 1.27)
							)
						)
					)
					(number "H5"
						(effects
							(font
								(size 1.27 1.27)
							)
						)
					)
				)
				(pin bidirectional line
					(at 0 -31.75 0)
					(length 5.08)
					(name "MGTXRXP2_117"
						(effects
							(font
								(size 1.27 1.27)
							)
						)
					)
					(number "G4"
						(effects
							(font
								(size 1.27 1.27)
							)
						)
					)
				)
				(pin bidirectional line
					(at 0 -34.29 0)
					(length 5.08)
					(name "MGTXRXN2_117"
						(effects
							(font
								(size 1.27 1.27)
							)
						)
					)
					(number "G3"
						(effects
							(font
								(size 1.27 1.27)
							)
						)
					)
				)
				(pin bidirectional line
					(at 0 -36.83 0)
					(length 5.08)
					(name "MGTXRXP3_117"
						(effects
							(font
								(size 1.27 1.27)
							)
						)
					)
					(number "F6"
						(effects
							(font
								(size 1.27 1.27)
							)
						)
					)
				)
				(pin bidirectional line
					(at 0 -39.37 0)
					(length 5.08)
					(name "MGTXRXN3_117"
						(effects
							(font
								(size 1.27 1.27)
							)
						)
					)
					(number "F5"
						(effects
							(font
								(size 1.27 1.27)
							)
						)
					)
				)
				(pin bidirectional line
					(at 0 -43.18 0)
					(length 5.08)
					(name "MGTREFCLK0P_117"
						(effects
							(font
								(size 1.27 1.27)
							)
						)
					)
					(number "G8"
						(effects
							(font
								(size 1.27 1.27)
							)
						)
					)
				)
				(pin bidirectional line
					(at 0 -45.72 0)
					(length 5.08)
					(name "MGTREFCLK0N_117"
						(effects
							(font
								(size 1.27 1.27)
							)
						)
					)
					(number "G7"
						(effects
							(font
								(size 1.27 1.27)
							)
						)
					)
				)
				(pin bidirectional line
					(at 0 -48.26 0)
					(length 5.08)
					(name "MGTREFCLK1P_117"
						(effects
							(font
								(size 1.27 1.27)
							)
						)
					)
					(number "J8"
						(effects
							(font
								(size 1.27 1.27)
							)
						)
					)
				)
				(pin bidirectional line
					(at 0 -50.8 0)
					(length 5.08)
					(name "MGTREFCLK1N_117"
						(effects
							(font
								(size 1.27 1.27)
							)
						)
					)
					(number "J7"
						(effects
							(font
								(size 1.27 1.27)
							)
						)
					)
				)
				(pin bidirectional line
					(at 48.26 0 180)
					(length 5.08)
					(name "MGTXTXP0_118"
						(effects
							(font
								(size 1.27 1.27)
							)
						)
					)
					(number "D2"
						(effects
							(font
								(size 1.27 1.27)
							)
						)
					)
				)
				(pin bidirectional line
					(at 48.26 -2.54 180)
					(length 5.08)
					(name "MGTXTXN0_118"
						(effects
							(font
								(size 1.27 1.27)
							)
						)
					)
					(number "D1"
						(effects
							(font
								(size 1.27 1.27)
							)
						)
					)
				)
				(pin bidirectional line
					(at 48.26 -5.08 180)
					(length 5.08)
					(name "MGTXTXP1_118"
						(effects
							(font
								(size 1.27 1.27)
							)
						)
					)
					(number "C4"
						(effects
							(font
								(size 1.27 1.27)
							)
						)
					)
				)
				(pin bidirectional line
					(at 48.26 -7.62 180)
					(length 5.08)
					(name "MGTXTXN1_118"
						(effects
							(font
								(size 1.27 1.27)
							)
						)
					)
					(number "C3"
						(effects
							(font
								(size 1.27 1.27)
							)
						)
					)
				)
				(pin bidirectional line
					(at 48.26 -10.16 180)
					(length 5.08)
					(name "MGTXTXP2_118"
						(effects
							(font
								(size 1.27 1.27)
							)
						)
					)
					(number "B2"
						(effects
							(font
								(size 1.27 1.27)
							)
						)
					)
				)
				(pin bidirectional line
					(at 48.26 -12.7 180)
					(length 5.08)
					(name "MGTXTXN2_118"
						(effects
							(font
								(size 1.27 1.27)
							)
						)
					)
					(number "B1"
						(effects
							(font
								(size 1.27 1.27)
							)
						)
					)
				)
				(pin bidirectional line
					(at 48.26 -15.24 180)
					(length 5.08)
					(name "MGTXTXP3_118"
						(effects
							(font
								(size 1.27 1.27)
							)
						)
					)
					(number "A4"
						(effects
							(font
								(size 1.27 1.27)
							)
						)
					)
				)
				(pin bidirectional line
					(at 48.26 -17.78 180)
					(length 5.08)
					(name "MGTXTXN3_118"
						(effects
							(font
								(size 1.27 1.27)
							)
						)
					)
					(number "A3"
						(effects
							(font
								(size 1.27 1.27)
							)
						)
					)
				)
				(pin bidirectional line
					(at 48.26 -21.59 180)
					(length 5.08)
					(name "MGTXRXP0_118"
						(effects
							(font
								(size 1.27 1.27)
							)
						)
					)
					(number "E4"
						(effects
							(font
								(size 1.27 1.27)
							)
						)
					)
				)
				(pin bidirectional line
					(at 48.26 -24.13 180)
					(length 5.08)
					(name "MGTXRXN0_118"
						(effects
							(font
								(size 1.27 1.27)
							)
						)
					)
					(number "E3"
						(effects
							(font
								(size 1.27 1.27)
							)
						)
					)
				)
				(pin bidirectional line
					(at 48.26 -26.67 180)
					(length 5.08)
					(name "MGTXRXP1_118"
						(effects
							(font
								(size 1.27 1.27)
							)
						)
					)
					(number "D6"
						(effects
							(font
								(size 1.27 1.27)
							)
						)
					)
				)
				(pin bidirectional line
					(at 48.26 -29.21 180)
					(length 5.08)
					(name "MGTXRXN1_118"
						(effects
							(font
								(size 1.27 1.27)
							)
						)
					)
					(number "D5"
						(effects
							(font
								(size 1.27 1.27)
							)
						)
					)
				)
				(pin bidirectional line
					(at 48.26 -31.75 180)
					(length 5.08)
					(name "MGTXRXP2_118"
						(effects
							(font
								(size 1.27 1.27)
							)
						)
					)
					(number "B6"
						(effects
							(font
								(size 1.27 1.27)
							)
						)
					)
				)
				(pin bidirectional line
					(at 48.26 -34.29 180)
					(length 5.08)
					(name "MGTXRXN2_118"
						(effects
							(font
								(size 1.27 1.27)
							)
						)
					)
					(number "B5"
						(effects
							(font
								(size 1.27 1.27)
							)
						)
					)
				)
				(pin bidirectional line
					(at 48.26 -36.83 180)
					(length 5.08)
					(name "MGTXRXP3_118"
						(effects
							(font
								(size 1.27 1.27)
							)
						)
					)
					(number "A8"
						(effects
							(font
								(size 1.27 1.27)
							)
						)
					)
				)
				(pin bidirectional line
					(at 48.26 -39.37 180)
					(length 5.08)
					(name "MGTXRXN3_118"
						(effects
							(font
								(size 1.27 1.27)
							)
						)
					)
					(number "A7"
						(effects
							(font
								(size 1.27 1.27)
							)
						)
					)
				)
				(pin bidirectional line
					(at 48.26 -43.18 180)
					(length 5.08)
					(name "MGTREFCLK0P_118"
						(effects
							(font
								(size 1.27 1.27)
							)
						)
					)
					(number "C8"
						(effects
							(font
								(size 1.27 1.27)
							)
						)
					)
				)
				(pin bidirectional line
					(at 48.26 -45.72 180)
					(length 5.08)
					(name "MGTREFCLK0N_118"
						(effects
							(font
								(size 1.27 1.27)
							)
						)
					)
					(number "C7"
						(effects
							(font
								(size 1.27 1.27)
							)
						)
					)
				)
				(pin bidirectional line
					(at 48.26 -48.26 180)
					(length 5.08)
					(name "MGTREFCLK1P_118"
						(effects
							(font
								(size 1.27 1.27)
							)
						)
					)
					(number "E8"
						(effects
							(font
								(size 1.27 1.27)
							)
						)
					)
				)
				(pin bidirectional line
					(at 48.26 -50.8 180)
					(length 5.08)
					(name "MGTREFCLK1N_118"
						(effects
							(font
								(size 1.27 1.27)
							)
						)
					)
					(number "E7"
						(effects
							(font
								(size 1.27 1.27)
							)
						)
					)
				)
			)
			(symbol "XC7K410T-2FFG900I_3_8_1"
				(rectangle
					(start 5.08 2.54)
					(end 24.13 -13.97)
					(stroke
						(width 0.254)
						(type default)
					)
					(fill
						(type background)
					)
				)
				(pin bidirectional line
					(at 0 0 0)
					(length 5.08)
					(name "MGTAVCC"
						(effects
							(font
								(size 1.27 1.27)
							)
						)
					)
					(number "B7"
						(effects
							(font
								(size 1.27 1.27)
							)
						)
					)
				)
				(pin passive line
					(at 0 0 0)
					(length 5.08)
					(hide yes)
					(name "MGTAVCC"
						(effects
							(font
								(size 1.27 1.27)
							)
						)
					)
					(number "D7"
						(effects
							(font
								(size 1.27 1.27)
							)
						)
					)
				)
				(pin passive line
					(at 0 0 0)
					(length 5.08)
					(hide yes)
					(name "MGTAVCC"
						(effects
							(font
								(size 1.27 1.27)
							)
						)
					)
					(number "F7"
						(effects
							(font
								(size 1.27 1.27)
							)
						)
					)
				)
				(pin passive line
					(at 0 0 0)
					(length 5.08)
					(hide yes)
					(name "MGTAVCC"
						(effects
							(font
								(size 1.27 1.27)
							)
						)
					)
					(number "H7"
						(effects
							(font
								(size 1.27 1.27)
							)
						)
					)
				)
				(pin passive line
					(at 0 0 0)
					(length 5.08)
					(hide yes)
					(name "MGTAVCC"
						(effects
							(font
								(size 1.27 1.27)
							)
						)
					)
					(number "K7"
						(effects
							(font
								(size 1.27 1.27)
							)
						)
					)
				)
				(pin passive line
					(at 0 0 0)
					(length 5.08)
					(hide yes)
					(name "MGTAVCC"
						(effects
							(font
								(size 1.27 1.27)
							)
						)
					)
					(number "M7"
						(effects
							(font
								(size 1.27 1.27)
							)
						)
					)
				)
				(pin passive line
					(at 0 0 0)
					(length 5.08)
					(hide yes)
					(name "MGTAVCC"
						(effects
							(font
								(size 1.27 1.27)
							)
						)
					)
					(number "P7"
						(effects
							(font
								(size 1.27 1.27)
							)
						)
					)
				)
				(pin bidirectional line
					(at 0 -2.54 0)
					(length 5.08)
					(name "MGTVCCAUX"
						(effects
							(font
								(size 1.27 1.27)
							)
						)
					)
					(number "T7"
						(effects
							(font
								(size 1.27 1.27)
							)
						)
					)
				)
				(pin passive line
					(at 0 -2.54 0)
					(length 5.08)
					(hide yes)
					(name "MGTVCCAUX"
						(effects
							(font
								(size 1.27 1.27)
							)
						)
					)
					(number "V7"
						(effects
							(font
								(size 1.27 1.27)
							)
						)
					)
				)
				(pin bidirectional line
					(at 0 -6.35 0)
					(length 5.08)
					(name "MGTAVTTRCAL_115"
						(effects
							(font
								(size 1.27 1.27)
							)
						)
					)
					(number "W7"
						(effects
							(font
								(size 1.27 1.27)
							)
						)
					)
				)
				(pin bidirectional line
					(at 0 -8.89 0)
					(length 5.08)
					(name "MGTAVTT"
						(effects
							(font
								(size 1.27 1.27)
							)
						)
					)
					(number "B3"
						(effects
							(font
								(size 1.27 1.27)
							)
						)
					)
				)
				(pin passive line
					(at 0 -8.89 0)
					(length 5.08)
					(hide yes)
					(name "MGTAVTT"
						(effects
							(font
								(size 1.27 1.27)
							)
						)
					)
					(number "C5"
						(effects
							(font
								(size 1.27 1.27)
							)
						)
					)
				)
				(pin passive line
					(at 0 -8.89 0)
					(length 5.08)
					(hide yes)
					(name "MGTAVTT"
						(effects
							(font
								(size 1.27 1.27)
							)
						)
					)
					(number "D3"
						(effects
							(font
								(size 1.27 1.27)
							)
						)
					)
				)
				(pin passive line
					(at 0 -8.89 0)
					(length 5.08)
					(hide yes)
					(name "MGTAVTT"
						(effects
							(font
								(size 1.27 1.27)
							)
						)
					)
					(number "E5"
						(effects
							(font
								(size 1.27 1.27)
							)
						)
					)
				)
				(pin passive line
					(at 0 -8.89 0)
					(length 5.08)
					(hide yes)
					(name "MGTAVTT"
						(effects
							(font
								(size 1.27 1.27)
							)
						)
					)
					(number "F3"
						(effects
							(font
								(size 1.27 1.27)
							)
						)
					)
				)
				(pin passive line
					(at 0 -8.89 0)
					(length 5.08)
					(hide yes)
					(name "MGTAVTT"
						(effects
							(font
								(size 1.27 1.27)
							)
						)
					)
					(number "G5"
						(effects
							(font
								(size 1.27 1.27)
							)
						)
					)
				)
				(pin passive line
					(at 0 -8.89 0)
					(length 5.08)
					(hide yes)
					(name "MGTAVTT"
						(effects
							(font
								(size 1.27 1.27)
							)
						)
					)
					(number "H3"
						(effects
							(font
								(size 1.27 1.27)
							)
						)
					)
				)
				(pin passive line
					(at 0 -8.89 0)
					(length 5.08)
					(hide yes)
					(name "MGTAVTT"
						(effects
							(font
								(size 1.27 1.27)
							)
						)
					)
					(number "J5"
						(effects
							(font
								(size 1.27 1.27)
							)
						)
					)
				)
				(pin passive line
					(at 0 -8.89 0)
					(length 5.08)
					(hide yes)
					(name "MGTAVTT"
						(effects
							(font
								(size 1.27 1.27)
							)
						)
					)
					(number "K3"
						(effects
							(font
								(size 1.27 1.27)
							)
						)
					)
				)
				(pin passive line
					(at 0 -8.89 0)
					(length 5.08)
					(hide yes)
					(name "MGTAVTT"
						(effects
							(font
								(size 1.27 1.27)
							)
						)
					)
					(number "L5"
						(effects
							(font
								(size 1.27 1.27)
							)
						)
					)
				)
				(pin passive line
					(at 0 -8.89 0)
					(length 5.08)
					(hide yes)
					(name "MGTAVTT"
						(effects
							(font
								(size 1.27 1.27)
							)
						)
					)
					(number "M3"
						(effects
							(font
								(size 1.27 1.27)
							)
						)
					)
				)
				(pin passive line
					(at 0 -8.89 0)
					(length 5.08)
					(hide yes)
					(name "MGTAVTT"
						(effects
							(font
								(size 1.27 1.27)
							)
						)
					)
					(number "N5"
						(effects
							(font
								(size 1.27 1.27)
							)
						)
					)
				)
				(pin passive line
					(at 0 -8.89 0)
					(length 5.08)
					(hide yes)
					(name "MGTAVTT"
						(effects
							(font
								(size 1.27 1.27)
							)
						)
					)
					(number "P3"
						(effects
							(font
								(size 1.27 1.27)
							)
						)
					)
				)
				(pin passive line
					(at 0 -8.89 0)
					(length 5.08)
					(hide yes)
					(name "MGTAVTT"
						(effects
							(font
								(size 1.27 1.27)
							)
						)
					)
					(number "R5"
						(effects
							(font
								(size 1.27 1.27)
							)
						)
					)
				)
				(pin passive line
					(at 0 -8.89 0)
					(length 5.08)
					(hide yes)
					(name "MGTAVTT"
						(effects
							(font
								(size 1.27 1.27)
							)
						)
					)
					(number "T3"
						(effects
							(font
								(size 1.27 1.27)
							)
						)
					)
				)
				(pin passive line
					(at 0 -8.89 0)
					(length 5.08)
					(hide yes)
					(name "MGTAVTT"
						(effects
							(font
								(size 1.27 1.27)
							)
						)
					)
					(number "U5"
						(effects
							(font
								(size 1.27 1.27)
							)
						)
					)
				)
				(pin passive line
					(at 0 -8.89 0)
					(length 5.08)
					(hide yes)
					(name "MGTAVTT"
						(effects
							(font
								(size 1.27 1.27)
							)
						)
					)
					(number "V3"
						(effects
							(font
								(size 1.27 1.27)
							)
						)
					)
				)
				(pin passive line
					(at 0 -8.89 0)
					(length 5.08)
					(hide yes)
					(name "MGTAVTT"
						(effects
							(font
								(size 1.27 1.27)
							)
						)
					)
					(number "W5"
						(effects
							(font
								(size 1.27 1.27)
							)
						)
					)
				)
				(pin bidirectional line
					(at 0 -11.43 0)
					(length 5.08)
					(name "MGTRREF_115"
						(effects
							(font
								(size 1.27 1.27)
							)
						)
					)
					(number "W8"
						(effects
							(font
								(size 1.27 1.27)
							)
						)
					)
				)
			)
			(symbol "XC7K410T-2FFG900I_3_9_1"
				(rectangle
					(start 5.08 2.54)
					(end 27.94 -29.21)
					(stroke
						(width 0.254)
						(type default)
					)
					(fill
						(type background)
					)
				)
				(pin bidirectional line
					(at 0 0 0)
					(length 5.08)
					(name "VCCO_0"
						(effects
							(font
								(size 1.27 1.27)
							)
						)
					)
					(number "AB6"
						(effects
							(font
								(size 1.27 1.27)
							)
						)
					)
				)
				(pin passive line
					(at 0 0 0)
					(length 5.08)
					(hide yes)
					(name "VCCO_0"
						(effects
							(font
								(size 1.27 1.27)
							)
						)
					)
					(number "T9"
						(effects
							(font
								(size 1.27 1.27)
							)
						)
					)
				)
				(pin bidirectional line
					(at 0 -3.81 0)
					(length 5.08)
					(name "CCLK_0"
						(effects
							(font
								(size 1.27 1.27)
							)
						)
					)
					(number "B10"
						(effects
							(font
								(size 1.27 1.27)
							)
						)
					)
				)
				(pin bidirectional line
					(at 0 -6.35 0)
					(length 5.08)
					(name "M0_0"
						(effects
							(font
								(size 1.27 1.27)
							)
						)
					)
					(number "AB5"
						(effects
							(font
								(size 1.27 1.27)
							)
						)
					)
				)
				(pin bidirectional line
					(at 0 -8.89 0)
					(length 5.08)
					(name "M1_0"
						(effects
							(font
								(size 1.27 1.27)
							)
						)
					)
					(number "AB2"
						(effects
							(font
								(size 1.27 1.27)
							)
						)
					)
				)
				(pin bidirectional line
					(at 0 -11.43 0)
					(length 5.08)
					(name "M2_0"
						(effects
							(font
								(size 1.27 1.27)
							)
						)
					)
					(number "AB1"
						(effects
							(font
								(size 1.27 1.27)
							)
						)
					)
				)
				(pin bidirectional line
					(at 0 -15.24 0)
					(length 5.08)
					(name "TDI_0"
						(effects
							(font
								(size 1.27 1.27)
							)
						)
					)
					(number "H10"
						(effects
							(font
								(size 1.27 1.27)
							)
						)
					)
				)
				(pin bidirectional line
					(at 0 -17.78 0)
					(length 5.08)
					(name "TDO_0"
						(effects
							(font
								(size 1.27 1.27)
							)
						)
					)
					(number "G10"
						(effects
							(font
								(size 1.27 1.27)
							)
						)
					)
				)
				(pin bidirectional line
					(at 0 -20.32 0)
					(length 5.08)
					(name "TMS_0"
						(effects
							(font
								(size 1.27 1.27)
							)
						)
					)
					(number "F10"
						(effects
							(font
								(size 1.27 1.27)
							)
						)
					)
				)
				(pin bidirectional line
					(at 0 -22.86 0)
					(length 5.08)
					(name "TCK_0"
						(effects
							(font
								(size 1.27 1.27)
							)
						)
					)
					(number "E10"
						(effects
							(font
								(size 1.27 1.27)
							)
						)
					)
				)
				(pin bidirectional line
					(at 0 -26.67 0)
					(length 5.08)
					(name "CFGBVS_0"
						(effects
							(font
								(size 1.27 1.27)
							)
						)
					)
					(number "L10"
						(effects
							(font
								(size 1.27 1.27)
							)
						)
					)
				)
				(pin bidirectional line
					(at 33.02 0 180)
					(length 5.08)
					(name "DONE_0"
						(effects
							(font
								(size 1.27 1.27)
							)
						)
					)
					(number "M10"
						(effects
							(font
								(size 1.27 1.27)
							)
						)
					)
				)
				(pin bidirectional line
					(at 33.02 -2.54 180)
					(length 5.08)
					(name "INIT_B_0"
						(effects
							(font
								(size 1.27 1.27)
							)
						)
					)
					(number "A10"
						(effects
							(font
								(size 1.27 1.27)
							)
						)
					)
				)
				(pin bidirectional line
					(at 33.02 -5.08 180)
					(length 5.08)
					(name "PROGRAM_B_0"
						(effects
							(font
								(size 1.27 1.27)
							)
						)
					)
					(number "K10"
						(effects
							(font
								(size 1.27 1.27)
							)
						)
					)
				)
				(pin bidirectional line
					(at 33.02 -8.89 180)
					(length 5.08)
					(name "VP_0"
						(effects
							(font
								(size 1.27 1.27)
							)
						)
					)
					(number "R15"
						(effects
							(font
								(size 1.27 1.27)
							)
						)
					)
				)
				(pin bidirectional line
					(at 33.02 -11.43 180)
					(length 5.08)
					(name "VN_0"
						(effects
							(font
								(size 1.27 1.27)
							)
						)
					)
					(number "T14"
						(effects
							(font
								(size 1.27 1.27)
							)
						)
					)
				)
				(pin bidirectional line
					(at 33.02 -15.24 180)
					(length 5.08)
					(name "VREFP_0"
						(effects
							(font
								(size 1.27 1.27)
							)
						)
					)
					(number "T15"
						(effects
							(font
								(size 1.27 1.27)
							)
						)
					)
				)
				(pin bidirectional line
					(at 33.02 -17.78 180)
					(length 5.08)
					(name "VREFN_0"
						(effects
							(font
								(size 1.27 1.27)
							)
						)
					)
					(number "R14"
						(effects
							(font
								(size 1.27 1.27)
							)
						)
					)
				)
				(pin bidirectional line
					(at 33.02 -21.59 180)
					(length 5.08)
					(name "DXP_0"
						(effects
							(font
								(size 1.27 1.27)
							)
						)
					)
					(number "U15"
						(effects
							(font
								(size 1.27 1.27)
							)
						)
					)
				)
				(pin bidirectional line
					(at 33.02 -24.13 180)
					(length 5.08)
					(name "DXN_0"
						(effects
							(font
								(size 1.27 1.27)
							)
						)
					)
					(number "U14"
						(effects
							(font
								(size 1.27 1.27)
							)
						)
					)
				)
			)
			(symbol "XC7K410T-2FFG900I_3_10_1"
				(rectangle
					(start 5.08 2.54)
					(end 20.32 -21.59)
					(stroke
						(width 0.254)
						(type default)
					)
					(fill
						(type background)
					)
				)
				(pin bidirectional line
					(at 0 0 0)
					(length 5.08)
					(name "VCCAUX"
						(effects
							(font
								(size 1.27 1.27)
							)
						)
					)
					(number "P13"
						(effects
							(font
								(size 1.27 1.27)
							)
						)
					)
				)
				(pin passive line
					(at 0 0 0)
					(length 5.08)
					(hide yes)
					(name "VCCAUX"
						(effects
							(font
								(size 1.27 1.27)
							)
						)
					)
					(number "T13"
						(effects
							(font
								(size 1.27 1.27)
							)
						)
					)
				)
				(pin passive line
					(at 0 0 0)
					(length 5.08)
					(hide yes)
					(name "VCCAUX"
						(effects
							(font
								(size 1.27 1.27)
							)
						)
					)
					(number "V13"
						(effects
							(font
								(size 1.27 1.27)
							)
						)
					)
				)
				(pin passive line
					(at 0 0 0)
					(length 5.08)
					(hide yes)
					(name "VCCAUX"
						(effects
							(font
								(size 1.27 1.27)
							)
						)
					)
					(number "V15"
						(effects
							(font
								(size 1.27 1.27)
							)
						)
					)
				)
				(pin passive line
					(at 0 0 0)
					(length 5.08)
					(hide yes)
					(name "VCCAUX"
						(effects
							(font
								(size 1.27 1.27)
							)
						)
					)
					(number "W14"
						(effects
							(font
								(size 1.27 1.27)
							)
						)
					)
				)
				(pin bidirectional line
					(at 0 -2.54 0)
					(length 5.08)
					(name "VCCAUX_IO_G0"
						(effects
							(font
								(size 1.27 1.27)
							)
						)
					)
					(number "V11"
						(effects
							(font
								(size 1.27 1.27)
							)
						)
					)
				)
				(pin passive line
					(at 0 -2.54 0)
					(length 5.08)
					(hide yes)
					(name "VCCAUX_IO_G0"
						(effects
							(font
								(size 1.27 1.27)
							)
						)
					)
					(number "W10"
						(effects
							(font
								(size 1.27 1.27)
							)
						)
					)
				)
				(pin passive line
					(at 0 -2.54 0)
					(length 5.08)
					(hide yes)
					(name "VCCAUX_IO_G0"
						(effects
							(font
								(size 1.27 1.27)
							)
						)
					)
					(number "W12"
						(effects
							(font
								(size 1.27 1.27)
							)
						)
					)
				)
				(pin bidirectional line
					(at 0 -5.08 0)
					(length 5.08)
					(name "VCCADC_0"
						(effects
							(font
								(size 1.27 1.27)
							)
						)
					)
					(number "P15"
						(effects
							(font
								(size 1.27 1.27)
							)
						)
					)
				)
				(pin bidirectional line
					(at 0 -7.62 0)
					(length 5.08)
					(name "VCCBRAM"
						(effects
							(font
								(size 1.27 1.27)
							)
						)
					)
					(number "N16"
						(effects
							(font
								(size 1.27 1.27)
							)
						)
					)
				)
				(pin passive line
					(at 0 -7.62 0)
					(length 5.08)
					(hide yes)
					(name "VCCBRAM"
						(effects
							(font
								(size 1.27 1.27)
							)
						)
					)
					(number "R16"
						(effects
							(font
								(size 1.27 1.27)
							)
						)
					)
				)
				(pin passive line
					(at 0 -7.62 0)
					(length 5.08)
					(hide yes)
					(name "VCCBRAM"
						(effects
							(font
								(size 1.27 1.27)
							)
						)
					)
					(number "U16"
						(effects
							(font
								(size 1.27 1.27)
							)
						)
					)
				)
				(pin passive line
					(at 0 -7.62 0)
					(length 5.08)
					(hide yes)
					(name "VCCBRAM"
						(effects
							(font
								(size 1.27 1.27)
							)
						)
					)
					(number "W16"
						(effects
							(font
								(size 1.27 1.27)
							)
						)
					)
				)
				(pin bidirectional line
					(at 0 -10.16 0)
					(length 5.08)
					(name "VCCINT"
						(effects
							(font
								(size 1.27 1.27)
							)
						)
					)
					(number "M11"
						(effects
							(font
								(size 1.27 1.27)
							)
						)
					)
				)
				(pin passive line
					(at 0 -10.16 0)
					(length 5.08)
					(hide yes)
					(name "VCCINT"
						(effects
							(font
								(size 1.27 1.27)
							)
						)
					)
					(number "M13"
						(effects
							(font
								(size 1.27 1.27)
							)
						)
					)
				)
				(pin passive line
					(at 0 -10.16 0)
					(length 5.08)
					(hide yes)
					(name "VCCINT"
						(effects
							(font
								(size 1.27 1.27)
							)
						)
					)
					(number "M15"
						(effects
							(font
								(size 1.27 1.27)
							)
						)
					)
				)
				(pin passive line
					(at 0 -10.16 0)
					(length 5.08)
					(hide yes)
					(name "VCCINT"
						(effects
							(font
								(size 1.27 1.27)
							)
						)
					)
					(number "M17"
						(effects
							(font
								(size 1.27 1.27)
							)
						)
					)
				)
				(pin passive line
					(at 0 -10.16 0)
					(length 5.08)
					(hide yes)
					(name "VCCINT"
						(effects
							(font
								(size 1.27 1.27)
							)
						)
					)
					(number "N10"
						(effects
							(font
								(size 1.27 1.27)
							)
						)
					)
				)
				(pin passive line
					(at 0 -10.16 0)
					(length 5.08)
					(hide yes)
					(name "VCCINT"
						(effects
							(font
								(size 1.27 1.27)
							)
						)
					)
					(number "N12"
						(effects
							(font
								(size 1.27 1.27)
							)
						)
					)
				)
				(pin passive line
					(at 0 -10.16 0)
					(length 5.08)
					(hide yes)
					(name "VCCINT"
						(effects
							(font
								(size 1.27 1.27)
							)
						)
					)
					(number "N14"
						(effects
							(font
								(size 1.27 1.27)
							)
						)
					)
				)
				(pin passive line
					(at 0 -10.16 0)
					(length 5.08)
					(hide yes)
					(name "VCCINT"
						(effects
							(font
								(size 1.27 1.27)
							)
						)
					)
					(number "N18"
						(effects
							(font
								(size 1.27 1.27)
							)
						)
					)
				)
				(pin passive line
					(at 0 -10.16 0)
					(length 5.08)
					(hide yes)
					(name "VCCINT"
						(effects
							(font
								(size 1.27 1.27)
							)
						)
					)
					(number "P11"
						(effects
							(font
								(size 1.27 1.27)
							)
						)
					)
				)
				(pin passive line
					(at 0 -10.16 0)
					(length 5.08)
					(hide yes)
					(name "VCCINT"
						(effects
							(font
								(size 1.27 1.27)
							)
						)
					)
					(number "P17"
						(effects
							(font
								(size 1.27 1.27)
							)
						)
					)
				)
				(pin passive line
					(at 0 -10.16 0)
					(length 5.08)
					(hide yes)
					(name "VCCINT"
						(effects
							(font
								(size 1.27 1.27)
							)
						)
					)
					(number "R10"
						(effects
							(font
								(size 1.27 1.27)
							)
						)
					)
				)
				(pin passive line
					(at 0 -10.16 0)
					(length 5.08)
					(hide yes)
					(name "VCCINT"
						(effects
							(font
								(size 1.27 1.27)
							)
						)
					)
					(number "R12"
						(effects
							(font
								(size 1.27 1.27)
							)
						)
					)
				)
				(pin passive line
					(at 0 -10.16 0)
					(length 5.08)
					(hide yes)
					(name "VCCINT"
						(effects
							(font
								(size 1.27 1.27)
							)
						)
					)
					(number "R18"
						(effects
							(font
								(size 1.27 1.27)
							)
						)
					)
				)
				(pin passive line
					(at 0 -10.16 0)
					(length 5.08)
					(hide yes)
					(name "VCCINT"
						(effects
							(font
								(size 1.27 1.27)
							)
						)
					)
					(number "T11"
						(effects
							(font
								(size 1.27 1.27)
							)
						)
					)
				)
				(pin passive line
					(at 0 -10.16 0)
					(length 5.08)
					(hide yes)
					(name "VCCINT"
						(effects
							(font
								(size 1.27 1.27)
							)
						)
					)
					(number "T17"
						(effects
							(font
								(size 1.27 1.27)
							)
						)
					)
				)
				(pin passive line
					(at 0 -10.16 0)
					(length 5.08)
					(hide yes)
					(name "VCCINT"
						(effects
							(font
								(size 1.27 1.27)
							)
						)
					)
					(number "U10"
						(effects
							(font
								(size 1.27 1.27)
							)
						)
					)
				)
				(pin passive line
					(at 0 -10.16 0)
					(length 5.08)
					(hide yes)
					(name "VCCINT"
						(effects
							(font
								(size 1.27 1.27)
							)
						)
					)
					(number "U12"
						(effects
							(font
								(size 1.27 1.27)
							)
						)
					)
				)
				(pin passive line
					(at 0 -10.16 0)
					(length 5.08)
					(hide yes)
					(name "VCCINT"
						(effects
							(font
								(size 1.27 1.27)
							)
						)
					)
					(number "U18"
						(effects
							(font
								(size 1.27 1.27)
							)
						)
					)
				)
				(pin passive line
					(at 0 -10.16 0)
					(length 5.08)
					(hide yes)
					(name "VCCINT"
						(effects
							(font
								(size 1.27 1.27)
							)
						)
					)
					(number "V17"
						(effects
							(font
								(size 1.27 1.27)
							)
						)
					)
				)
				(pin passive line
					(at 0 -10.16 0)
					(length 5.08)
					(hide yes)
					(name "VCCINT"
						(effects
							(font
								(size 1.27 1.27)
							)
						)
					)
					(number "W18"
						(effects
							(font
								(size 1.27 1.27)
							)
						)
					)
				)
				(pin bidirectional line
					(at 0 -12.7 0)
					(length 5.08)
					(name "VCCBATT_0"
						(effects
							(font
								(size 1.27 1.27)
							)
						)
					)
					(number "C10"
						(effects
							(font
								(size 1.27 1.27)
							)
						)
					)
				)
				(pin bidirectional line
					(at 0 -16.51 0)
					(length 5.08)
					(name "GNDADC_0"
						(effects
							(font
								(size 1.27 1.27)
							)
						)
					)
					(number "P14"
						(effects
							(font
								(size 1.27 1.27)
							)
						)
					)
				)
				(pin bidirectional line
					(at 0 -19.05 0)
					(length 5.08)
					(name "GND"
						(effects
							(font
								(size 1.27 1.27)
							)
						)
					)
					(number "A1"
						(effects
							(font
								(size 1.27 1.27)
							)
						)
					)
				)
				(pin passive line
					(at 0 -19.05 0)
					(length 5.08)
					(hide yes)
					(name "GND"
						(effects
							(font
								(size 1.27 1.27)
							)
						)
					)
					(number "A14"
						(effects
							(font
								(size 1.27 1.27)
							)
						)
					)
				)
				(pin passive line
					(at 0 -19.05 0)
					(length 5.08)
					(hide yes)
					(name "GND"
						(effects
							(font
								(size 1.27 1.27)
							)
						)
					)
					(number "A2"
						(effects
							(font
								(size 1.27 1.27)
							)
						)
					)
				)
				(pin passive line
					(at 0 -19.05 0)
					(length 5.08)
					(hide yes)
					(name "GND"
						(effects
							(font
								(size 1.27 1.27)
							)
						)
					)
					(number "A24"
						(effects
							(font
								(size 1.27 1.27)
							)
						)
					)
				)
				(pin passive line
					(at 0 -19.05 0)
					(length 5.08)
					(hide yes)
					(name "GND"
						(effects
							(font
								(size 1.27 1.27)
							)
						)
					)
					(number "A5"
						(effects
							(font
								(size 1.27 1.27)
							)
						)
					)
				)
				(pin passive line
					(at 0 -19.05 0)
					(length 5.08)
					(hide yes)
					(name "GND"
						(effects
							(font
								(size 1.27 1.27)
							)
						)
					)
					(number "A6"
						(effects
							(font
								(size 1.27 1.27)
							)
						)
					)
				)
				(pin passive line
					(at 0 -19.05 0)
					(length 5.08)
					(hide yes)
					(name "GND"
						(effects
							(font
								(size 1.27 1.27)
							)
						)
					)
					(number "A9"
						(effects
							(font
								(size 1.27 1.27)
							)
						)
					)
				)
				(pin passive line
					(at 0 -19.05 0)
					(length 5.08)
					(hide yes)
					(name "GND"
						(effects
							(font
								(size 1.27 1.27)
							)
						)
					)
					(number "AA1"
						(effects
							(font
								(size 1.27 1.27)
							)
						)
					)
				)
				(pin passive line
					(at 0 -19.05 0)
					(length 5.08)
					(hide yes)
					(name "GND"
						(effects
							(font
								(size 1.27 1.27)
							)
						)
					)
					(number "AA14"
						(effects
							(font
								(size 1.27 1.27)
							)
						)
					)
				)
				(pin passive line
					(at 0 -19.05 0)
					(length 5.08)
					(hide yes)
					(name "GND"
						(effects
							(font
								(size 1.27 1.27)
							)
						)
					)
					(number "AA2"
						(effects
							(font
								(size 1.27 1.27)
							)
						)
					)
				)
				(pin passive line
					(at 0 -19.05 0)
					(length 5.08)
					(hide yes)
					(name "GND"
						(effects
							(font
								(size 1.27 1.27)
							)
						)
					)
					(number "AA24"
						(effects
							(font
								(size 1.27 1.27)
							)
						)
					)
				)
				(pin passive line
					(at 0 -19.05 0)
					(length 5.08)
					(hide yes)
					(name "GND"
						(effects
							(font
								(size 1.27 1.27)
							)
						)
					)
					(number "AA5"
						(effects
							(font
								(size 1.27 1.27)
							)
						)
					)
				)
				(pin passive line
					(at 0 -19.05 0)
					(length 5.08)
					(hide yes)
					(name "GND"
						(effects
							(font
								(size 1.27 1.27)
							)
						)
					)
					(number "AA6"
						(effects
							(font
								(size 1.27 1.27)
							)
						)
					)
				)
				(pin passive line
					(at 0 -19.05 0)
					(length 5.08)
					(hide yes)
					(name "GND"
						(effects
							(font
								(size 1.27 1.27)
							)
						)
					)
					(number "AA7"
						(effects
							(font
								(size 1.27 1.27)
							)
						)
					)
				)
				(pin passive line
					(at 0 -19.05 0)
					(length 5.08)
					(hide yes)
					(name "GND"
						(effects
							(font
								(size 1.27 1.27)
							)
						)
					)
					(number "AB11"
						(effects
							(font
								(size 1.27 1.27)
							)
						)
					)
				)
				(pin passive line
					(at 0 -19.05 0)
					(length 5.08)
					(hide yes)
					(name "GND"
						(effects
							(font
								(size 1.27 1.27)
							)
						)
					)
					(number "AB21"
						(effects
							(font
								(size 1.27 1.27)
							)
						)
					)
				)
				(pin passive line
					(at 0 -19.05 0)
					(length 5.08)
					(hide yes)
					(name "GND"
						(effects
							(font
								(size 1.27 1.27)
							)
						)
					)
					(number "AB3"
						(effects
							(font
								(size 1.27 1.27)
							)
						)
					)
				)
				(pin passive line
					(at 0 -19.05 0)
					(length 5.08)
					(hide yes)
					(name "GND"
						(effects
							(font
								(size 1.27 1.27)
							)
						)
					)
					(number "AB4"
						(effects
							(font
								(size 1.27 1.27)
							)
						)
					)
				)
				(pin passive line
					(at 0 -19.05 0)
					(length 5.08)
					(hide yes)
					(name "GND"
						(effects
							(font
								(size 1.27 1.27)
							)
						)
					)
					(number "AC18"
						(effects
							(font
								(size 1.27 1.27)
							)
						)
					)
				)
				(pin passive line
					(at 0 -19.05 0)
					(length 5.08)
					(hide yes)
					(name "GND"
						(effects
							(font
								(size 1.27 1.27)
							)
						)
					)
					(number "AC28"
						(effects
							(font
								(size 1.27 1.27)
							)
						)
					)
				)
				(pin passive line
					(at 0 -19.05 0)
					(length 5.08)
					(hide yes)
					(name "GND"
						(effects
							(font
								(size 1.27 1.27)
							)
						)
					)
					(number "AC8"
						(effects
							(font
								(size 1.27 1.27)
							)
						)
					)
				)
				(pin passive line
					(at 0 -19.05 0)
					(length 5.08)
					(hide yes)
					(name "GND"
						(effects
							(font
								(size 1.27 1.27)
							)
						)
					)
					(number "AD15"
						(effects
							(font
								(size 1.27 1.27)
							)
						)
					)
				)
				(pin passive line
					(at 0 -19.05 0)
					(length 5.08)
					(hide yes)
					(name "GND"
						(effects
							(font
								(size 1.27 1.27)
							)
						)
					)
					(number "AD25"
						(effects
							(font
								(size 1.27 1.27)
							)
						)
					)
				)
				(pin passive line
					(at 0 -19.05 0)
					(length 5.08)
					(hide yes)
					(name "GND"
						(effects
							(font
								(size 1.27 1.27)
							)
						)
					)
					(number "AD5"
						(effects
							(font
								(size 1.27 1.27)
							)
						)
					)
				)
				(pin passive line
					(at 0 -19.05 0)
					(length 5.08)
					(hide yes)
					(name "GND"
						(effects
							(font
								(size 1.27 1.27)
							)
						)
					)
					(number "AE12"
						(effects
							(font
								(size 1.27 1.27)
							)
						)
					)
				)
				(pin passive line
					(at 0 -19.05 0)
					(length 5.08)
					(hide yes)
					(name "GND"
						(effects
							(font
								(size 1.27 1.27)
							)
						)
					)
					(number "AE2"
						(effects
							(font
								(size 1.27 1.27)
							)
						)
					)
				)
				(pin passive line
					(at 0 -19.05 0)
					(length 5.08)
					(hide yes)
					(name "GND"
						(effects
							(font
								(size 1.27 1.27)
							)
						)
					)
					(number "AE22"
						(effects
							(font
								(size 1.27 1.27)
							)
						)
					)
				)
				(pin passive line
					(at 0 -19.05 0)
					(length 5.08)
					(hide yes)
					(name "GND"
						(effects
							(font
								(size 1.27 1.27)
							)
						)
					)
					(number "AF19"
						(effects
							(font
								(size 1.27 1.27)
							)
						)
					)
				)
				(pin passive line
					(at 0 -19.05 0)
					(length 5.08)
					(hide yes)
					(name "GND"
						(effects
							(font
								(size 1.27 1.27)
							)
						)
					)
					(number "AF29"
						(effects
							(font
								(size 1.27 1.27)
							)
						)
					)
				)
				(pin passive line
					(at 0 -19.05 0)
					(length 5.08)
					(hide yes)
					(name "GND"
						(effects
							(font
								(size 1.27 1.27)
							)
						)
					)
					(number "AF9"
						(effects
							(font
								(size 1.27 1.27)
							)
						)
					)
				)
				(pin passive line
					(at 0 -19.05 0)
					(length 5.08)
					(hide yes)
					(name "GND"
						(effects
							(font
								(size 1.27 1.27)
							)
						)
					)
					(number "AG16"
						(effects
							(font
								(size 1.27 1.27)
							)
						)
					)
				)
				(pin passive line
					(at 0 -19.05 0)
					(length 5.08)
					(hide yes)
					(name "GND"
						(effects
							(font
								(size 1.27 1.27)
							)
						)
					)
					(number "AG26"
						(effects
							(font
								(size 1.27 1.27)
							)
						)
					)
				)
				(pin passive line
					(at 0 -19.05 0)
					(length 5.08)
					(hide yes)
					(name "GND"
						(effects
							(font
								(size 1.27 1.27)
							)
						)
					)
					(number "AG6"
						(effects
							(font
								(size 1.27 1.27)
							)
						)
					)
				)
				(pin passive line
					(at 0 -19.05 0)
					(length 5.08)
					(hide yes)
					(name "GND"
						(effects
							(font
								(size 1.27 1.27)
							)
						)
					)
					(number "AH13"
						(effects
							(font
								(size 1.27 1.27)
							)
						)
					)
				)
				(pin passive line
					(at 0 -19.05 0)
					(length 5.08)
					(hide yes)
					(name "GND"
						(effects
							(font
								(size 1.27 1.27)
							)
						)
					)
					(number "AH23"
						(effects
							(font
								(size 1.27 1.27)
							)
						)
					)
				)
				(pin passive line
					(at 0 -19.05 0)
					(length 5.08)
					(hide yes)
					(name "GND"
						(effects
							(font
								(size 1.27 1.27)
							)
						)
					)
					(number "AH3"
						(effects
							(font
								(size 1.27 1.27)
							)
						)
					)
				)
				(pin passive line
					(at 0 -19.05 0)
					(length 5.08)
					(hide yes)
					(name "GND"
						(effects
							(font
								(size 1.27 1.27)
							)
						)
					)
					(number "AJ10"
						(effects
							(font
								(size 1.27 1.27)
							)
						)
					)
				)
				(pin passive line
					(at 0 -19.05 0)
					(length 5.08)
					(hide yes)
					(name "GND"
						(effects
							(font
								(size 1.27 1.27)
							)
						)
					)
					(number "AJ20"
						(effects
							(font
								(size 1.27 1.27)
							)
						)
					)
				)
				(pin passive line
					(at 0 -19.05 0)
					(length 5.08)
					(hide yes)
					(name "GND"
						(effects
							(font
								(size 1.27 1.27)
							)
						)
					)
					(number "AJ30"
						(effects
							(font
								(size 1.27 1.27)
							)
						)
					)
				)
				(pin passive line
					(at 0 -19.05 0)
					(length 5.08)
					(hide yes)
					(name "GND"
						(effects
							(font
								(size 1.27 1.27)
							)
						)
					)
					(number "AK17"
						(effects
							(font
								(size 1.27 1.27)
							)
						)
					)
				)
				(pin passive line
					(at 0 -19.05 0)
					(length 5.08)
					(hide yes)
					(name "GND"
						(effects
							(font
								(size 1.27 1.27)
							)
						)
					)
					(number "AK27"
						(effects
							(font
								(size 1.27 1.27)
							)
						)
					)
				)
				(pin passive line
					(at 0 -19.05 0)
					(length 5.08)
					(hide yes)
					(name "GND"
						(effects
							(font
								(size 1.27 1.27)
							)
						)
					)
					(number "AK7"
						(effects
							(font
								(size 1.27 1.27)
							)
						)
					)
				)
				(pin passive line
					(at 0 -19.05 0)
					(length 5.08)
					(hide yes)
					(name "GND"
						(effects
							(font
								(size 1.27 1.27)
							)
						)
					)
					(number "B11"
						(effects
							(font
								(size 1.27 1.27)
							)
						)
					)
				)
				(pin passive line
					(at 0 -19.05 0)
					(length 5.08)
					(hide yes)
					(name "GND"
						(effects
							(font
								(size 1.27 1.27)
							)
						)
					)
					(number "B21"
						(effects
							(font
								(size 1.27 1.27)
							)
						)
					)
				)
				(pin passive line
					(at 0 -19.05 0)
					(length 5.08)
					(hide yes)
					(name "GND"
						(effects
							(font
								(size 1.27 1.27)
							)
						)
					)
					(number "B4"
						(effects
							(font
								(size 1.27 1.27)
							)
						)
					)
				)
				(pin passive line
					(at 0 -19.05 0)
					(length 5.08)
					(hide yes)
					(name "GND"
						(effects
							(font
								(size 1.27 1.27)
							)
						)
					)
					(number "B8"
						(effects
							(font
								(size 1.27 1.27)
							)
						)
					)
				)
				(pin passive line
					(at 0 -19.05 0)
					(length 5.08)
					(hide yes)
					(name "GND"
						(effects
							(font
								(size 1.27 1.27)
							)
						)
					)
					(number "B9"
						(effects
							(font
								(size 1.27 1.27)
							)
						)
					)
				)
				(pin passive line
					(at 0 -19.05 0)
					(length 5.08)
					(hide yes)
					(name "GND"
						(effects
							(font
								(size 1.27 1.27)
							)
						)
					)
					(number "C1"
						(effects
							(font
								(size 1.27 1.27)
							)
						)
					)
				)
				(pin passive line
					(at 0 -19.05 0)
					(length 5.08)
					(hide yes)
					(name "GND"
						(effects
							(font
								(size 1.27 1.27)
							)
						)
					)
					(number "C18"
						(effects
							(font
								(size 1.27 1.27)
							)
						)
					)
				)
				(pin passive line
					(at 0 -19.05 0)
					(length 5.08)
					(hide yes)
					(name "GND"
						(effects
							(font
								(size 1.27 1.27)
							)
						)
					)
					(number "C2"
						(effects
							(font
								(size 1.27 1.27)
							)
						)
					)
				)
				(pin passive line
					(at 0 -19.05 0)
					(length 5.08)
					(hide yes)
					(name "GND"
						(effects
							(font
								(size 1.27 1.27)
							)
						)
					)
					(number "C28"
						(effects
							(font
								(size 1.27 1.27)
							)
						)
					)
				)
				(pin passive line
					(at 0 -19.05 0)
					(length 5.08)
					(hide yes)
					(name "GND"
						(effects
							(font
								(size 1.27 1.27)
							)
						)
					)
					(number "C6"
						(effects
							(font
								(size 1.27 1.27)
							)
						)
					)
				)
				(pin passive line
					(at 0 -19.05 0)
					(length 5.08)
					(hide yes)
					(name "GND"
						(effects
							(font
								(size 1.27 1.27)
							)
						)
					)
					(number "C9"
						(effects
							(font
								(size 1.27 1.27)
							)
						)
					)
				)
				(pin passive line
					(at 0 -19.05 0)
					(length 5.08)
					(hide yes)
					(name "GND"
						(effects
							(font
								(size 1.27 1.27)
							)
						)
					)
					(number "D15"
						(effects
							(font
								(size 1.27 1.27)
							)
						)
					)
				)
				(pin passive line
					(at 0 -19.05 0)
					(length 5.08)
					(hide yes)
					(name "GND"
						(effects
							(font
								(size 1.27 1.27)
							)
						)
					)
					(number "D25"
						(effects
							(font
								(size 1.27 1.27)
							)
						)
					)
				)
				(pin passive line
					(at 0 -19.05 0)
					(length 5.08)
					(hide yes)
					(name "GND"
						(effects
							(font
								(size 1.27 1.27)
							)
						)
					)
					(number "D4"
						(effects
							(font
								(size 1.27 1.27)
							)
						)
					)
				)
				(pin passive line
					(at 0 -19.05 0)
					(length 5.08)
					(hide yes)
					(name "GND"
						(effects
							(font
								(size 1.27 1.27)
							)
						)
					)
					(number "D8"
						(effects
							(font
								(size 1.27 1.27)
							)
						)
					)
				)
				(pin passive line
					(at 0 -19.05 0)
					(length 5.08)
					(hide yes)
					(name "GND"
						(effects
							(font
								(size 1.27 1.27)
							)
						)
					)
					(number "D9"
						(effects
							(font
								(size 1.27 1.27)
							)
						)
					)
				)
				(pin passive line
					(at 0 -19.05 0)
					(length 5.08)
					(hide yes)
					(name "GND"
						(effects
							(font
								(size 1.27 1.27)
							)
						)
					)
					(number "E1"
						(effects
							(font
								(size 1.27 1.27)
							)
						)
					)
				)
				(pin passive line
					(at 0 -19.05 0)
					(length 5.08)
					(hide yes)
					(name "GND"
						(effects
							(font
								(size 1.27 1.27)
							)
						)
					)
					(number "E12"
						(effects
							(font
								(size 1.27 1.27)
							)
						)
					)
				)
				(pin passive line
					(at 0 -19.05 0)
					(length 5.08)
					(hide yes)
					(name "GND"
						(effects
							(font
								(size 1.27 1.27)
							)
						)
					)
					(number "E2"
						(effects
							(font
								(size 1.27 1.27)
							)
						)
					)
				)
				(pin passive line
					(at 0 -19.05 0)
					(length 5.08)
					(hide yes)
					(name "GND"
						(effects
							(font
								(size 1.27 1.27)
							)
						)
					)
					(number "E22"
						(effects
							(font
								(size 1.27 1.27)
							)
						)
					)
				)
				(pin passive line
					(at 0 -19.05 0)
					(length 5.08)
					(hide yes)
					(name "GND"
						(effects
							(font
								(size 1.27 1.27)
							)
						)
					)
					(number "E6"
						(effects
							(font
								(size 1.27 1.27)
							)
						)
					)
				)
				(pin passive line
					(at 0 -19.05 0)
					(length 5.08)
					(hide yes)
					(name "GND"
						(effects
							(font
								(size 1.27 1.27)
							)
						)
					)
					(number "E9"
						(effects
							(font
								(size 1.27 1.27)
							)
						)
					)
				)
				(pin passive line
					(at 0 -19.05 0)
					(length 5.08)
					(hide yes)
					(name "GND"
						(effects
							(font
								(size 1.27 1.27)
							)
						)
					)
					(number "F19"
						(effects
							(font
								(size 1.27 1.27)
							)
						)
					)
				)
				(pin passive line
					(at 0 -19.05 0)
					(length 5.08)
					(hide yes)
					(name "GND"
						(effects
							(font
								(size 1.27 1.27)
							)
						)
					)
					(number "F29"
						(effects
							(font
								(size 1.27 1.27)
							)
						)
					)
				)
				(pin passive line
					(at 0 -19.05 0)
					(length 5.08)
					(hide yes)
					(name "GND"
						(effects
							(font
								(size 1.27 1.27)
							)
						)
					)
					(number "F4"
						(effects
							(font
								(size 1.27 1.27)
							)
						)
					)
				)
				(pin passive line
					(at 0 -19.05 0)
					(length 5.08)
					(hide yes)
					(name "GND"
						(effects
							(font
								(size 1.27 1.27)
							)
						)
					)
					(number "F8"
						(effects
							(font
								(size 1.27 1.27)
							)
						)
					)
				)
				(pin passive line
					(at 0 -19.05 0)
					(length 5.08)
					(hide yes)
					(name "GND"
						(effects
							(font
								(size 1.27 1.27)
							)
						)
					)
					(number "F9"
						(effects
							(font
								(size 1.27 1.27)
							)
						)
					)
				)
				(pin passive line
					(at 0 -19.05 0)
					(length 5.08)
					(hide yes)
					(name "GND"
						(effects
							(font
								(size 1.27 1.27)
							)
						)
					)
					(number "G1"
						(effects
							(font
								(size 1.27 1.27)
							)
						)
					)
				)
				(pin passive line
					(at 0 -19.05 0)
					(length 5.08)
					(hide yes)
					(name "GND"
						(effects
							(font
								(size 1.27 1.27)
							)
						)
					)
					(number "G16"
						(effects
							(font
								(size 1.27 1.27)
							)
						)
					)
				)
				(pin passive line
					(at 0 -19.05 0)
					(length 5.08)
					(hide yes)
					(name "GND"
						(effects
							(font
								(size 1.27 1.27)
							)
						)
					)
					(number "G2"
						(effects
							(font
								(size 1.27 1.27)
							)
						)
					)
				)
				(pin passive line
					(at 0 -19.05 0)
					(length 5.08)
					(hide yes)
					(name "GND"
						(effects
							(font
								(size 1.27 1.27)
							)
						)
					)
					(number "G26"
						(effects
							(font
								(size 1.27 1.27)
							)
						)
					)
				)
				(pin passive line
					(at 0 -19.05 0)
					(length 5.08)
					(hide yes)
					(name "GND"
						(effects
							(font
								(size 1.27 1.27)
							)
						)
					)
					(number "G6"
						(effects
							(font
								(size 1.27 1.27)
							)
						)
					)
				)
				(pin passive line
					(at 0 -19.05 0)
					(length 5.08)
					(hide yes)
					(name "GND"
						(effects
							(font
								(size 1.27 1.27)
							)
						)
					)
					(number "G9"
						(effects
							(font
								(size 1.27 1.27)
							)
						)
					)
				)
				(pin passive line
					(at 0 -19.05 0)
					(length 5.08)
					(hide yes)
					(name "GND"
						(effects
							(font
								(size 1.27 1.27)
							)
						)
					)
					(number "H13"
						(effects
							(font
								(size 1.27 1.27)
							)
						)
					)
				)
				(pin passive line
					(at 0 -19.05 0)
					(length 5.08)
					(hide yes)
					(name "GND"
						(effects
							(font
								(size 1.27 1.27)
							)
						)
					)
					(number "H23"
						(effects
							(font
								(size 1.27 1.27)
							)
						)
					)
				)
				(pin passive line
					(at 0 -19.05 0)
					(length 5.08)
					(hide yes)
					(name "GND"
						(effects
							(font
								(size 1.27 1.27)
							)
						)
					)
					(number "H4"
						(effects
							(font
								(size 1.27 1.27)
							)
						)
					)
				)
				(pin passive line
					(at 0 -19.05 0)
					(length 5.08)
					(hide yes)
					(name "GND"
						(effects
							(font
								(size 1.27 1.27)
							)
						)
					)
					(number "H8"
						(effects
							(font
								(size 1.27 1.27)
							)
						)
					)
				)
				(pin passive line
					(at 0 -19.05 0)
					(length 5.08)
					(hide yes)
					(name "GND"
						(effects
							(font
								(size 1.27 1.27)
							)
						)
					)
					(number "H9"
						(effects
							(font
								(size 1.27 1.27)
							)
						)
					)
				)
				(pin passive line
					(at 0 -19.05 0)
					(length 5.08)
					(hide yes)
					(name "GND"
						(effects
							(font
								(size 1.27 1.27)
							)
						)
					)
					(number "J1"
						(effects
							(font
								(size 1.27 1.27)
							)
						)
					)
				)
				(pin passive line
					(at 0 -19.05 0)
					(length 5.08)
					(hide yes)
					(name "GND"
						(effects
							(font
								(size 1.27 1.27)
							)
						)
					)
					(number "J10"
						(effects
							(font
								(size 1.27 1.27)
							)
						)
					)
				)
				(pin passive line
					(at 0 -19.05 0)
					(length 5.08)
					(hide yes)
					(name "GND"
						(effects
							(font
								(size 1.27 1.27)
							)
						)
					)
					(number "J2"
						(effects
							(font
								(size 1.27 1.27)
							)
						)
					)
				)
				(pin passive line
					(at 0 -19.05 0)
					(length 5.08)
					(hide yes)
					(name "GND"
						(effects
							(font
								(size 1.27 1.27)
							)
						)
					)
					(number "J20"
						(effects
							(font
								(size 1.27 1.27)
							)
						)
					)
				)
				(pin passive line
					(at 0 -19.05 0)
					(length 5.08)
					(hide yes)
					(name "GND"
						(effects
							(font
								(size 1.27 1.27)
							)
						)
					)
					(number "J30"
						(effects
							(font
								(size 1.27 1.27)
							)
						)
					)
				)
				(pin passive line
					(at 0 -19.05 0)
					(length 5.08)
					(hide yes)
					(name "GND"
						(effects
							(font
								(size 1.27 1.27)
							)
						)
					)
					(number "J6"
						(effects
							(font
								(size 1.27 1.27)
							)
						)
					)
				)
				(pin passive line
					(at 0 -19.05 0)
					(length 5.08)
					(hide yes)
					(name "GND"
						(effects
							(font
								(size 1.27 1.27)
							)
						)
					)
					(number "J9"
						(effects
							(font
								(size 1.27 1.27)
							)
						)
					)
				)
				(pin passive line
					(at 0 -19.05 0)
					(length 5.08)
					(hide yes)
					(name "GND"
						(effects
							(font
								(size 1.27 1.27)
							)
						)
					)
					(number "K17"
						(effects
							(font
								(size 1.27 1.27)
							)
						)
					)
				)
				(pin passive line
					(at 0 -19.05 0)
					(length 5.08)
					(hide yes)
					(name "GND"
						(effects
							(font
								(size 1.27 1.27)
							)
						)
					)
					(number "K27"
						(effects
							(font
								(size 1.27 1.27)
							)
						)
					)
				)
				(pin passive line
					(at 0 -19.05 0)
					(length 5.08)
					(hide yes)
					(name "GND"
						(effects
							(font
								(size 1.27 1.27)
							)
						)
					)
					(number "K4"
						(effects
							(font
								(size 1.27 1.27)
							)
						)
					)
				)
				(pin passive line
					(at 0 -19.05 0)
					(length 5.08)
					(hide yes)
					(name "GND"
						(effects
							(font
								(size 1.27 1.27)
							)
						)
					)
					(number "K8"
						(effects
							(font
								(size 1.27 1.27)
							)
						)
					)
				)
				(pin passive line
					(at 0 -19.05 0)
					(length 5.08)
					(hide yes)
					(name "GND"
						(effects
							(font
								(size 1.27 1.27)
							)
						)
					)
					(number "K9"
						(effects
							(font
								(size 1.27 1.27)
							)
						)
					)
				)
				(pin passive line
					(at 0 -19.05 0)
					(length 5.08)
					(hide yes)
					(name "GND"
						(effects
							(font
								(size 1.27 1.27)
							)
						)
					)
					(number "L1"
						(effects
							(font
								(size 1.27 1.27)
							)
						)
					)
				)
				(pin passive line
					(at 0 -19.05 0)
					(length 5.08)
					(hide yes)
					(name "GND"
						(effects
							(font
								(size 1.27 1.27)
							)
						)
					)
					(number "L14"
						(effects
							(font
								(size 1.27 1.27)
							)
						)
					)
				)
				(pin passive line
					(at 0 -19.05 0)
					(length 5.08)
					(hide yes)
					(name "GND"
						(effects
							(font
								(size 1.27 1.27)
							)
						)
					)
					(number "L2"
						(effects
							(font
								(size 1.27 1.27)
							)
						)
					)
				)
				(pin passive line
					(at 0 -19.05 0)
					(length 5.08)
					(hide yes)
					(name "GND"
						(effects
							(font
								(size 1.27 1.27)
							)
						)
					)
					(number "L24"
						(effects
							(font
								(size 1.27 1.27)
							)
						)
					)
				)
				(pin passive line
					(at 0 -19.05 0)
					(length 5.08)
					(hide yes)
					(name "GND"
						(effects
							(font
								(size 1.27 1.27)
							)
						)
					)
					(number "L6"
						(effects
							(font
								(size 1.27 1.27)
							)
						)
					)
				)
				(pin passive line
					(at 0 -19.05 0)
					(length 5.08)
					(hide yes)
					(name "GND"
						(effects
							(font
								(size 1.27 1.27)
							)
						)
					)
					(number "L9"
						(effects
							(font
								(size 1.27 1.27)
							)
						)
					)
				)
				(pin passive line
					(at 0 -19.05 0)
					(length 5.08)
					(hide yes)
					(name "GND"
						(effects
							(font
								(size 1.27 1.27)
							)
						)
					)
					(number "M12"
						(effects
							(font
								(size 1.27 1.27)
							)
						)
					)
				)
				(pin passive line
					(at 0 -19.05 0)
					(length 5.08)
					(hide yes)
					(name "GND"
						(effects
							(font
								(size 1.27 1.27)
							)
						)
					)
					(number "M14"
						(effects
							(font
								(size 1.27 1.27)
							)
						)
					)
				)
				(pin passive line
					(at 0 -19.05 0)
					(length 5.08)
					(hide yes)
					(name "GND"
						(effects
							(font
								(size 1.27 1.27)
							)
						)
					)
					(number "M16"
						(effects
							(font
								(size 1.27 1.27)
							)
						)
					)
				)
				(pin passive line
					(at 0 -19.05 0)
					(length 5.08)
					(hide yes)
					(name "GND"
						(effects
							(font
								(size 1.27 1.27)
							)
						)
					)
					(number "M18"
						(effects
							(font
								(size 1.27 1.27)
							)
						)
					)
				)
				(pin passive line
					(at 0 -19.05 0)
					(length 5.08)
					(hide yes)
					(name "GND"
						(effects
							(font
								(size 1.27 1.27)
							)
						)
					)
					(number "M21"
						(effects
							(font
								(size 1.27 1.27)
							)
						)
					)
				)
				(pin passive line
					(at 0 -19.05 0)
					(length 5.08)
					(hide yes)
					(name "GND"
						(effects
							(font
								(size 1.27 1.27)
							)
						)
					)
					(number "M4"
						(effects
							(font
								(size 1.27 1.27)
							)
						)
					)
				)
				(pin passive line
					(at 0 -19.05 0)
					(length 5.08)
					(hide yes)
					(name "GND"
						(effects
							(font
								(size 1.27 1.27)
							)
						)
					)
					(number "M8"
						(effects
							(font
								(size 1.27 1.27)
							)
						)
					)
				)
				(pin passive line
					(at 0 -19.05 0)
					(length 5.08)
					(hide yes)
					(name "GND"
						(effects
							(font
								(size 1.27 1.27)
							)
						)
					)
					(number "M9"
						(effects
							(font
								(size 1.27 1.27)
							)
						)
					)
				)
				(pin passive line
					(at 0 -19.05 0)
					(length 5.08)
					(hide yes)
					(name "GND"
						(effects
							(font
								(size 1.27 1.27)
							)
						)
					)
					(number "N1"
						(effects
							(font
								(size 1.27 1.27)
							)
						)
					)
				)
				(pin passive line
					(at 0 -19.05 0)
					(length 5.08)
					(hide yes)
					(name "GND"
						(effects
							(font
								(size 1.27 1.27)
							)
						)
					)
					(number "N11"
						(effects
							(font
								(size 1.27 1.27)
							)
						)
					)
				)
				(pin passive line
					(at 0 -19.05 0)
					(length 5.08)
					(hide yes)
					(name "GND"
						(effects
							(font
								(size 1.27 1.27)
							)
						)
					)
					(number "N13"
						(effects
							(font
								(size 1.27 1.27)
							)
						)
					)
				)
				(pin passive line
					(at 0 -19.05 0)
					(length 5.08)
					(hide yes)
					(name "GND"
						(effects
							(font
								(size 1.27 1.27)
							)
						)
					)
					(number "N15"
						(effects
							(font
								(size 1.27 1.27)
							)
						)
					)
				)
				(pin passive line
					(at 0 -19.05 0)
					(length 5.08)
					(hide yes)
					(name "GND"
						(effects
							(font
								(size 1.27 1.27)
							)
						)
					)
					(number "N17"
						(effects
							(font
								(size 1.27 1.27)
							)
						)
					)
				)
				(pin passive line
					(at 0 -19.05 0)
					(length 5.08)
					(hide yes)
					(name "GND"
						(effects
							(font
								(size 1.27 1.27)
							)
						)
					)
					(number "N2"
						(effects
							(font
								(size 1.27 1.27)
							)
						)
					)
				)
				(pin passive line
					(at 0 -19.05 0)
					(length 5.08)
					(hide yes)
					(name "GND"
						(effects
							(font
								(size 1.27 1.27)
							)
						)
					)
					(number "N28"
						(effects
							(font
								(size 1.27 1.27)
							)
						)
					)
				)
				(pin passive line
					(at 0 -19.05 0)
					(length 5.08)
					(hide yes)
					(name "GND"
						(effects
							(font
								(size 1.27 1.27)
							)
						)
					)
					(number "N6"
						(effects
							(font
								(size 1.27 1.27)
							)
						)
					)
				)
				(pin passive line
					(at 0 -19.05 0)
					(length 5.08)
					(hide yes)
					(name "GND"
						(effects
							(font
								(size 1.27 1.27)
							)
						)
					)
					(number "N9"
						(effects
							(font
								(size 1.27 1.27)
							)
						)
					)
				)
				(pin passive line
					(at 0 -19.05 0)
					(length 5.08)
					(hide yes)
					(name "GND"
						(effects
							(font
								(size 1.27 1.27)
							)
						)
					)
					(number "P10"
						(effects
							(font
								(size 1.27 1.27)
							)
						)
					)
				)
				(pin passive line
					(at 0 -19.05 0)
					(length 5.08)
					(hide yes)
					(name "GND"
						(effects
							(font
								(size 1.27 1.27)
							)
						)
					)
					(number "P12"
						(effects
							(font
								(size 1.27 1.27)
							)
						)
					)
				)
				(pin passive line
					(at 0 -19.05 0)
					(length 5.08)
					(hide yes)
					(name "GND"
						(effects
							(font
								(size 1.27 1.27)
							)
						)
					)
					(number "P16"
						(effects
							(font
								(size 1.27 1.27)
							)
						)
					)
				)
				(pin passive line
					(at 0 -19.05 0)
					(length 5.08)
					(hide yes)
					(name "GND"
						(effects
							(font
								(size 1.27 1.27)
							)
						)
					)
					(number "P18"
						(effects
							(font
								(size 1.27 1.27)
							)
						)
					)
				)
				(pin passive line
					(at 0 -19.05 0)
					(length 5.08)
					(hide yes)
					(name "GND"
						(effects
							(font
								(size 1.27 1.27)
							)
						)
					)
					(number "P25"
						(effects
							(font
								(size 1.27 1.27)
							)
						)
					)
				)
				(pin passive line
					(at 0 -19.05 0)
					(length 5.08)
					(hide yes)
					(name "GND"
						(effects
							(font
								(size 1.27 1.27)
							)
						)
					)
					(number "P4"
						(effects
							(font
								(size 1.27 1.27)
							)
						)
					)
				)
				(pin passive line
					(at 0 -19.05 0)
					(length 5.08)
					(hide yes)
					(name "GND"
						(effects
							(font
								(size 1.27 1.27)
							)
						)
					)
					(number "P8"
						(effects
							(font
								(size 1.27 1.27)
							)
						)
					)
				)
				(pin passive line
					(at 0 -19.05 0)
					(length 5.08)
					(hide yes)
					(name "GND"
						(effects
							(font
								(size 1.27 1.27)
							)
						)
					)
					(number "P9"
						(effects
							(font
								(size 1.27 1.27)
							)
						)
					)
				)
				(pin passive line
					(at 0 -19.05 0)
					(length 5.08)
					(hide yes)
					(name "GND"
						(effects
							(font
								(size 1.27 1.27)
							)
						)
					)
					(number "R1"
						(effects
							(font
								(size 1.27 1.27)
							)
						)
					)
				)
				(pin passive line
					(at 0 -19.05 0)
					(length 5.08)
					(hide yes)
					(name "GND"
						(effects
							(font
								(size 1.27 1.27)
							)
						)
					)
					(number "R11"
						(effects
							(font
								(size 1.27 1.27)
							)
						)
					)
				)
				(pin passive line
					(at 0 -19.05 0)
					(length 5.08)
					(hide yes)
					(name "GND"
						(effects
							(font
								(size 1.27 1.27)
							)
						)
					)
					(number "R13"
						(effects
							(font
								(size 1.27 1.27)
							)
						)
					)
				)
				(pin passive line
					(at 0 -19.05 0)
					(length 5.08)
					(hide yes)
					(name "GND"
						(effects
							(font
								(size 1.27 1.27)
							)
						)
					)
					(number "R17"
						(effects
							(font
								(size 1.27 1.27)
							)
						)
					)
				)
				(pin passive line
					(at 0 -19.05 0)
					(length 5.08)
					(hide yes)
					(name "GND"
						(effects
							(font
								(size 1.27 1.27)
							)
						)
					)
					(number "R2"
						(effects
							(font
								(size 1.27 1.27)
							)
						)
					)
				)
				(pin passive line
					(at 0 -19.05 0)
					(length 5.08)
					(hide yes)
					(name "GND"
						(effects
							(font
								(size 1.27 1.27)
							)
						)
					)
					(number "R22"
						(effects
							(font
								(size 1.27 1.27)
							)
						)
					)
				)
				(pin passive line
					(at 0 -19.05 0)
					(length 5.08)
					(hide yes)
					(name "GND"
						(effects
							(font
								(size 1.27 1.27)
							)
						)
					)
					(number "R6"
						(effects
							(font
								(size 1.27 1.27)
							)
						)
					)
				)
				(pin passive line
					(at 0 -19.05 0)
					(length 5.08)
					(hide yes)
					(name "GND"
						(effects
							(font
								(size 1.27 1.27)
							)
						)
					)
					(number "R9"
						(effects
							(font
								(size 1.27 1.27)
							)
						)
					)
				)
				(pin passive line
					(at 0 -19.05 0)
					(length 5.08)
					(hide yes)
					(name "GND"
						(effects
							(font
								(size 1.27 1.27)
							)
						)
					)
					(number "T10"
						(effects
							(font
								(size 1.27 1.27)
							)
						)
					)
				)
				(pin passive line
					(at 0 -19.05 0)
					(length 5.08)
					(hide yes)
					(name "GND"
						(effects
							(font
								(size 1.27 1.27)
							)
						)
					)
					(number "T12"
						(effects
							(font
								(size 1.27 1.27)
							)
						)
					)
				)
				(pin passive line
					(at 0 -19.05 0)
					(length 5.08)
					(hide yes)
					(name "GND"
						(effects
							(font
								(size 1.27 1.27)
							)
						)
					)
					(number "T16"
						(effects
							(font
								(size 1.27 1.27)
							)
						)
					)
				)
				(pin passive line
					(at 0 -19.05 0)
					(length 5.08)
					(hide yes)
					(name "GND"
						(effects
							(font
								(size 1.27 1.27)
							)
						)
					)
					(number "T18"
						(effects
							(font
								(size 1.27 1.27)
							)
						)
					)
				)
				(pin passive line
					(at 0 -19.05 0)
					(length 5.08)
					(hide yes)
					(name "GND"
						(effects
							(font
								(size 1.27 1.27)
							)
						)
					)
					(number "T19"
						(effects
							(font
								(size 1.27 1.27)
							)
						)
					)
				)
				(pin passive line
					(at 0 -19.05 0)
					(length 5.08)
					(hide yes)
					(name "GND"
						(effects
							(font
								(size 1.27 1.27)
							)
						)
					)
					(number "T29"
						(effects
							(font
								(size 1.27 1.27)
							)
						)
					)
				)
				(pin passive line
					(at 0 -19.05 0)
					(length 5.08)
					(hide yes)
					(name "GND"
						(effects
							(font
								(size 1.27 1.27)
							)
						)
					)
					(number "T4"
						(effects
							(font
								(size 1.27 1.27)
							)
						)
					)
				)
				(pin passive line
					(at 0 -19.05 0)
					(length 5.08)
					(hide yes)
					(name "GND"
						(effects
							(font
								(size 1.27 1.27)
							)
						)
					)
					(number "T8"
						(effects
							(font
								(size 1.27 1.27)
							)
						)
					)
				)
				(pin passive line
					(at 0 -19.05 0)
					(length 5.08)
					(hide yes)
					(name "GND"
						(effects
							(font
								(size 1.27 1.27)
							)
						)
					)
					(number "U1"
						(effects
							(font
								(size 1.27 1.27)
							)
						)
					)
				)
				(pin passive line
					(at 0 -19.05 0)
					(length 5.08)
					(hide yes)
					(name "GND"
						(effects
							(font
								(size 1.27 1.27)
							)
						)
					)
					(number "U11"
						(effects
							(font
								(size 1.27 1.27)
							)
						)
					)
				)
				(pin passive line
					(at 0 -19.05 0)
					(length 5.08)
					(hide yes)
					(name "GND"
						(effects
							(font
								(size 1.27 1.27)
							)
						)
					)
					(number "U13"
						(effects
							(font
								(size 1.27 1.27)
							)
						)
					)
				)
				(pin passive line
					(at 0 -19.05 0)
					(length 5.08)
					(hide yes)
					(name "GND"
						(effects
							(font
								(size 1.27 1.27)
							)
						)
					)
					(number "U17"
						(effects
							(font
								(size 1.27 1.27)
							)
						)
					)
				)
				(pin passive line
					(at 0 -19.05 0)
					(length 5.08)
					(hide yes)
					(name "GND"
						(effects
							(font
								(size 1.27 1.27)
							)
						)
					)
					(number "U2"
						(effects
							(font
								(size 1.27 1.27)
							)
						)
					)
				)
				(pin passive line
					(at 0 -19.05 0)
					(length 5.08)
					(hide yes)
					(name "GND"
						(effects
							(font
								(size 1.27 1.27)
							)
						)
					)
					(number "U26"
						(effects
							(font
								(size 1.27 1.27)
							)
						)
					)
				)
				(pin passive line
					(at 0 -19.05 0)
					(length 5.08)
					(hide yes)
					(name "GND"
						(effects
							(font
								(size 1.27 1.27)
							)
						)
					)
					(number "U6"
						(effects
							(font
								(size 1.27 1.27)
							)
						)
					)
				)
				(pin passive line
					(at 0 -19.05 0)
					(length 5.08)
					(hide yes)
					(name "GND"
						(effects
							(font
								(size 1.27 1.27)
							)
						)
					)
					(number "U9"
						(effects
							(font
								(size 1.27 1.27)
							)
						)
					)
				)
				(pin passive line
					(at 0 -19.05 0)
					(length 5.08)
					(hide yes)
					(name "GND"
						(effects
							(font
								(size 1.27 1.27)
							)
						)
					)
					(number "V10"
						(effects
							(font
								(size 1.27 1.27)
							)
						)
					)
				)
				(pin passive line
					(at 0 -19.05 0)
					(length 5.08)
					(hide yes)
					(name "GND"
						(effects
							(font
								(size 1.27 1.27)
							)
						)
					)
					(number "V12"
						(effects
							(font
								(size 1.27 1.27)
							)
						)
					)
				)
				(pin passive line
					(at 0 -19.05 0)
					(length 5.08)
					(hide yes)
					(name "GND"
						(effects
							(font
								(size 1.27 1.27)
							)
						)
					)
					(number "V14"
						(effects
							(font
								(size 1.27 1.27)
							)
						)
					)
				)
				(pin passive line
					(at 0 -19.05 0)
					(length 5.08)
					(hide yes)
					(name "GND"
						(effects
							(font
								(size 1.27 1.27)
							)
						)
					)
					(number "V16"
						(effects
							(font
								(size 1.27 1.27)
							)
						)
					)
				)
				(pin passive line
					(at 0 -19.05 0)
					(length 5.08)
					(hide yes)
					(name "GND"
						(effects
							(font
								(size 1.27 1.27)
							)
						)
					)
					(number "V18"
						(effects
							(font
								(size 1.27 1.27)
							)
						)
					)
				)
				(pin passive line
					(at 0 -19.05 0)
					(length 5.08)
					(hide yes)
					(name "GND"
						(effects
							(font
								(size 1.27 1.27)
							)
						)
					)
					(number "V23"
						(effects
							(font
								(size 1.27 1.27)
							)
						)
					)
				)
				(pin passive line
					(at 0 -19.05 0)
					(length 5.08)
					(hide yes)
					(name "GND"
						(effects
							(font
								(size 1.27 1.27)
							)
						)
					)
					(number "V4"
						(effects
							(font
								(size 1.27 1.27)
							)
						)
					)
				)
				(pin passive line
					(at 0 -19.05 0)
					(length 5.08)
					(hide yes)
					(name "GND"
						(effects
							(font
								(size 1.27 1.27)
							)
						)
					)
					(number "V8"
						(effects
							(font
								(size 1.27 1.27)
							)
						)
					)
				)
				(pin passive line
					(at 0 -19.05 0)
					(length 5.08)
					(hide yes)
					(name "GND"
						(effects
							(font
								(size 1.27 1.27)
							)
						)
					)
					(number "V9"
						(effects
							(font
								(size 1.27 1.27)
							)
						)
					)
				)
				(pin passive line
					(at 0 -19.05 0)
					(length 5.08)
					(hide yes)
					(name "GND"
						(effects
							(font
								(size 1.27 1.27)
							)
						)
					)
					(number "W1"
						(effects
							(font
								(size 1.27 1.27)
							)
						)
					)
				)
				(pin passive line
					(at 0 -19.05 0)
					(length 5.08)
					(hide yes)
					(name "GND"
						(effects
							(font
								(size 1.27 1.27)
							)
						)
					)
					(number "W11"
						(effects
							(font
								(size 1.27 1.27)
							)
						)
					)
				)
				(pin passive line
					(at 0 -19.05 0)
					(length 5.08)
					(hide yes)
					(name "GND"
						(effects
							(font
								(size 1.27 1.27)
							)
						)
					)
					(number "W13"
						(effects
							(font
								(size 1.27 1.27)
							)
						)
					)
				)
				(pin passive line
					(at 0 -19.05 0)
					(length 5.08)
					(hide yes)
					(name "GND"
						(effects
							(font
								(size 1.27 1.27)
							)
						)
					)
					(number "W15"
						(effects
							(font
								(size 1.27 1.27)
							)
						)
					)
				)
				(pin passive line
					(at 0 -19.05 0)
					(length 5.08)
					(hide yes)
					(name "GND"
						(effects
							(font
								(size 1.27 1.27)
							)
						)
					)
					(number "W17"
						(effects
							(font
								(size 1.27 1.27)
							)
						)
					)
				)
				(pin passive line
					(at 0 -19.05 0)
					(length 5.08)
					(hide yes)
					(name "GND"
						(effects
							(font
								(size 1.27 1.27)
							)
						)
					)
					(number "W2"
						(effects
							(font
								(size 1.27 1.27)
							)
						)
					)
				)
				(pin passive line
					(at 0 -19.05 0)
					(length 5.08)
					(hide yes)
					(name "GND"
						(effects
							(font
								(size 1.27 1.27)
							)
						)
					)
					(number "W20"
						(effects
							(font
								(size 1.27 1.27)
							)
						)
					)
				)
				(pin passive line
					(at 0 -19.05 0)
					(length 5.08)
					(hide yes)
					(name "GND"
						(effects
							(font
								(size 1.27 1.27)
							)
						)
					)
					(number "W30"
						(effects
							(font
								(size 1.27 1.27)
							)
						)
					)
				)
				(pin passive line
					(at 0 -19.05 0)
					(length 5.08)
					(hide yes)
					(name "GND"
						(effects
							(font
								(size 1.27 1.27)
							)
						)
					)
					(number "W6"
						(effects
							(font
								(size 1.27 1.27)
							)
						)
					)
				)
				(pin passive line
					(at 0 -19.05 0)
					(length 5.08)
					(hide yes)
					(name "GND"
						(effects
							(font
								(size 1.27 1.27)
							)
						)
					)
					(number "W9"
						(effects
							(font
								(size 1.27 1.27)
							)
						)
					)
				)
				(pin passive line
					(at 0 -19.05 0)
					(length 5.08)
					(hide yes)
					(name "GND"
						(effects
							(font
								(size 1.27 1.27)
							)
						)
					)
					(number "Y17"
						(effects
							(font
								(size 1.27 1.27)
							)
						)
					)
				)
				(pin passive line
					(at 0 -19.05 0)
					(length 5.08)
					(hide yes)
					(name "GND"
						(effects
							(font
								(size 1.27 1.27)
							)
						)
					)
					(number "Y27"
						(effects
							(font
								(size 1.27 1.27)
							)
						)
					)
				)
				(pin passive line
					(at 0 -19.05 0)
					(length 5.08)
					(hide yes)
					(name "GND"
						(effects
							(font
								(size 1.27 1.27)
							)
						)
					)
					(number "Y3"
						(effects
							(font
								(size 1.27 1.27)
							)
						)
					)
				)
				(pin passive line
					(at 0 -19.05 0)
					(length 5.08)
					(hide yes)
					(name "GND"
						(effects
							(font
								(size 1.27 1.27)
							)
						)
					)
					(number "Y4"
						(effects
							(font
								(size 1.27 1.27)
							)
						)
					)
				)
				(pin passive line
					(at 0 -19.05 0)
					(length 5.08)
					(hide yes)
					(name "GND"
						(effects
							(font
								(size 1.27 1.27)
							)
						)
					)
					(number "Y7"
						(effects
							(font
								(size 1.27 1.27)
							)
						)
					)
				)
				(pin passive line
					(at 0 -19.05 0)
					(length 5.08)
					(hide yes)
					(name "GND"
						(effects
							(font
								(size 1.27 1.27)
							)
						)
					)
					(number "Y8"
						(effects
							(font
								(size 1.27 1.27)
							)
						)
					)
				)
				(pin passive line
					(at 0 -19.05 0)
					(length 5.08)
					(hide yes)
					(name "GND"
						(effects
							(font
								(size 1.27 1.27)
							)
						)
					)
					(number "Y9"
						(effects
							(font
								(size 1.27 1.27)
							)
						)
					)
				)
			)
		)
	(symbol "XC7K410T-2FFG900I_4"
			(exclude_from_sim no)
			(in_bom yes)
			(on_board yes)
			(property "Reference" "U"
				(at 82.55 -2.54 0)
				(effects
					(font
						(size 1.27 1.27)
						(thickness 0.15)
					)
					(justify left bottom)
				)
			)
			(property "Value" "XC7K410T-2FFG900I"
				(at 82.55 -7.62 0)
				(effects
					(font
						(size 1.27 1.27)
						(thickness 0.15)
					)
					(justify left bottom)
					(hide yes)
				)
			)
			(property "Footprint" "antmicro-footprints:BGA-900_31x31mm_Layout30x30_P1x1mm_FFG900"
				(at 82.55 -10.16 0)
				(effects
					(font
						(size 1.27 1.27)
						(thickness 0.15)
					)
					(justify left bottom)
					(hide yes)
				)
			)
			(property "Datasheet" "https://eu.mouser.com/datasheet/2/903/ds180_7Series_Overview-1591537.pdf"
				(at 82.55 -12.7 0)
				(effects
					(font
						(size 1.27 1.27)
						(thickness 0.15)
					)
					(justify left bottom)
					(hide yes)
				)
			)
			(property "Description" "FPGA, Kintex-7, MMCM, PLL, 350 I/O's, 710 MHz, 406720 Cells, 970 mV to 1.03 V, FCBGA-900"
				(at 0 0 0)
				(effects
					(font
						(size 1.27 1.27)
					)
					(hide yes)
				)
			)
			(property "MPN" "XC7K410T-2FFG900I"
				(at 82.55 -5.08 0)
				(effects
					(font
						(size 1.27 1.27)
						(thickness 0.15)
					)
					(justify left bottom)
				)
			)
			(property "Manufacturer" "AMD-Xilinx"
				(at 82.55 -15.24 0)
				(effects
					(font
						(size 1.27 1.27)
						(thickness 0.15)
					)
					(justify left bottom)
					(hide yes)
				)
			)
			(property "Author" "Antmicro"
				(at 82.55 -17.78 0)
				(effects
					(font
						(size 1.27 1.27)
						(thickness 0.15)
					)
					(justify left bottom)
					(hide yes)
				)
			)
			(property "License" "Apache-2.0"
				(at 82.55 -20.32 0)
				(effects
					(font
						(size 1.27 1.27)
						(thickness 0.15)
					)
					(justify left bottom)
					(hide yes)
				)
			)
			(property "ki_locked" ""
				(at 0 0 0)
				(effects
					(font
						(size 1.27 1.27)
					)
				)
			)
			(property "ki_keywords" "SMT, MICROCONTROLLER, IC, FPGA"
				(at 0 0 0)
				(effects
					(font
						(size 1.27 1.27)
					)
					(hide yes)
				)
			)
			(symbol "XC7K410T-2FFG900I_4_1_1"
				(rectangle
					(start 5.08 5.08)
					(end 50.8 -130.81)
					(stroke
						(width 0.254)
						(type default)
					)
					(fill
						(type background)
					)
				)
				(text "BANK 12"
					(at 15.24 2.54 0)
					(effects
						(font
							(size 1.27 1.27)
							(thickness 0.15)
						)
						(justify left bottom)
					)
				)
				(text "BANK 13"
					(at 31.75 2.54 0)
					(effects
						(font
							(size 1.27 1.27)
							(thickness 0.15)
						)
						(justify left bottom)
					)
				)
				(pin bidirectional line
					(at 0 0 0)
					(length 5.08)
					(name "VCCO_12"
						(effects
							(font
								(size 1.27 1.27)
							)
						)
					)
					(number "AC23"
						(effects
							(font
								(size 1.27 1.27)
							)
						)
					)
				)
				(pin passive line
					(at 0 0 0)
					(length 5.08)
					(hide yes)
					(name "VCCO_12"
						(effects
							(font
								(size 1.27 1.27)
							)
						)
					)
					(number "AD20"
						(effects
							(font
								(size 1.27 1.27)
							)
						)
					)
				)
				(pin passive line
					(at 0 0 0)
					(length 5.08)
					(hide yes)
					(name "VCCO_12"
						(effects
							(font
								(size 1.27 1.27)
							)
						)
					)
					(number "AF24"
						(effects
							(font
								(size 1.27 1.27)
							)
						)
					)
				)
				(pin passive line
					(at 0 0 0)
					(length 5.08)
					(hide yes)
					(name "VCCO_12"
						(effects
							(font
								(size 1.27 1.27)
							)
						)
					)
					(number "AG21"
						(effects
							(font
								(size 1.27 1.27)
							)
						)
					)
				)
				(pin passive line
					(at 0 0 0)
					(length 5.08)
					(hide yes)
					(name "VCCO_12"
						(effects
							(font
								(size 1.27 1.27)
							)
						)
					)
					(number "AK22"
						(effects
							(font
								(size 1.27 1.27)
							)
						)
					)
				)
				(pin passive line
					(at 0 0 0)
					(length 5.08)
					(hide yes)
					(name "VCCO_12"
						(effects
							(font
								(size 1.27 1.27)
							)
						)
					)
					(number "Y22"
						(effects
							(font
								(size 1.27 1.27)
							)
						)
					)
				)
				(pin bidirectional line
					(at 0 -3.81 0)
					(length 5.08)
					(name "IO_0_12"
						(effects
							(font
								(size 1.27 1.27)
							)
						)
					)
					(number "Y20"
						(effects
							(font
								(size 1.27 1.27)
							)
						)
					)
				)
				(pin bidirectional line
					(at 0 -6.35 0)
					(length 5.08)
					(name "IO_L1P_T0_12"
						(effects
							(font
								(size 1.27 1.27)
							)
						)
					)
					(number "Y23"
						(effects
							(font
								(size 1.27 1.27)
							)
						)
					)
				)
				(pin bidirectional line
					(at 0 -8.89 0)
					(length 5.08)
					(name "IO_L1N_T0_12"
						(effects
							(font
								(size 1.27 1.27)
							)
						)
					)
					(number "Y24"
						(effects
							(font
								(size 1.27 1.27)
							)
						)
					)
				)
				(pin bidirectional line
					(at 0 -11.43 0)
					(length 5.08)
					(name "IO_L2P_T0_12"
						(effects
							(font
								(size 1.27 1.27)
							)
						)
					)
					(number "Y21"
						(effects
							(font
								(size 1.27 1.27)
							)
						)
					)
				)
				(pin bidirectional line
					(at 0 -13.97 0)
					(length 5.08)
					(name "IO_L2N_T0_12"
						(effects
							(font
								(size 1.27 1.27)
							)
						)
					)
					(number "AA21"
						(effects
							(font
								(size 1.27 1.27)
							)
						)
					)
				)
				(pin bidirectional line
					(at 0 -16.51 0)
					(length 5.08)
					(name "IO_L3P_T0_DQS_12"
						(effects
							(font
								(size 1.27 1.27)
							)
						)
					)
					(number "AB22"
						(effects
							(font
								(size 1.27 1.27)
							)
						)
					)
				)
				(pin bidirectional line
					(at 0 -19.05 0)
					(length 5.08)
					(name "IO_L3N_T0_DQS_12"
						(effects
							(font
								(size 1.27 1.27)
							)
						)
					)
					(number "AB23"
						(effects
							(font
								(size 1.27 1.27)
							)
						)
					)
				)
				(pin bidirectional line
					(at 0 -21.59 0)
					(length 5.08)
					(name "IO_L4P_T0_12"
						(effects
							(font
								(size 1.27 1.27)
							)
						)
					)
					(number "AA22"
						(effects
							(font
								(size 1.27 1.27)
							)
						)
					)
				)
				(pin bidirectional line
					(at 0 -24.13 0)
					(length 5.08)
					(name "IO_L4N_T0_12"
						(effects
							(font
								(size 1.27 1.27)
							)
						)
					)
					(number "AA23"
						(effects
							(font
								(size 1.27 1.27)
							)
						)
					)
				)
				(pin bidirectional line
					(at 0 -26.67 0)
					(length 5.08)
					(name "IO_L5P_T0_12"
						(effects
							(font
								(size 1.27 1.27)
							)
						)
					)
					(number "AC20"
						(effects
							(font
								(size 1.27 1.27)
							)
						)
					)
				)
				(pin bidirectional line
					(at 0 -29.21 0)
					(length 5.08)
					(name "IO_L5N_T0_12"
						(effects
							(font
								(size 1.27 1.27)
							)
						)
					)
					(number "AC21"
						(effects
							(font
								(size 1.27 1.27)
							)
						)
					)
				)
				(pin bidirectional line
					(at 0 -31.75 0)
					(length 5.08)
					(name "IO_L6P_T0_12"
						(effects
							(font
								(size 1.27 1.27)
							)
						)
					)
					(number "AA20"
						(effects
							(font
								(size 1.27 1.27)
							)
						)
					)
				)
				(pin bidirectional line
					(at 0 -34.29 0)
					(length 5.08)
					(name "IO_L6N_T0_VREF_12"
						(effects
							(font
								(size 1.27 1.27)
							)
						)
					)
					(number "AB20"
						(effects
							(font
								(size 1.27 1.27)
							)
						)
					)
				)
				(pin bidirectional line
					(at 0 -36.83 0)
					(length 5.08)
					(name "IO_L7P_T1_12"
						(effects
							(font
								(size 1.27 1.27)
							)
						)
					)
					(number "AB24"
						(effects
							(font
								(size 1.27 1.27)
							)
						)
					)
				)
				(pin bidirectional line
					(at 0 -39.37 0)
					(length 5.08)
					(name "IO_L7N_T1_12"
						(effects
							(font
								(size 1.27 1.27)
							)
						)
					)
					(number "AC25"
						(effects
							(font
								(size 1.27 1.27)
							)
						)
					)
				)
				(pin bidirectional line
					(at 0 -41.91 0)
					(length 5.08)
					(name "IO_L8P_T1_12"
						(effects
							(font
								(size 1.27 1.27)
							)
						)
					)
					(number "AC22"
						(effects
							(font
								(size 1.27 1.27)
							)
						)
					)
				)
				(pin bidirectional line
					(at 0 -44.45 0)
					(length 5.08)
					(name "IO_L8N_T1_12"
						(effects
							(font
								(size 1.27 1.27)
							)
						)
					)
					(number "AD22"
						(effects
							(font
								(size 1.27 1.27)
							)
						)
					)
				)
				(pin bidirectional line
					(at 0 -46.99 0)
					(length 5.08)
					(name "IO_L9P_T1_DQS_12"
						(effects
							(font
								(size 1.27 1.27)
							)
						)
					)
					(number "AC24"
						(effects
							(font
								(size 1.27 1.27)
							)
						)
					)
				)
				(pin bidirectional line
					(at 0 -49.53 0)
					(length 5.08)
					(name "IO_L9N_T1_DQS_12"
						(effects
							(font
								(size 1.27 1.27)
							)
						)
					)
					(number "AD24"
						(effects
							(font
								(size 1.27 1.27)
							)
						)
					)
				)
				(pin bidirectional line
					(at 0 -52.07 0)
					(length 5.08)
					(name "IO_L10P_T1_12"
						(effects
							(font
								(size 1.27 1.27)
							)
						)
					)
					(number "AD21"
						(effects
							(font
								(size 1.27 1.27)
							)
						)
					)
				)
				(pin bidirectional line
					(at 0 -54.61 0)
					(length 5.08)
					(name "IO_L10N_T1_12"
						(effects
							(font
								(size 1.27 1.27)
							)
						)
					)
					(number "AE21"
						(effects
							(font
								(size 1.27 1.27)
							)
						)
					)
				)
				(pin bidirectional line
					(at 0 -57.15 0)
					(length 5.08)
					(name "IO_L11P_T1_SRCC_12"
						(effects
							(font
								(size 1.27 1.27)
							)
						)
					)
					(number "AE23"
						(effects
							(font
								(size 1.27 1.27)
							)
						)
					)
				)
				(pin bidirectional line
					(at 0 -59.69 0)
					(length 5.08)
					(name "IO_L11N_T1_SRCC_12"
						(effects
							(font
								(size 1.27 1.27)
							)
						)
					)
					(number "AF23"
						(effects
							(font
								(size 1.27 1.27)
							)
						)
					)
				)
				(pin bidirectional line
					(at 0 -62.23 0)
					(length 5.08)
					(name "IO_L12P_T1_MRCC_12"
						(effects
							(font
								(size 1.27 1.27)
							)
						)
					)
					(number "AD23"
						(effects
							(font
								(size 1.27 1.27)
							)
						)
					)
				)
				(pin bidirectional line
					(at 0 -64.77 0)
					(length 5.08)
					(name "IO_L12N_T1_MRCC_12"
						(effects
							(font
								(size 1.27 1.27)
							)
						)
					)
					(number "AE24"
						(effects
							(font
								(size 1.27 1.27)
							)
						)
					)
				)
				(pin bidirectional line
					(at 0 -67.31 0)
					(length 5.08)
					(name "IO_L13P_T2_MRCC_12"
						(effects
							(font
								(size 1.27 1.27)
							)
						)
					)
					(number "AF22"
						(effects
							(font
								(size 1.27 1.27)
							)
						)
					)
				)
				(pin bidirectional line
					(at 0 -69.85 0)
					(length 5.08)
					(name "IO_L13N_T2_MRCC_12"
						(effects
							(font
								(size 1.27 1.27)
							)
						)
					)
					(number "AG23"
						(effects
							(font
								(size 1.27 1.27)
							)
						)
					)
				)
				(pin bidirectional line
					(at 0 -72.39 0)
					(length 5.08)
					(name "IO_L14P_T2_SRCC_12"
						(effects
							(font
								(size 1.27 1.27)
							)
						)
					)
					(number "AG24"
						(effects
							(font
								(size 1.27 1.27)
							)
						)
					)
				)
				(pin bidirectional line
					(at 0 -74.93 0)
					(length 5.08)
					(name "IO_L14N_T2_SRCC_12"
						(effects
							(font
								(size 1.27 1.27)
							)
						)
					)
					(number "AH24"
						(effects
							(font
								(size 1.27 1.27)
							)
						)
					)
				)
				(pin bidirectional line
					(at 0 -77.47 0)
					(length 5.08)
					(name "IO_L15P_T2_DQS_12"
						(effects
							(font
								(size 1.27 1.27)
							)
						)
					)
					(number "AJ24"
						(effects
							(font
								(size 1.27 1.27)
							)
						)
					)
				)
				(pin bidirectional line
					(at 0 -80.01 0)
					(length 5.08)
					(name "IO_L15N_T2_DQS_12"
						(effects
							(font
								(size 1.27 1.27)
							)
						)
					)
					(number "AK25"
						(effects
							(font
								(size 1.27 1.27)
							)
						)
					)
				)
				(pin bidirectional line
					(at 0 -82.55 0)
					(length 5.08)
					(name "IO_L16P_T2_12"
						(effects
							(font
								(size 1.27 1.27)
							)
						)
					)
					(number "AE25"
						(effects
							(font
								(size 1.27 1.27)
							)
						)
					)
				)
				(pin bidirectional line
					(at 0 -85.09 0)
					(length 5.08)
					(name "IO_L16N_T2_12"
						(effects
							(font
								(size 1.27 1.27)
							)
						)
					)
					(number "AF25"
						(effects
							(font
								(size 1.27 1.27)
							)
						)
					)
				)
				(pin bidirectional line
					(at 0 -87.63 0)
					(length 5.08)
					(name "IO_L17P_T2_12"
						(effects
							(font
								(size 1.27 1.27)
							)
						)
					)
					(number "AK23"
						(effects
							(font
								(size 1.27 1.27)
							)
						)
					)
				)
				(pin bidirectional line
					(at 0 -90.17 0)
					(length 5.08)
					(name "IO_L17N_T2_12"
						(effects
							(font
								(size 1.27 1.27)
							)
						)
					)
					(number "AK24"
						(effects
							(font
								(size 1.27 1.27)
							)
						)
					)
				)
				(pin bidirectional line
					(at 0 -92.71 0)
					(length 5.08)
					(name "IO_L18P_T2_12"
						(effects
							(font
								(size 1.27 1.27)
							)
						)
					)
					(number "AG25"
						(effects
							(font
								(size 1.27 1.27)
							)
						)
					)
				)
				(pin bidirectional line
					(at 0 -95.25 0)
					(length 5.08)
					(name "IO_L18N_T2_12"
						(effects
							(font
								(size 1.27 1.27)
							)
						)
					)
					(number "AH25"
						(effects
							(font
								(size 1.27 1.27)
							)
						)
					)
				)
				(pin bidirectional line
					(at 0 -97.79 0)
					(length 5.08)
					(name "IO_L19P_T3_12"
						(effects
							(font
								(size 1.27 1.27)
							)
						)
					)
					(number "AF20"
						(effects
							(font
								(size 1.27 1.27)
							)
						)
					)
				)
				(pin bidirectional line
					(at 0 -100.33 0)
					(length 5.08)
					(name "IO_L19N_T3_VREF_12"
						(effects
							(font
								(size 1.27 1.27)
							)
						)
					)
					(number "AF21"
						(effects
							(font
								(size 1.27 1.27)
							)
						)
					)
				)
				(pin bidirectional line
					(at 0 -102.87 0)
					(length 5.08)
					(name "IO_L20P_T3_12"
						(effects
							(font
								(size 1.27 1.27)
							)
						)
					)
					(number "AG22"
						(effects
							(font
								(size 1.27 1.27)
							)
						)
					)
				)
				(pin bidirectional line
					(at 0 -105.41 0)
					(length 5.08)
					(name "IO_L20N_T3_12"
						(effects
							(font
								(size 1.27 1.27)
							)
						)
					)
					(number "AH22"
						(effects
							(font
								(size 1.27 1.27)
							)
						)
					)
				)
				(pin bidirectional line
					(at 0 -107.95 0)
					(length 5.08)
					(name "IO_L21P_T3_DQS_12"
						(effects
							(font
								(size 1.27 1.27)
							)
						)
					)
					(number "AJ22"
						(effects
							(font
								(size 1.27 1.27)
							)
						)
					)
				)
				(pin bidirectional line
					(at 0 -110.49 0)
					(length 5.08)
					(name "IO_L21N_T3_DQS_12"
						(effects
							(font
								(size 1.27 1.27)
							)
						)
					)
					(number "AJ23"
						(effects
							(font
								(size 1.27 1.27)
							)
						)
					)
				)
				(pin bidirectional line
					(at 0 -113.03 0)
					(length 5.08)
					(name "IO_L22P_T3_12"
						(effects
							(font
								(size 1.27 1.27)
							)
						)
					)
					(number "AG20"
						(effects
							(font
								(size 1.27 1.27)
							)
						)
					)
				)
				(pin bidirectional line
					(at 0 -115.57 0)
					(length 5.08)
					(name "IO_L22N_T3_12"
						(effects
							(font
								(size 1.27 1.27)
							)
						)
					)
					(number "AH20"
						(effects
							(font
								(size 1.27 1.27)
							)
						)
					)
				)
				(pin bidirectional line
					(at 0 -118.11 0)
					(length 5.08)
					(name "IO_L23P_T3_12"
						(effects
							(font
								(size 1.27 1.27)
							)
						)
					)
					(number "AH21"
						(effects
							(font
								(size 1.27 1.27)
							)
						)
					)
				)
				(pin bidirectional line
					(at 0 -120.65 0)
					(length 5.08)
					(name "IO_L23N_T3_12"
						(effects
							(font
								(size 1.27 1.27)
							)
						)
					)
					(number "AJ21"
						(effects
							(font
								(size 1.27 1.27)
							)
						)
					)
				)
				(pin bidirectional line
					(at 0 -123.19 0)
					(length 5.08)
					(name "IO_L24P_T3_12"
						(effects
							(font
								(size 1.27 1.27)
							)
						)
					)
					(number "AK20"
						(effects
							(font
								(size 1.27 1.27)
							)
						)
					)
				)
				(pin bidirectional line
					(at 0 -125.73 0)
					(length 5.08)
					(name "IO_L24N_T3_12"
						(effects
							(font
								(size 1.27 1.27)
							)
						)
					)
					(number "AK21"
						(effects
							(font
								(size 1.27 1.27)
							)
						)
					)
				)
				(pin bidirectional line
					(at 0 -128.27 0)
					(length 5.08)
					(name "IO_25_12"
						(effects
							(font
								(size 1.27 1.27)
							)
						)
					)
					(number "AE20"
						(effects
							(font
								(size 1.27 1.27)
							)
						)
					)
				)
				(pin bidirectional line
					(at 55.88 0 180)
					(length 5.08)
					(name "VCCO_13"
						(effects
							(font
								(size 1.27 1.27)
							)
						)
					)
					(number "AA29"
						(effects
							(font
								(size 1.27 1.27)
							)
						)
					)
				)
				(pin passive line
					(at 55.88 0 180)
					(length 5.08)
					(hide yes)
					(name "VCCO_13"
						(effects
							(font
								(size 1.27 1.27)
							)
						)
					)
					(number "AB26"
						(effects
							(font
								(size 1.27 1.27)
							)
						)
					)
				)
				(pin passive line
					(at 55.88 0 180)
					(length 5.08)
					(hide yes)
					(name "VCCO_13"
						(effects
							(font
								(size 1.27 1.27)
							)
						)
					)
					(number "AD30"
						(effects
							(font
								(size 1.27 1.27)
							)
						)
					)
				)
				(pin passive line
					(at 55.88 0 180)
					(length 5.08)
					(hide yes)
					(name "VCCO_13"
						(effects
							(font
								(size 1.27 1.27)
							)
						)
					)
					(number "AE27"
						(effects
							(font
								(size 1.27 1.27)
							)
						)
					)
				)
				(pin passive line
					(at 55.88 0 180)
					(length 5.08)
					(hide yes)
					(name "VCCO_13"
						(effects
							(font
								(size 1.27 1.27)
							)
						)
					)
					(number "AH28"
						(effects
							(font
								(size 1.27 1.27)
							)
						)
					)
				)
				(pin passive line
					(at 55.88 0 180)
					(length 5.08)
					(hide yes)
					(name "VCCO_13"
						(effects
							(font
								(size 1.27 1.27)
							)
						)
					)
					(number "AJ25"
						(effects
							(font
								(size 1.27 1.27)
							)
						)
					)
				)
				(pin bidirectional line
					(at 55.88 -3.81 180)
					(length 5.08)
					(name "IO_0_13"
						(effects
							(font
								(size 1.27 1.27)
							)
						)
					)
					(number "Y25"
						(effects
							(font
								(size 1.27 1.27)
							)
						)
					)
				)
				(pin bidirectional line
					(at 55.88 -6.35 180)
					(length 5.08)
					(name "IO_L1P_T0_13"
						(effects
							(font
								(size 1.27 1.27)
							)
						)
					)
					(number "Y26"
						(effects
							(font
								(size 1.27 1.27)
							)
						)
					)
				)
				(pin bidirectional line
					(at 55.88 -8.89 180)
					(length 5.08)
					(name "IO_L1N_T0_13"
						(effects
							(font
								(size 1.27 1.27)
							)
						)
					)
					(number "AA26"
						(effects
							(font
								(size 1.27 1.27)
							)
						)
					)
				)
				(pin bidirectional line
					(at 55.88 -11.43 180)
					(length 5.08)
					(name "IO_L2P_T0_13"
						(effects
							(font
								(size 1.27 1.27)
							)
						)
					)
					(number "W27"
						(effects
							(font
								(size 1.27 1.27)
							)
						)
					)
				)
				(pin bidirectional line
					(at 55.88 -13.97 180)
					(length 5.08)
					(name "IO_L2N_T0_13"
						(effects
							(font
								(size 1.27 1.27)
							)
						)
					)
					(number "W28"
						(effects
							(font
								(size 1.27 1.27)
							)
						)
					)
				)
				(pin bidirectional line
					(at 55.88 -16.51 180)
					(length 5.08)
					(name "IO_L3P_T0_DQS_13"
						(effects
							(font
								(size 1.27 1.27)
							)
						)
					)
					(number "Y28"
						(effects
							(font
								(size 1.27 1.27)
							)
						)
					)
				)
				(pin bidirectional line
					(at 55.88 -19.05 180)
					(length 5.08)
					(name "IO_L3N_T0_DQS_13"
						(effects
							(font
								(size 1.27 1.27)
							)
						)
					)
					(number "AA28"
						(effects
							(font
								(size 1.27 1.27)
							)
						)
					)
				)
				(pin bidirectional line
					(at 55.88 -21.59 180)
					(length 5.08)
					(name "IO_L4P_T0_13"
						(effects
							(font
								(size 1.27 1.27)
							)
						)
					)
					(number "W29"
						(effects
							(font
								(size 1.27 1.27)
							)
						)
					)
				)
				(pin bidirectional line
					(at 55.88 -24.13 180)
					(length 5.08)
					(name "IO_L4N_T0_13"
						(effects
							(font
								(size 1.27 1.27)
							)
						)
					)
					(number "Y29"
						(effects
							(font
								(size 1.27 1.27)
							)
						)
					)
				)
				(pin bidirectional line
					(at 55.88 -26.67 180)
					(length 5.08)
					(name "IO_L5P_T0_13"
						(effects
							(font
								(size 1.27 1.27)
							)
						)
					)
					(number "AA27"
						(effects
							(font
								(size 1.27 1.27)
							)
						)
					)
				)
				(pin bidirectional line
					(at 55.88 -29.21 180)
					(length 5.08)
					(name "IO_L5N_T0_13"
						(effects
							(font
								(size 1.27 1.27)
							)
						)
					)
					(number "AB28"
						(effects
							(font
								(size 1.27 1.27)
							)
						)
					)
				)
				(pin bidirectional line
					(at 55.88 -31.75 180)
					(length 5.08)
					(name "IO_L6P_T0_13"
						(effects
							(font
								(size 1.27 1.27)
							)
						)
					)
					(number "AA25"
						(effects
							(font
								(size 1.27 1.27)
							)
						)
					)
				)
				(pin bidirectional line
					(at 55.88 -34.29 180)
					(length 5.08)
					(name "IO_L6N_T0_VREF_13"
						(effects
							(font
								(size 1.27 1.27)
							)
						)
					)
					(number "AB25"
						(effects
							(font
								(size 1.27 1.27)
							)
						)
					)
				)
				(pin bidirectional line
					(at 55.88 -36.83 180)
					(length 5.08)
					(name "IO_L7P_T1_13"
						(effects
							(font
								(size 1.27 1.27)
							)
						)
					)
					(number "AC29"
						(effects
							(font
								(size 1.27 1.27)
							)
						)
					)
				)
				(pin bidirectional line
					(at 55.88 -39.37 180)
					(length 5.08)
					(name "IO_L7N_T1_13"
						(effects
							(font
								(size 1.27 1.27)
							)
						)
					)
					(number "AC30"
						(effects
							(font
								(size 1.27 1.27)
							)
						)
					)
				)
				(pin bidirectional line
					(at 55.88 -41.91 180)
					(length 5.08)
					(name "IO_L8P_T1_13"
						(effects
							(font
								(size 1.27 1.27)
							)
						)
					)
					(number "Y30"
						(effects
							(font
								(size 1.27 1.27)
							)
						)
					)
				)
				(pin bidirectional line
					(at 55.88 -44.45 180)
					(length 5.08)
					(name "IO_L8N_T1_13"
						(effects
							(font
								(size 1.27 1.27)
							)
						)
					)
					(number "AA30"
						(effects
							(font
								(size 1.27 1.27)
							)
						)
					)
				)
				(pin bidirectional line
					(at 55.88 -46.99 180)
					(length 5.08)
					(name "IO_L9P_T1_DQS_13"
						(effects
							(font
								(size 1.27 1.27)
							)
						)
					)
					(number "AD29"
						(effects
							(font
								(size 1.27 1.27)
							)
						)
					)
				)
				(pin bidirectional line
					(at 55.88 -49.53 180)
					(length 5.08)
					(name "IO_L9N_T1_DQS_13"
						(effects
							(font
								(size 1.27 1.27)
							)
						)
					)
					(number "AE29"
						(effects
							(font
								(size 1.27 1.27)
							)
						)
					)
				)
				(pin bidirectional line
					(at 55.88 -52.07 180)
					(length 5.08)
					(name "IO_L10P_T1_13"
						(effects
							(font
								(size 1.27 1.27)
							)
						)
					)
					(number "AB29"
						(effects
							(font
								(size 1.27 1.27)
							)
						)
					)
				)
				(pin bidirectional line
					(at 55.88 -54.61 180)
					(length 5.08)
					(name "IO_L10N_T1_13"
						(effects
							(font
								(size 1.27 1.27)
							)
						)
					)
					(number "AB30"
						(effects
							(font
								(size 1.27 1.27)
							)
						)
					)
				)
				(pin bidirectional line
					(at 55.88 -57.15 180)
					(length 5.08)
					(name "IO_L11P_T1_SRCC_13"
						(effects
							(font
								(size 1.27 1.27)
							)
						)
					)
					(number "AD27"
						(effects
							(font
								(size 1.27 1.27)
							)
						)
					)
				)
				(pin bidirectional line
					(at 55.88 -59.69 180)
					(length 5.08)
					(name "IO_L11N_T1_SRCC_13"
						(effects
							(font
								(size 1.27 1.27)
							)
						)
					)
					(number "AD28"
						(effects
							(font
								(size 1.27 1.27)
							)
						)
					)
				)
				(pin bidirectional line
					(at 55.88 -62.23 180)
					(length 5.08)
					(name "IO_L12P_T1_MRCC_13"
						(effects
							(font
								(size 1.27 1.27)
							)
						)
					)
					(number "AB27"
						(effects
							(font
								(size 1.27 1.27)
							)
						)
					)
				)
				(pin bidirectional line
					(at 55.88 -64.77 180)
					(length 5.08)
					(name "IO_L12N_T1_MRCC_13"
						(effects
							(font
								(size 1.27 1.27)
							)
						)
					)
					(number "AC27"
						(effects
							(font
								(size 1.27 1.27)
							)
						)
					)
				)
				(pin bidirectional line
					(at 55.88 -67.31 180)
					(length 5.08)
					(name "IO_L13P_T2_MRCC_13"
						(effects
							(font
								(size 1.27 1.27)
							)
						)
					)
					(number "AG29"
						(effects
							(font
								(size 1.27 1.27)
							)
						)
					)
				)
				(pin bidirectional line
					(at 55.88 -69.85 180)
					(length 5.08)
					(name "IO_L13N_T2_MRCC_13"
						(effects
							(font
								(size 1.27 1.27)
							)
						)
					)
					(number "AH29"
						(effects
							(font
								(size 1.27 1.27)
							)
						)
					)
				)
				(pin bidirectional line
					(at 55.88 -72.39 180)
					(length 5.08)
					(name "IO_L14P_T2_SRCC_13"
						(effects
							(font
								(size 1.27 1.27)
							)
						)
					)
					(number "AE28"
						(effects
							(font
								(size 1.27 1.27)
							)
						)
					)
				)
				(pin bidirectional line
					(at 55.88 -74.93 180)
					(length 5.08)
					(name "IO_L14N_T2_SRCC_13"
						(effects
							(font
								(size 1.27 1.27)
							)
						)
					)
					(number "AF28"
						(effects
							(font
								(size 1.27 1.27)
							)
						)
					)
				)
				(pin bidirectional line
					(at 55.88 -77.47 180)
					(length 5.08)
					(name "IO_L15P_T2_DQS_13"
						(effects
							(font
								(size 1.27 1.27)
							)
						)
					)
					(number "AK29"
						(effects
							(font
								(size 1.27 1.27)
							)
						)
					)
				)
				(pin bidirectional line
					(at 55.88 -80.01 180)
					(length 5.08)
					(name "IO_L15N_T2_DQS_13"
						(effects
							(font
								(size 1.27 1.27)
							)
						)
					)
					(number "AK30"
						(effects
							(font
								(size 1.27 1.27)
							)
						)
					)
				)
				(pin bidirectional line
					(at 55.88 -82.55 180)
					(length 5.08)
					(name "IO_L16P_T2_13"
						(effects
							(font
								(size 1.27 1.27)
							)
						)
					)
					(number "AE30"
						(effects
							(font
								(size 1.27 1.27)
							)
						)
					)
				)
				(pin bidirectional line
					(at 55.88 -85.09 180)
					(length 5.08)
					(name "IO_L16N_T2_13"
						(effects
							(font
								(size 1.27 1.27)
							)
						)
					)
					(number "AF30"
						(effects
							(font
								(size 1.27 1.27)
							)
						)
					)
				)
				(pin bidirectional line
					(at 55.88 -87.63 180)
					(length 5.08)
					(name "IO_L17P_T2_13"
						(effects
							(font
								(size 1.27 1.27)
							)
						)
					)
					(number "AJ28"
						(effects
							(font
								(size 1.27 1.27)
							)
						)
					)
				)
				(pin bidirectional line
					(at 55.88 -90.17 180)
					(length 5.08)
					(name "IO_L17N_T2_13"
						(effects
							(font
								(size 1.27 1.27)
							)
						)
					)
					(number "AJ29"
						(effects
							(font
								(size 1.27 1.27)
							)
						)
					)
				)
				(pin bidirectional line
					(at 55.88 -92.71 180)
					(length 5.08)
					(name "IO_L18P_T2_13"
						(effects
							(font
								(size 1.27 1.27)
							)
						)
					)
					(number "AG30"
						(effects
							(font
								(size 1.27 1.27)
							)
						)
					)
				)
				(pin bidirectional line
					(at 55.88 -95.25 180)
					(length 5.08)
					(name "IO_L18N_T2_13"
						(effects
							(font
								(size 1.27 1.27)
							)
						)
					)
					(number "AH30"
						(effects
							(font
								(size 1.27 1.27)
							)
						)
					)
				)
				(pin bidirectional line
					(at 55.88 -97.79 180)
					(length 5.08)
					(name "IO_L19P_T3_13"
						(effects
							(font
								(size 1.27 1.27)
							)
						)
					)
					(number "AC26"
						(effects
							(font
								(size 1.27 1.27)
							)
						)
					)
				)
				(pin bidirectional line
					(at 55.88 -100.33 180)
					(length 5.08)
					(name "IO_L19N_T3_VREF_13"
						(effects
							(font
								(size 1.27 1.27)
							)
						)
					)
					(number "AD26"
						(effects
							(font
								(size 1.27 1.27)
							)
						)
					)
				)
				(pin bidirectional line
					(at 55.88 -102.87 180)
					(length 5.08)
					(name "IO_L20P_T3_13"
						(effects
							(font
								(size 1.27 1.27)
							)
						)
					)
					(number "AJ27"
						(effects
							(font
								(size 1.27 1.27)
							)
						)
					)
				)
				(pin bidirectional line
					(at 55.88 -105.41 180)
					(length 5.08)
					(name "IO_L20N_T3_13"
						(effects
							(font
								(size 1.27 1.27)
							)
						)
					)
					(number "AK28"
						(effects
							(font
								(size 1.27 1.27)
							)
						)
					)
				)
				(pin bidirectional line
					(at 55.88 -107.95 180)
					(length 5.08)
					(name "IO_L21P_T3_DQS_13"
						(effects
							(font
								(size 1.27 1.27)
							)
						)
					)
					(number "AG27"
						(effects
							(font
								(size 1.27 1.27)
							)
						)
					)
				)
				(pin bidirectional line
					(at 55.88 -110.49 180)
					(length 5.08)
					(name "IO_L21N_T3_DQS_13"
						(effects
							(font
								(size 1.27 1.27)
							)
						)
					)
					(number "AG28"
						(effects
							(font
								(size 1.27 1.27)
							)
						)
					)
				)
				(pin bidirectional line
					(at 55.88 -113.03 180)
					(length 5.08)
					(name "IO_L22P_T3_13"
						(effects
							(font
								(size 1.27 1.27)
							)
						)
					)
					(number "AH26"
						(effects
							(font
								(size 1.27 1.27)
							)
						)
					)
				)
				(pin bidirectional line
					(at 55.88 -115.57 180)
					(length 5.08)
					(name "IO_L22N_T3_13"
						(effects
							(font
								(size 1.27 1.27)
							)
						)
					)
					(number "AH27"
						(effects
							(font
								(size 1.27 1.27)
							)
						)
					)
				)
				(pin bidirectional line
					(at 55.88 -118.11 180)
					(length 5.08)
					(name "IO_L23P_T3_13"
						(effects
							(font
								(size 1.27 1.27)
							)
						)
					)
					(number "AF26"
						(effects
							(font
								(size 1.27 1.27)
							)
						)
					)
				)
				(pin bidirectional line
					(at 55.88 -120.65 180)
					(length 5.08)
					(name "IO_L23N_T3_13"
						(effects
							(font
								(size 1.27 1.27)
							)
						)
					)
					(number "AF27"
						(effects
							(font
								(size 1.27 1.27)
							)
						)
					)
				)
				(pin bidirectional line
					(at 55.88 -123.19 180)
					(length 5.08)
					(name "IO_L24P_T3_13"
						(effects
							(font
								(size 1.27 1.27)
							)
						)
					)
					(number "AJ26"
						(effects
							(font
								(size 1.27 1.27)
							)
						)
					)
				)
				(pin bidirectional line
					(at 55.88 -125.73 180)
					(length 5.08)
					(name "IO_L24N_T3_13"
						(effects
							(font
								(size 1.27 1.27)
							)
						)
					)
					(number "AK26"
						(effects
							(font
								(size 1.27 1.27)
							)
						)
					)
				)
				(pin bidirectional line
					(at 55.88 -128.27 180)
					(length 5.08)
					(name "IO_25_13"
						(effects
							(font
								(size 1.27 1.27)
							)
						)
					)
					(number "AE26"
						(effects
							(font
								(size 1.27 1.27)
							)
						)
					)
				)
			)
			(symbol "XC7K410T-2FFG900I_4_2_1"
				(rectangle
					(start 5.08 5.08)
					(end 64.77 -130.81)
					(stroke
						(width 0.254)
						(type default)
					)
					(fill
						(type background)
					)
				)
				(text "BANK 14"
					(at 15.24 2.54 0)
					(effects
						(font
							(size 1.27 1.27)
							(thickness 0.15)
						)
						(justify left bottom)
					)
				)
				(text "BANK 15"
					(at 45.72 2.54 0)
					(effects
						(font
							(size 1.27 1.27)
							(thickness 0.15)
						)
						(justify left bottom)
					)
				)
				(pin bidirectional line
					(at 0 0 0)
					(length 5.08)
					(name "VCCO_14"
						(effects
							(font
								(size 1.27 1.27)
							)
						)
					)
					(number "P30"
						(effects
							(font
								(size 1.27 1.27)
							)
						)
					)
				)
				(pin passive line
					(at 0 0 0)
					(length 5.08)
					(hide yes)
					(name "VCCO_14"
						(effects
							(font
								(size 1.27 1.27)
							)
						)
					)
					(number "R27"
						(effects
							(font
								(size 1.27 1.27)
							)
						)
					)
				)
				(pin passive line
					(at 0 0 0)
					(length 5.08)
					(hide yes)
					(name "VCCO_14"
						(effects
							(font
								(size 1.27 1.27)
							)
						)
					)
					(number "T24"
						(effects
							(font
								(size 1.27 1.27)
							)
						)
					)
				)
				(pin passive line
					(at 0 0 0)
					(length 5.08)
					(hide yes)
					(name "VCCO_14"
						(effects
							(font
								(size 1.27 1.27)
							)
						)
					)
					(number "U21"
						(effects
							(font
								(size 1.27 1.27)
							)
						)
					)
				)
				(pin passive line
					(at 0 0 0)
					(length 5.08)
					(hide yes)
					(name "VCCO_14"
						(effects
							(font
								(size 1.27 1.27)
							)
						)
					)
					(number "V28"
						(effects
							(font
								(size 1.27 1.27)
							)
						)
					)
				)
				(pin passive line
					(at 0 0 0)
					(length 5.08)
					(hide yes)
					(name "VCCO_14"
						(effects
							(font
								(size 1.27 1.27)
							)
						)
					)
					(number "W25"
						(effects
							(font
								(size 1.27 1.27)
							)
						)
					)
				)
				(pin bidirectional line
					(at 0 -3.81 0)
					(length 5.08)
					(name "IO_0_14"
						(effects
							(font
								(size 1.27 1.27)
							)
						)
					)
					(number "R19"
						(effects
							(font
								(size 1.27 1.27)
							)
						)
					)
				)
				(pin bidirectional line
					(at 0 -6.35 0)
					(length 5.08)
					(name "IO_L1P_T0_D00_MOSI_14"
						(effects
							(font
								(size 1.27 1.27)
							)
						)
					)
					(number "P24"
						(effects
							(font
								(size 1.27 1.27)
							)
						)
					)
				)
				(pin bidirectional line
					(at 0 -8.89 0)
					(length 5.08)
					(name "IO_L1N_T0_D01_DIN_14"
						(effects
							(font
								(size 1.27 1.27)
							)
						)
					)
					(number "R25"
						(effects
							(font
								(size 1.27 1.27)
							)
						)
					)
				)
				(pin bidirectional line
					(at 0 -11.43 0)
					(length 5.08)
					(name "IO_L2P_T0_D02_14"
						(effects
							(font
								(size 1.27 1.27)
							)
						)
					)
					(number "R20"
						(effects
							(font
								(size 1.27 1.27)
							)
						)
					)
				)
				(pin bidirectional line
					(at 0 -13.97 0)
					(length 5.08)
					(name "IO_L2N_T0_D03_14"
						(effects
							(font
								(size 1.27 1.27)
							)
						)
					)
					(number "R21"
						(effects
							(font
								(size 1.27 1.27)
							)
						)
					)
				)
				(pin bidirectional line
					(at 0 -16.51 0)
					(length 5.08)
					(name "IO_L3P_T0_DQS_PUDC_B_14"
						(effects
							(font
								(size 1.27 1.27)
							)
						)
					)
					(number "R23"
						(effects
							(font
								(size 1.27 1.27)
							)
						)
					)
				)
				(pin bidirectional line
					(at 0 -19.05 0)
					(length 5.08)
					(name "IO_L3N_T0_DQS_EMCCLK_14"
						(effects
							(font
								(size 1.27 1.27)
							)
						)
					)
					(number "R24"
						(effects
							(font
								(size 1.27 1.27)
							)
						)
					)
				)
				(pin bidirectional line
					(at 0 -21.59 0)
					(length 5.08)
					(name "IO_L4P_T0_D04_14"
						(effects
							(font
								(size 1.27 1.27)
							)
						)
					)
					(number "T20"
						(effects
							(font
								(size 1.27 1.27)
							)
						)
					)
				)
				(pin bidirectional line
					(at 0 -24.13 0)
					(length 5.08)
					(name "IO_L4N_T0_D05_14"
						(effects
							(font
								(size 1.27 1.27)
							)
						)
					)
					(number "T21"
						(effects
							(font
								(size 1.27 1.27)
							)
						)
					)
				)
				(pin bidirectional line
					(at 0 -26.67 0)
					(length 5.08)
					(name "IO_L5P_T0_D06_14"
						(effects
							(font
								(size 1.27 1.27)
							)
						)
					)
					(number "T22"
						(effects
							(font
								(size 1.27 1.27)
							)
						)
					)
				)
				(pin bidirectional line
					(at 0 -29.21 0)
					(length 5.08)
					(name "IO_L5N_T0_D07_14"
						(effects
							(font
								(size 1.27 1.27)
							)
						)
					)
					(number "T23"
						(effects
							(font
								(size 1.27 1.27)
							)
						)
					)
				)
				(pin bidirectional line
					(at 0 -31.75 0)
					(length 5.08)
					(name "IO_L6P_T0_FCS_B_14"
						(effects
							(font
								(size 1.27 1.27)
							)
						)
					)
					(number "U19"
						(effects
							(font
								(size 1.27 1.27)
							)
						)
					)
				)
				(pin bidirectional line
					(at 0 -34.29 0)
					(length 5.08)
					(name "IO_L6N_T0_D08_VREF_14"
						(effects
							(font
								(size 1.27 1.27)
							)
						)
					)
					(number "U20"
						(effects
							(font
								(size 1.27 1.27)
							)
						)
					)
				)
				(pin bidirectional line
					(at 0 -36.83 0)
					(length 5.08)
					(name "IO_L7P_T1_D09_14"
						(effects
							(font
								(size 1.27 1.27)
							)
						)
					)
					(number "P29"
						(effects
							(font
								(size 1.27 1.27)
							)
						)
					)
				)
				(pin bidirectional line
					(at 0 -39.37 0)
					(length 5.08)
					(name "IO_L7N_T1_D10_14"
						(effects
							(font
								(size 1.27 1.27)
							)
						)
					)
					(number "R29"
						(effects
							(font
								(size 1.27 1.27)
							)
						)
					)
				)
				(pin bidirectional line
					(at 0 -41.91 0)
					(length 5.08)
					(name "IO_L8P_T1_D11_14"
						(effects
							(font
								(size 1.27 1.27)
							)
						)
					)
					(number "P27"
						(effects
							(font
								(size 1.27 1.27)
							)
						)
					)
				)
				(pin bidirectional line
					(at 0 -44.45 0)
					(length 5.08)
					(name "IO_L8N_T1_D12_14"
						(effects
							(font
								(size 1.27 1.27)
							)
						)
					)
					(number "P28"
						(effects
							(font
								(size 1.27 1.27)
							)
						)
					)
				)
				(pin bidirectional line
					(at 0 -46.99 0)
					(length 5.08)
					(name "IO_L9P_T1_DQS_14"
						(effects
							(font
								(size 1.27 1.27)
							)
						)
					)
					(number "R30"
						(effects
							(font
								(size 1.27 1.27)
							)
						)
					)
				)
				(pin bidirectional line
					(at 0 -49.53 0)
					(length 5.08)
					(name "IO_L9N_T1_DQS_D13_14"
						(effects
							(font
								(size 1.27 1.27)
							)
						)
					)
					(number "T30"
						(effects
							(font
								(size 1.27 1.27)
							)
						)
					)
				)
				(pin bidirectional line
					(at 0 -52.07 0)
					(length 5.08)
					(name "IO_L10P_T1_D14_14"
						(effects
							(font
								(size 1.27 1.27)
							)
						)
					)
					(number "P26"
						(effects
							(font
								(size 1.27 1.27)
							)
						)
					)
				)
				(pin bidirectional line
					(at 0 -54.61 0)
					(length 5.08)
					(name "IO_L10N_T1_D15_14"
						(effects
							(font
								(size 1.27 1.27)
							)
						)
					)
					(number "R26"
						(effects
							(font
								(size 1.27 1.27)
							)
						)
					)
				)
				(pin bidirectional line
					(at 0 -57.15 0)
					(length 5.08)
					(name "IO_L11P_T1_SRCC_14"
						(effects
							(font
								(size 1.27 1.27)
							)
						)
					)
					(number "R28"
						(effects
							(font
								(size 1.27 1.27)
							)
						)
					)
				)
				(pin bidirectional line
					(at 0 -59.69 0)
					(length 5.08)
					(name "IO_L11N_T1_SRCC_14"
						(effects
							(font
								(size 1.27 1.27)
							)
						)
					)
					(number "T28"
						(effects
							(font
								(size 1.27 1.27)
							)
						)
					)
				)
				(pin bidirectional line
					(at 0 -62.23 0)
					(length 5.08)
					(name "IO_L12P_T1_MRCC_14"
						(effects
							(font
								(size 1.27 1.27)
							)
						)
					)
					(number "T26"
						(effects
							(font
								(size 1.27 1.27)
							)
						)
					)
				)
				(pin bidirectional line
					(at 0 -64.77 0)
					(length 5.08)
					(name "IO_L12N_T1_MRCC_14"
						(effects
							(font
								(size 1.27 1.27)
							)
						)
					)
					(number "T27"
						(effects
							(font
								(size 1.27 1.27)
							)
						)
					)
				)
				(pin bidirectional line
					(at 0 -67.31 0)
					(length 5.08)
					(name "IO_L13P_T2_MRCC_14"
						(effects
							(font
								(size 1.27 1.27)
							)
						)
					)
					(number "U27"
						(effects
							(font
								(size 1.27 1.27)
							)
						)
					)
				)
				(pin bidirectional line
					(at 0 -69.85 0)
					(length 5.08)
					(name "IO_L13N_T2_MRCC_14"
						(effects
							(font
								(size 1.27 1.27)
							)
						)
					)
					(number "U28"
						(effects
							(font
								(size 1.27 1.27)
							)
						)
					)
				)
				(pin bidirectional line
					(at 0 -72.39 0)
					(length 5.08)
					(name "IO_L14P_T2_SRCC_14"
						(effects
							(font
								(size 1.27 1.27)
							)
						)
					)
					(number "T25"
						(effects
							(font
								(size 1.27 1.27)
							)
						)
					)
				)
				(pin bidirectional line
					(at 0 -74.93 0)
					(length 5.08)
					(name "IO_L14N_T2_SRCC_14"
						(effects
							(font
								(size 1.27 1.27)
							)
						)
					)
					(number "U25"
						(effects
							(font
								(size 1.27 1.27)
							)
						)
					)
				)
				(pin bidirectional line
					(at 0 -77.47 0)
					(length 5.08)
					(name "IO_L15P_T2_DQS_RDWR_B_14"
						(effects
							(font
								(size 1.27 1.27)
							)
						)
					)
					(number "U29"
						(effects
							(font
								(size 1.27 1.27)
							)
						)
					)
				)
				(pin bidirectional line
					(at 0 -80.01 0)
					(length 5.08)
					(name "IO_L15N_T2_DQS_DOUT_CSO_B_14"
						(effects
							(font
								(size 1.27 1.27)
							)
						)
					)
					(number "U30"
						(effects
							(font
								(size 1.27 1.27)
							)
						)
					)
				)
				(pin bidirectional line
					(at 0 -82.55 0)
					(length 5.08)
					(name "IO_L16P_T2_CSI_B_14"
						(effects
							(font
								(size 1.27 1.27)
							)
						)
					)
					(number "V26"
						(effects
							(font
								(size 1.27 1.27)
							)
						)
					)
				)
				(pin bidirectional line
					(at 0 -85.09 0)
					(length 5.08)
					(name "IO_L16N_T2_A15_D31_14"
						(effects
							(font
								(size 1.27 1.27)
							)
						)
					)
					(number "V27"
						(effects
							(font
								(size 1.27 1.27)
							)
						)
					)
				)
				(pin bidirectional line
					(at 0 -87.63 0)
					(length 5.08)
					(name "IO_L17P_T2_A14_D30_14"
						(effects
							(font
								(size 1.27 1.27)
							)
						)
					)
					(number "V29"
						(effects
							(font
								(size 1.27 1.27)
							)
						)
					)
				)
				(pin bidirectional line
					(at 0 -90.17 0)
					(length 5.08)
					(name "IO_L17N_T2_A13_D29_14"
						(effects
							(font
								(size 1.27 1.27)
							)
						)
					)
					(number "V30"
						(effects
							(font
								(size 1.27 1.27)
							)
						)
					)
				)
				(pin bidirectional line
					(at 0 -92.71 0)
					(length 5.08)
					(name "IO_L18P_T2_A12_D28_14"
						(effects
							(font
								(size 1.27 1.27)
							)
						)
					)
					(number "V25"
						(effects
							(font
								(size 1.27 1.27)
							)
						)
					)
				)
				(pin bidirectional line
					(at 0 -95.25 0)
					(length 5.08)
					(name "IO_L18N_T2_A11_D27_14"
						(effects
							(font
								(size 1.27 1.27)
							)
						)
					)
					(number "W26"
						(effects
							(font
								(size 1.27 1.27)
							)
						)
					)
				)
				(pin bidirectional line
					(at 0 -97.79 0)
					(length 5.08)
					(name "IO_L19P_T3_A10_D26_14"
						(effects
							(font
								(size 1.27 1.27)
							)
						)
					)
					(number "V19"
						(effects
							(font
								(size 1.27 1.27)
							)
						)
					)
				)
				(pin bidirectional line
					(at 0 -100.33 0)
					(length 5.08)
					(name "IO_L19N_T3_A09_D25_VREF_14"
						(effects
							(font
								(size 1.27 1.27)
							)
						)
					)
					(number "V20"
						(effects
							(font
								(size 1.27 1.27)
							)
						)
					)
				)
				(pin bidirectional line
					(at 0 -102.87 0)
					(length 5.08)
					(name "IO_L20P_T3_A08_D24_14"
						(effects
							(font
								(size 1.27 1.27)
							)
						)
					)
					(number "W23"
						(effects
							(font
								(size 1.27 1.27)
							)
						)
					)
				)
				(pin bidirectional line
					(at 0 -105.41 0)
					(length 5.08)
					(name "IO_L20N_T3_A07_D23_14"
						(effects
							(font
								(size 1.27 1.27)
							)
						)
					)
					(number "W24"
						(effects
							(font
								(size 1.27 1.27)
							)
						)
					)
				)
				(pin bidirectional line
					(at 0 -107.95 0)
					(length 5.08)
					(name "IO_L21P_T3_DQS_14"
						(effects
							(font
								(size 1.27 1.27)
							)
						)
					)
					(number "U22"
						(effects
							(font
								(size 1.27 1.27)
							)
						)
					)
				)
				(pin bidirectional line
					(at 0 -110.49 0)
					(length 5.08)
					(name "IO_L21N_T3_DQS_A06_D22_14"
						(effects
							(font
								(size 1.27 1.27)
							)
						)
					)
					(number "U23"
						(effects
							(font
								(size 1.27 1.27)
							)
						)
					)
				)
				(pin bidirectional line
					(at 0 -113.03 0)
					(length 5.08)
					(name "IO_L22P_T3_A05_D21_14"
						(effects
							(font
								(size 1.27 1.27)
							)
						)
					)
					(number "V21"
						(effects
							(font
								(size 1.27 1.27)
							)
						)
					)
				)
				(pin bidirectional line
					(at 0 -115.57 0)
					(length 5.08)
					(name "IO_L22N_T3_A04_D20_14"
						(effects
							(font
								(size 1.27 1.27)
							)
						)
					)
					(number "V22"
						(effects
							(font
								(size 1.27 1.27)
							)
						)
					)
				)
				(pin bidirectional line
					(at 0 -118.11 0)
					(length 5.08)
					(name "IO_L23P_T3_A03_D19_14"
						(effects
							(font
								(size 1.27 1.27)
							)
						)
					)
					(number "U24"
						(effects
							(font
								(size 1.27 1.27)
							)
						)
					)
				)
				(pin bidirectional line
					(at 0 -120.65 0)
					(length 5.08)
					(name "IO_L23N_T3_A02_D18_14"
						(effects
							(font
								(size 1.27 1.27)
							)
						)
					)
					(number "V24"
						(effects
							(font
								(size 1.27 1.27)
							)
						)
					)
				)
				(pin bidirectional line
					(at 0 -123.19 0)
					(length 5.08)
					(name "IO_L24P_T3_A01_D17_14"
						(effects
							(font
								(size 1.27 1.27)
							)
						)
					)
					(number "W21"
						(effects
							(font
								(size 1.27 1.27)
							)
						)
					)
				)
				(pin bidirectional line
					(at 0 -125.73 0)
					(length 5.08)
					(name "IO_L24N_T3_A00_D16_14"
						(effects
							(font
								(size 1.27 1.27)
							)
						)
					)
					(number "W22"
						(effects
							(font
								(size 1.27 1.27)
							)
						)
					)
				)
				(pin bidirectional line
					(at 0 -128.27 0)
					(length 5.08)
					(name "IO_25_14"
						(effects
							(font
								(size 1.27 1.27)
							)
						)
					)
					(number "W19"
						(effects
							(font
								(size 1.27 1.27)
							)
						)
					)
				)
				(pin bidirectional line
					(at 69.85 0 180)
					(length 5.08)
					(name "VCCO_15"
						(effects
							(font
								(size 1.27 1.27)
							)
						)
					)
					(number "J25"
						(effects
							(font
								(size 1.27 1.27)
							)
						)
					)
				)
				(pin passive line
					(at 69.85 0 180)
					(length 5.08)
					(hide yes)
					(name "VCCO_15"
						(effects
							(font
								(size 1.27 1.27)
							)
						)
					)
					(number "K22"
						(effects
							(font
								(size 1.27 1.27)
							)
						)
					)
				)
				(pin passive line
					(at 69.85 0 180)
					(length 5.08)
					(hide yes)
					(name "VCCO_15"
						(effects
							(font
								(size 1.27 1.27)
							)
						)
					)
					(number "L29"
						(effects
							(font
								(size 1.27 1.27)
							)
						)
					)
				)
				(pin passive line
					(at 69.85 0 180)
					(length 5.08)
					(hide yes)
					(name "VCCO_15"
						(effects
							(font
								(size 1.27 1.27)
							)
						)
					)
					(number "M26"
						(effects
							(font
								(size 1.27 1.27)
							)
						)
					)
				)
				(pin passive line
					(at 69.85 0 180)
					(length 5.08)
					(hide yes)
					(name "VCCO_15"
						(effects
							(font
								(size 1.27 1.27)
							)
						)
					)
					(number "N23"
						(effects
							(font
								(size 1.27 1.27)
							)
						)
					)
				)
				(pin passive line
					(at 69.85 0 180)
					(length 5.08)
					(hide yes)
					(name "VCCO_15"
						(effects
							(font
								(size 1.27 1.27)
							)
						)
					)
					(number "P20"
						(effects
							(font
								(size 1.27 1.27)
							)
						)
					)
				)
				(pin bidirectional line
					(at 69.85 -3.81 180)
					(length 5.08)
					(name "IO_0_15"
						(effects
							(font
								(size 1.27 1.27)
							)
						)
					)
					(number "M19"
						(effects
							(font
								(size 1.27 1.27)
							)
						)
					)
				)
				(pin bidirectional line
					(at 69.85 -6.35 180)
					(length 5.08)
					(name "IO_L1P_T0_AD0P_15"
						(effects
							(font
								(size 1.27 1.27)
							)
						)
					)
					(number "J23"
						(effects
							(font
								(size 1.27 1.27)
							)
						)
					)
				)
				(pin bidirectional line
					(at 69.85 -8.89 180)
					(length 5.08)
					(name "IO_L1N_T0_AD0N_15"
						(effects
							(font
								(size 1.27 1.27)
							)
						)
					)
					(number "J24"
						(effects
							(font
								(size 1.27 1.27)
							)
						)
					)
				)
				(pin bidirectional line
					(at 69.85 -11.43 180)
					(length 5.08)
					(name "IO_L2P_T0_AD8P_15"
						(effects
							(font
								(size 1.27 1.27)
							)
						)
					)
					(number "L22"
						(effects
							(font
								(size 1.27 1.27)
							)
						)
					)
				)
				(pin bidirectional line
					(at 69.85 -13.97 180)
					(length 5.08)
					(name "IO_L2N_T0_AD8N_15"
						(effects
							(font
								(size 1.27 1.27)
							)
						)
					)
					(number "L23"
						(effects
							(font
								(size 1.27 1.27)
							)
						)
					)
				)
				(pin bidirectional line
					(at 69.85 -16.51 180)
					(length 5.08)
					(name "IO_L3P_T0_DQS_AD1P_15"
						(effects
							(font
								(size 1.27 1.27)
							)
						)
					)
					(number "K23"
						(effects
							(font
								(size 1.27 1.27)
							)
						)
					)
				)
				(pin bidirectional line
					(at 69.85 -19.05 180)
					(length 5.08)
					(name "IO_L3N_T0_DQS_AD1N_15"
						(effects
							(font
								(size 1.27 1.27)
							)
						)
					)
					(number "K24"
						(effects
							(font
								(size 1.27 1.27)
							)
						)
					)
				)
				(pin bidirectional line
					(at 69.85 -21.59 180)
					(length 5.08)
					(name "IO_L4P_T0_AD9P_15"
						(effects
							(font
								(size 1.27 1.27)
							)
						)
					)
					(number "L21"
						(effects
							(font
								(size 1.27 1.27)
							)
						)
					)
				)
				(pin bidirectional line
					(at 69.85 -24.13 180)
					(length 5.08)
					(name "IO_L4N_T0_AD9N_15"
						(effects
							(font
								(size 1.27 1.27)
							)
						)
					)
					(number "K21"
						(effects
							(font
								(size 1.27 1.27)
							)
						)
					)
				)
				(pin bidirectional line
					(at 69.85 -26.67 180)
					(length 5.08)
					(name "IO_L5P_T0_AD2P_15"
						(effects
							(font
								(size 1.27 1.27)
							)
						)
					)
					(number "J21"
						(effects
							(font
								(size 1.27 1.27)
							)
						)
					)
				)
				(pin bidirectional line
					(at 69.85 -29.21 180)
					(length 5.08)
					(name "IO_L5N_T0_AD2N_15"
						(effects
							(font
								(size 1.27 1.27)
							)
						)
					)
					(number "J22"
						(effects
							(font
								(size 1.27 1.27)
							)
						)
					)
				)
				(pin bidirectional line
					(at 69.85 -31.75 180)
					(length 5.08)
					(name "IO_L6P_T0_15"
						(effects
							(font
								(size 1.27 1.27)
							)
						)
					)
					(number "M20"
						(effects
							(font
								(size 1.27 1.27)
							)
						)
					)
				)
				(pin bidirectional line
					(at 69.85 -34.29 180)
					(length 5.08)
					(name "IO_L6N_T0_VREF_15"
						(effects
							(font
								(size 1.27 1.27)
							)
						)
					)
					(number "L20"
						(effects
							(font
								(size 1.27 1.27)
							)
						)
					)
				)
				(pin bidirectional line
					(at 69.85 -36.83 180)
					(length 5.08)
					(name "IO_L7P_T1_AD10P_15"
						(effects
							(font
								(size 1.27 1.27)
							)
						)
					)
					(number "J29"
						(effects
							(font
								(size 1.27 1.27)
							)
						)
					)
				)
				(pin bidirectional line
					(at 69.85 -39.37 180)
					(length 5.08)
					(name "IO_L7N_T1_AD10N_15"
						(effects
							(font
								(size 1.27 1.27)
							)
						)
					)
					(number "H29"
						(effects
							(font
								(size 1.27 1.27)
							)
						)
					)
				)
				(pin bidirectional line
					(at 69.85 -41.91 180)
					(length 5.08)
					(name "IO_L8P_T1_AD3P_15"
						(effects
							(font
								(size 1.27 1.27)
							)
						)
					)
					(number "J27"
						(effects
							(font
								(size 1.27 1.27)
							)
						)
					)
				)
				(pin bidirectional line
					(at 69.85 -44.45 180)
					(length 5.08)
					(name "IO_L8N_T1_AD3N_15"
						(effects
							(font
								(size 1.27 1.27)
							)
						)
					)
					(number "J28"
						(effects
							(font
								(size 1.27 1.27)
							)
						)
					)
				)
				(pin bidirectional line
					(at 69.85 -46.99 180)
					(length 5.08)
					(name "IO_L9P_T1_DQS_AD11P_15"
						(effects
							(font
								(size 1.27 1.27)
							)
						)
					)
					(number "L30"
						(effects
							(font
								(size 1.27 1.27)
							)
						)
					)
				)
				(pin bidirectional line
					(at 69.85 -49.53 180)
					(length 5.08)
					(name "IO_L9N_T1_DQS_AD11N_15"
						(effects
							(font
								(size 1.27 1.27)
							)
						)
					)
					(number "K30"
						(effects
							(font
								(size 1.27 1.27)
							)
						)
					)
				)
				(pin bidirectional line
					(at 69.85 -52.07 180)
					(length 5.08)
					(name "IO_L10P_T1_AD4P_15"
						(effects
							(font
								(size 1.27 1.27)
							)
						)
					)
					(number "K26"
						(effects
							(font
								(size 1.27 1.27)
							)
						)
					)
				)
				(pin bidirectional line
					(at 69.85 -54.61 180)
					(length 5.08)
					(name "IO_L10N_T1_AD4N_15"
						(effects
							(font
								(size 1.27 1.27)
							)
						)
					)
					(number "J26"
						(effects
							(font
								(size 1.27 1.27)
							)
						)
					)
				)
				(pin bidirectional line
					(at 69.85 -57.15 180)
					(length 5.08)
					(name "IO_L11P_T1_SRCC_AD12P_15"
						(effects
							(font
								(size 1.27 1.27)
							)
						)
					)
					(number "L26"
						(effects
							(font
								(size 1.27 1.27)
							)
						)
					)
				)
				(pin bidirectional line
					(at 69.85 -59.69 180)
					(length 5.08)
					(name "IO_L11N_T1_SRCC_AD12N_15"
						(effects
							(font
								(size 1.27 1.27)
							)
						)
					)
					(number "L27"
						(effects
							(font
								(size 1.27 1.27)
							)
						)
					)
				)
				(pin bidirectional line
					(at 69.85 -62.23 180)
					(length 5.08)
					(name "IO_L12P_T1_MRCC_AD5P_15"
						(effects
							(font
								(size 1.27 1.27)
							)
						)
					)
					(number "L25"
						(effects
							(font
								(size 1.27 1.27)
							)
						)
					)
				)
				(pin bidirectional line
					(at 69.85 -64.77 180)
					(length 5.08)
					(name "IO_L12N_T1_MRCC_AD5N_15"
						(effects
							(font
								(size 1.27 1.27)
							)
						)
					)
					(number "K25"
						(effects
							(font
								(size 1.27 1.27)
							)
						)
					)
				)
				(pin bidirectional line
					(at 69.85 -67.31 180)
					(length 5.08)
					(name "IO_L13P_T2_MRCC_15"
						(effects
							(font
								(size 1.27 1.27)
							)
						)
					)
					(number "K28"
						(effects
							(font
								(size 1.27 1.27)
							)
						)
					)
				)
				(pin bidirectional line
					(at 69.85 -69.85 180)
					(length 5.08)
					(name "IO_L13N_T2_MRCC_15"
						(effects
							(font
								(size 1.27 1.27)
							)
						)
					)
					(number "K29"
						(effects
							(font
								(size 1.27 1.27)
							)
						)
					)
				)
				(pin bidirectional line
					(at 69.85 -72.39 180)
					(length 5.08)
					(name "IO_L14P_T2_SRCC_15"
						(effects
							(font
								(size 1.27 1.27)
							)
						)
					)
					(number "M28"
						(effects
							(font
								(size 1.27 1.27)
							)
						)
					)
				)
				(pin bidirectional line
					(at 69.85 -74.93 180)
					(length 5.08)
					(name "IO_L14N_T2_SRCC_15"
						(effects
							(font
								(size 1.27 1.27)
							)
						)
					)
					(number "L28"
						(effects
							(font
								(size 1.27 1.27)
							)
						)
					)
				)
				(pin bidirectional line
					(at 69.85 -77.47 180)
					(length 5.08)
					(name "IO_L15P_T2_DQS_15"
						(effects
							(font
								(size 1.27 1.27)
							)
						)
					)
					(number "M29"
						(effects
							(font
								(size 1.27 1.27)
							)
						)
					)
				)
				(pin bidirectional line
					(at 69.85 -80.01 180)
					(length 5.08)
					(name "IO_L15N_T2_DQS_ADV_B_15"
						(effects
							(font
								(size 1.27 1.27)
							)
						)
					)
					(number "M30"
						(effects
							(font
								(size 1.27 1.27)
							)
						)
					)
				)
				(pin bidirectional line
					(at 69.85 -82.55 180)
					(length 5.08)
					(name "IO_L16P_T2_A28_15"
						(effects
							(font
								(size 1.27 1.27)
							)
						)
					)
					(number "N27"
						(effects
							(font
								(size 1.27 1.27)
							)
						)
					)
				)
				(pin bidirectional line
					(at 69.85 -85.09 180)
					(length 5.08)
					(name "IO_L16N_T2_A27_15"
						(effects
							(font
								(size 1.27 1.27)
							)
						)
					)
					(number "M27"
						(effects
							(font
								(size 1.27 1.27)
							)
						)
					)
				)
				(pin bidirectional line
					(at 69.85 -87.63 180)
					(length 5.08)
					(name "IO_L17P_T2_A26_15"
						(effects
							(font
								(size 1.27 1.27)
							)
						)
					)
					(number "N29"
						(effects
							(font
								(size 1.27 1.27)
							)
						)
					)
				)
				(pin bidirectional line
					(at 69.85 -90.17 180)
					(length 5.08)
					(name "IO_L17N_T2_A25_15"
						(effects
							(font
								(size 1.27 1.27)
							)
						)
					)
					(number "N30"
						(effects
							(font
								(size 1.27 1.27)
							)
						)
					)
				)
				(pin bidirectional line
					(at 69.85 -92.71 180)
					(length 5.08)
					(name "IO_L18P_T2_A24_15"
						(effects
							(font
								(size 1.27 1.27)
							)
						)
					)
					(number "N25"
						(effects
							(font
								(size 1.27 1.27)
							)
						)
					)
				)
				(pin bidirectional line
					(at 69.85 -95.25 180)
					(length 5.08)
					(name "IO_L18N_T2_A23_15"
						(effects
							(font
								(size 1.27 1.27)
							)
						)
					)
					(number "N26"
						(effects
							(font
								(size 1.27 1.27)
							)
						)
					)
				)
				(pin bidirectional line
					(at 69.85 -97.79 180)
					(length 5.08)
					(name "IO_L19P_T3_A22_15"
						(effects
							(font
								(size 1.27 1.27)
							)
						)
					)
					(number "N19"
						(effects
							(font
								(size 1.27 1.27)
							)
						)
					)
				)
				(pin bidirectional line
					(at 69.85 -100.33 180)
					(length 5.08)
					(name "IO_L19N_T3_A21_VREF_15"
						(effects
							(font
								(size 1.27 1.27)
							)
						)
					)
					(number "N20"
						(effects
							(font
								(size 1.27 1.27)
							)
						)
					)
				)
				(pin bidirectional line
					(at 69.85 -102.87 180)
					(length 5.08)
					(name "IO_L20P_T3_A20_15"
						(effects
							(font
								(size 1.27 1.27)
							)
						)
					)
					(number "N21"
						(effects
							(font
								(size 1.27 1.27)
							)
						)
					)
				)
				(pin bidirectional line
					(at 69.85 -105.41 180)
					(length 5.08)
					(name "IO_L20N_T3_A19_15"
						(effects
							(font
								(size 1.27 1.27)
							)
						)
					)
					(number "N22"
						(effects
							(font
								(size 1.27 1.27)
							)
						)
					)
				)
				(pin bidirectional line
					(at 69.85 -107.95 180)
					(length 5.08)
					(name "IO_L21P_T3_DQS_15"
						(effects
							(font
								(size 1.27 1.27)
							)
						)
					)
					(number "P23"
						(effects
							(font
								(size 1.27 1.27)
							)
						)
					)
				)
				(pin bidirectional line
					(at 69.85 -110.49 180)
					(length 5.08)
					(name "IO_L21N_T3_DQS_A18_15"
						(effects
							(font
								(size 1.27 1.27)
							)
						)
					)
					(number "N24"
						(effects
							(font
								(size 1.27 1.27)
							)
						)
					)
				)
				(pin bidirectional line
					(at 69.85 -113.03 180)
					(length 5.08)
					(name "IO_L22P_T3_A17_15"
						(effects
							(font
								(size 1.27 1.27)
							)
						)
					)
					(number "P21"
						(effects
							(font
								(size 1.27 1.27)
							)
						)
					)
				)
				(pin bidirectional line
					(at 69.85 -115.57 180)
					(length 5.08)
					(name "IO_L22N_T3_A16_15"
						(effects
							(font
								(size 1.27 1.27)
							)
						)
					)
					(number "P22"
						(effects
							(font
								(size 1.27 1.27)
							)
						)
					)
				)
				(pin bidirectional line
					(at 69.85 -118.11 180)
					(length 5.08)
					(name "IO_L23P_T3_FOE_B_15"
						(effects
							(font
								(size 1.27 1.27)
							)
						)
					)
					(number "M24"
						(effects
							(font
								(size 1.27 1.27)
							)
						)
					)
				)
				(pin bidirectional line
					(at 69.85 -120.65 180)
					(length 5.08)
					(name "IO_L23N_T3_FWE_B_15"
						(effects
							(font
								(size 1.27 1.27)
							)
						)
					)
					(number "M25"
						(effects
							(font
								(size 1.27 1.27)
							)
						)
					)
				)
				(pin bidirectional line
					(at 69.85 -123.19 180)
					(length 5.08)
					(name "IO_L24P_T3_RS1_15"
						(effects
							(font
								(size 1.27 1.27)
							)
						)
					)
					(number "M22"
						(effects
							(font
								(size 1.27 1.27)
							)
						)
					)
				)
				(pin bidirectional line
					(at 69.85 -125.73 180)
					(length 5.08)
					(name "IO_L24N_T3_RS0_15"
						(effects
							(font
								(size 1.27 1.27)
							)
						)
					)
					(number "M23"
						(effects
							(font
								(size 1.27 1.27)
							)
						)
					)
				)
				(pin bidirectional line
					(at 69.85 -128.27 180)
					(length 5.08)
					(name "IO_25_15"
						(effects
							(font
								(size 1.27 1.27)
							)
						)
					)
					(number "P19"
						(effects
							(font
								(size 1.27 1.27)
							)
						)
					)
				)
			)
			(symbol "XC7K410T-2FFG900I_4_3_1"
				(rectangle
					(start 5.08 5.08)
					(end 49.53 -130.81)
					(stroke
						(width 0.254)
						(type default)
					)
					(fill
						(type background)
					)
				)
				(text "BANK 16"
					(at 15.24 2.54 0)
					(effects
						(font
							(size 1.27 1.27)
							(thickness 0.15)
						)
						(justify left bottom)
					)
				)
				(text "BANK 17"
					(at 30.48 2.54 0)
					(effects
						(font
							(size 1.27 1.27)
							(thickness 0.15)
						)
						(justify left bottom)
					)
				)
				(pin bidirectional line
					(at 0 0 0)
					(length 5.08)
					(name "VCCO_16"
						(effects
							(font
								(size 1.27 1.27)
							)
						)
					)
					(number "A29"
						(effects
							(font
								(size 1.27 1.27)
							)
						)
					)
				)
				(pin passive line
					(at 0 0 0)
					(length 5.08)
					(hide yes)
					(name "VCCO_16"
						(effects
							(font
								(size 1.27 1.27)
							)
						)
					)
					(number "B26"
						(effects
							(font
								(size 1.27 1.27)
							)
						)
					)
				)
				(pin passive line
					(at 0 0 0)
					(length 5.08)
					(hide yes)
					(name "VCCO_16"
						(effects
							(font
								(size 1.27 1.27)
							)
						)
					)
					(number "C23"
						(effects
							(font
								(size 1.27 1.27)
							)
						)
					)
				)
				(pin passive line
					(at 0 0 0)
					(length 5.08)
					(hide yes)
					(name "VCCO_16"
						(effects
							(font
								(size 1.27 1.27)
							)
						)
					)
					(number "D30"
						(effects
							(font
								(size 1.27 1.27)
							)
						)
					)
				)
				(pin passive line
					(at 0 0 0)
					(length 5.08)
					(hide yes)
					(name "VCCO_16"
						(effects
							(font
								(size 1.27 1.27)
							)
						)
					)
					(number "E27"
						(effects
							(font
								(size 1.27 1.27)
							)
						)
					)
				)
				(pin passive line
					(at 0 0 0)
					(length 5.08)
					(hide yes)
					(name "VCCO_16"
						(effects
							(font
								(size 1.27 1.27)
							)
						)
					)
					(number "F24"
						(effects
							(font
								(size 1.27 1.27)
							)
						)
					)
				)
				(pin passive line
					(at 0 0 0)
					(length 5.08)
					(hide yes)
					(name "VCCO_16"
						(effects
							(font
								(size 1.27 1.27)
							)
						)
					)
					(number "H28"
						(effects
							(font
								(size 1.27 1.27)
							)
						)
					)
				)
				(pin bidirectional line
					(at 0 -3.81 0)
					(length 5.08)
					(name "IO_0_16"
						(effects
							(font
								(size 1.27 1.27)
							)
						)
					)
					(number "F23"
						(effects
							(font
								(size 1.27 1.27)
							)
						)
					)
				)
				(pin bidirectional line
					(at 0 -6.35 0)
					(length 5.08)
					(name "IO_L1P_T0_16"
						(effects
							(font
								(size 1.27 1.27)
							)
						)
					)
					(number "B23"
						(effects
							(font
								(size 1.27 1.27)
							)
						)
					)
				)
				(pin bidirectional line
					(at 0 -8.89 0)
					(length 5.08)
					(name "IO_L1N_T0_16"
						(effects
							(font
								(size 1.27 1.27)
							)
						)
					)
					(number "A23"
						(effects
							(font
								(size 1.27 1.27)
							)
						)
					)
				)
				(pin bidirectional line
					(at 0 -11.43 0)
					(length 5.08)
					(name "IO_L2P_T0_16"
						(effects
							(font
								(size 1.27 1.27)
							)
						)
					)
					(number "E23"
						(effects
							(font
								(size 1.27 1.27)
							)
						)
					)
				)
				(pin bidirectional line
					(at 0 -13.97 0)
					(length 5.08)
					(name "IO_L2N_T0_16"
						(effects
							(font
								(size 1.27 1.27)
							)
						)
					)
					(number "D23"
						(effects
							(font
								(size 1.27 1.27)
							)
						)
					)
				)
				(pin bidirectional line
					(at 0 -16.51 0)
					(length 5.08)
					(name "IO_L3P_T0_DQS_16"
						(effects
							(font
								(size 1.27 1.27)
							)
						)
					)
					(number "F25"
						(effects
							(font
								(size 1.27 1.27)
							)
						)
					)
				)
				(pin bidirectional line
					(at 0 -19.05 0)
					(length 5.08)
					(name "IO_L3N_T0_DQS_16"
						(effects
							(font
								(size 1.27 1.27)
							)
						)
					)
					(number "E25"
						(effects
							(font
								(size 1.27 1.27)
							)
						)
					)
				)
				(pin bidirectional line
					(at 0 -21.59 0)
					(length 5.08)
					(name "IO_L4P_T0_16"
						(effects
							(font
								(size 1.27 1.27)
							)
						)
					)
					(number "E24"
						(effects
							(font
								(size 1.27 1.27)
							)
						)
					)
				)
				(pin bidirectional line
					(at 0 -24.13 0)
					(length 5.08)
					(name "IO_L4N_T0_16"
						(effects
							(font
								(size 1.27 1.27)
							)
						)
					)
					(number "D24"
						(effects
							(font
								(size 1.27 1.27)
							)
						)
					)
				)
				(pin bidirectional line
					(at 0 -26.67 0)
					(length 5.08)
					(name "IO_L5P_T0_16"
						(effects
							(font
								(size 1.27 1.27)
							)
						)
					)
					(number "F26"
						(effects
							(font
								(size 1.27 1.27)
							)
						)
					)
				)
				(pin bidirectional line
					(at 0 -29.21 0)
					(length 5.08)
					(name "IO_L5N_T0_16"
						(effects
							(font
								(size 1.27 1.27)
							)
						)
					)
					(number "E26"
						(effects
							(font
								(size 1.27 1.27)
							)
						)
					)
				)
				(pin bidirectional line
					(at 0 -31.75 0)
					(length 5.08)
					(name "IO_L6P_T0_16"
						(effects
							(font
								(size 1.27 1.27)
							)
						)
					)
					(number "G23"
						(effects
							(font
								(size 1.27 1.27)
							)
						)
					)
				)
				(pin bidirectional line
					(at 0 -34.29 0)
					(length 5.08)
					(name "IO_L6N_T0_VREF_16"
						(effects
							(font
								(size 1.27 1.27)
							)
						)
					)
					(number "G24"
						(effects
							(font
								(size 1.27 1.27)
							)
						)
					)
				)
				(pin bidirectional line
					(at 0 -36.83 0)
					(length 5.08)
					(name "IO_L7P_T1_16"
						(effects
							(font
								(size 1.27 1.27)
							)
						)
					)
					(number "B27"
						(effects
							(font
								(size 1.27 1.27)
							)
						)
					)
				)
				(pin bidirectional line
					(at 0 -39.37 0)
					(length 5.08)
					(name "IO_L7N_T1_16"
						(effects
							(font
								(size 1.27 1.27)
							)
						)
					)
					(number "A27"
						(effects
							(font
								(size 1.27 1.27)
							)
						)
					)
				)
				(pin bidirectional line
					(at 0 -41.91 0)
					(length 5.08)
					(name "IO_L8P_T1_16"
						(effects
							(font
								(size 1.27 1.27)
							)
						)
					)
					(number "C24"
						(effects
							(font
								(size 1.27 1.27)
							)
						)
					)
				)
				(pin bidirectional line
					(at 0 -44.45 0)
					(length 5.08)
					(name "IO_L8N_T1_16"
						(effects
							(font
								(size 1.27 1.27)
							)
						)
					)
					(number "B24"
						(effects
							(font
								(size 1.27 1.27)
							)
						)
					)
				)
				(pin bidirectional line
					(at 0 -46.99 0)
					(length 5.08)
					(name "IO_L9P_T1_DQS_16"
						(effects
							(font
								(size 1.27 1.27)
							)
						)
					)
					(number "B28"
						(effects
							(font
								(size 1.27 1.27)
							)
						)
					)
				)
				(pin bidirectional line
					(at 0 -49.53 0)
					(length 5.08)
					(name "IO_L9N_T1_DQS_16"
						(effects
							(font
								(size 1.27 1.27)
							)
						)
					)
					(number "A28"
						(effects
							(font
								(size 1.27 1.27)
							)
						)
					)
				)
				(pin bidirectional line
					(at 0 -52.07 0)
					(length 5.08)
					(name "IO_L10P_T1_16"
						(effects
							(font
								(size 1.27 1.27)
							)
						)
					)
					(number "A25"
						(effects
							(font
								(size 1.27 1.27)
							)
						)
					)
				)
				(pin bidirectional line
					(at 0 -54.61 0)
					(length 5.08)
					(name "IO_L10N_T1_16"
						(effects
							(font
								(size 1.27 1.27)
							)
						)
					)
					(number "A26"
						(effects
							(font
								(size 1.27 1.27)
							)
						)
					)
				)
				(pin bidirectional line
					(at 0 -57.15 0)
					(length 5.08)
					(name "IO_L11P_T1_SRCC_16"
						(effects
							(font
								(size 1.27 1.27)
							)
						)
					)
					(number "D26"
						(effects
							(font
								(size 1.27 1.27)
							)
						)
					)
				)
				(pin bidirectional line
					(at 0 -59.69 0)
					(length 5.08)
					(name "IO_L11N_T1_SRCC_16"
						(effects
							(font
								(size 1.27 1.27)
							)
						)
					)
					(number "C26"
						(effects
							(font
								(size 1.27 1.27)
							)
						)
					)
				)
				(pin bidirectional line
					(at 0 -62.23 0)
					(length 5.08)
					(name "IO_L12P_T1_MRCC_16"
						(effects
							(font
								(size 1.27 1.27)
							)
						)
					)
					(number "C25"
						(effects
							(font
								(size 1.27 1.27)
							)
						)
					)
				)
				(pin bidirectional line
					(at 0 -64.77 0)
					(length 5.08)
					(name "IO_L12N_T1_MRCC_16"
						(effects
							(font
								(size 1.27 1.27)
							)
						)
					)
					(number "B25"
						(effects
							(font
								(size 1.27 1.27)
							)
						)
					)
				)
				(pin bidirectional line
					(at 0 -67.31 0)
					(length 5.08)
					(name "IO_L13P_T2_MRCC_16"
						(effects
							(font
								(size 1.27 1.27)
							)
						)
					)
					(number "D27"
						(effects
							(font
								(size 1.27 1.27)
							)
						)
					)
				)
				(pin bidirectional line
					(at 0 -69.85 0)
					(length 5.08)
					(name "IO_L13N_T2_MRCC_16"
						(effects
							(font
								(size 1.27 1.27)
							)
						)
					)
					(number "C27"
						(effects
							(font
								(size 1.27 1.27)
							)
						)
					)
				)
				(pin bidirectional line
					(at 0 -72.39 0)
					(length 5.08)
					(name "IO_L14P_T2_SRCC_16"
						(effects
							(font
								(size 1.27 1.27)
							)
						)
					)
					(number "E28"
						(effects
							(font
								(size 1.27 1.27)
							)
						)
					)
				)
				(pin bidirectional line
					(at 0 -74.93 0)
					(length 5.08)
					(name "IO_L14N_T2_SRCC_16"
						(effects
							(font
								(size 1.27 1.27)
							)
						)
					)
					(number "D28"
						(effects
							(font
								(size 1.27 1.27)
							)
						)
					)
				)
				(pin bidirectional line
					(at 0 -77.47 0)
					(length 5.08)
					(name "IO_L15P_T2_DQS_16"
						(effects
							(font
								(size 1.27 1.27)
							)
						)
					)
					(number "C29"
						(effects
							(font
								(size 1.27 1.27)
							)
						)
					)
				)
				(pin bidirectional line
					(at 0 -80.01 0)
					(length 5.08)
					(name "IO_L15N_T2_DQS_16"
						(effects
							(font
								(size 1.27 1.27)
							)
						)
					)
					(number "B29"
						(effects
							(font
								(size 1.27 1.27)
							)
						)
					)
				)
				(pin bidirectional line
					(at 0 -82.55 0)
					(length 5.08)
					(name "IO_L16P_T2_16"
						(effects
							(font
								(size 1.27 1.27)
							)
						)
					)
					(number "D29"
						(effects
							(font
								(size 1.27 1.27)
							)
						)
					)
				)
				(pin bidirectional line
					(at 0 -85.09 0)
					(length 5.08)
					(name "IO_L16N_T2_16"
						(effects
							(font
								(size 1.27 1.27)
							)
						)
					)
					(number "C30"
						(effects
							(font
								(size 1.27 1.27)
							)
						)
					)
				)
				(pin bidirectional line
					(at 0 -87.63 0)
					(length 5.08)
					(name "IO_L17P_T2_16"
						(effects
							(font
								(size 1.27 1.27)
							)
						)
					)
					(number "B30"
						(effects
							(font
								(size 1.27 1.27)
							)
						)
					)
				)
				(pin bidirectional line
					(at 0 -90.17 0)
					(length 5.08)
					(name "IO_L17N_T2_16"
						(effects
							(font
								(size 1.27 1.27)
							)
						)
					)
					(number "A30"
						(effects
							(font
								(size 1.27 1.27)
							)
						)
					)
				)
				(pin bidirectional line
					(at 0 -92.71 0)
					(length 5.08)
					(name "IO_L18P_T2_16"
						(effects
							(font
								(size 1.27 1.27)
							)
						)
					)
					(number "E29"
						(effects
							(font
								(size 1.27 1.27)
							)
						)
					)
				)
				(pin bidirectional line
					(at 0 -95.25 0)
					(length 5.08)
					(name "IO_L18N_T2_16"
						(effects
							(font
								(size 1.27 1.27)
							)
						)
					)
					(number "E30"
						(effects
							(font
								(size 1.27 1.27)
							)
						)
					)
				)
				(pin bidirectional line
					(at 0 -97.79 0)
					(length 5.08)
					(name "IO_L19P_T3_16"
						(effects
							(font
								(size 1.27 1.27)
							)
						)
					)
					(number "H24"
						(effects
							(font
								(size 1.27 1.27)
							)
						)
					)
				)
				(pin bidirectional line
					(at 0 -100.33 0)
					(length 5.08)
					(name "IO_L19N_T3_VREF_16"
						(effects
							(font
								(size 1.27 1.27)
							)
						)
					)
					(number "H25"
						(effects
							(font
								(size 1.27 1.27)
							)
						)
					)
				)
				(pin bidirectional line
					(at 0 -102.87 0)
					(length 5.08)
					(name "IO_L20P_T3_16"
						(effects
							(font
								(size 1.27 1.27)
							)
						)
					)
					(number "G28"
						(effects
							(font
								(size 1.27 1.27)
							)
						)
					)
				)
				(pin bidirectional line
					(at 0 -105.41 0)
					(length 5.08)
					(name "IO_L20N_T3_16"
						(effects
							(font
								(size 1.27 1.27)
							)
						)
					)
					(number "F28"
						(effects
							(font
								(size 1.27 1.27)
							)
						)
					)
				)
				(pin bidirectional line
					(at 0 -107.95 0)
					(length 5.08)
					(name "IO_L21P_T3_DQS_16"
						(effects
							(font
								(size 1.27 1.27)
							)
						)
					)
					(number "G27"
						(effects
							(font
								(size 1.27 1.27)
							)
						)
					)
				)
				(pin bidirectional line
					(at 0 -110.49 0)
					(length 5.08)
					(name "IO_L21N_T3_DQS_16"
						(effects
							(font
								(size 1.27 1.27)
							)
						)
					)
					(number "F27"
						(effects
							(font
								(size 1.27 1.27)
							)
						)
					)
				)
				(pin bidirectional line
					(at 0 -113.03 0)
					(length 5.08)
					(name "IO_L22P_T3_16"
						(effects
							(font
								(size 1.27 1.27)
							)
						)
					)
					(number "G29"
						(effects
							(font
								(size 1.27 1.27)
							)
						)
					)
				)
				(pin bidirectional line
					(at 0 -115.57 0)
					(length 5.08)
					(name "IO_L22N_T3_16"
						(effects
							(font
								(size 1.27 1.27)
							)
						)
					)
					(number "F30"
						(effects
							(font
								(size 1.27 1.27)
							)
						)
					)
				)
				(pin bidirectional line
					(at 0 -118.11 0)
					(length 5.08)
					(name "IO_L23P_T3_16"
						(effects
							(font
								(size 1.27 1.27)
							)
						)
					)
					(number "H26"
						(effects
							(font
								(size 1.27 1.27)
							)
						)
					)
				)
				(pin bidirectional line
					(at 0 -120.65 0)
					(length 5.08)
					(name "IO_L23N_T3_16"
						(effects
							(font
								(size 1.27 1.27)
							)
						)
					)
					(number "H27"
						(effects
							(font
								(size 1.27 1.27)
							)
						)
					)
				)
				(pin bidirectional line
					(at 0 -123.19 0)
					(length 5.08)
					(name "IO_L24P_T3_16"
						(effects
							(font
								(size 1.27 1.27)
							)
						)
					)
					(number "H30"
						(effects
							(font
								(size 1.27 1.27)
							)
						)
					)
				)
				(pin bidirectional line
					(at 0 -125.73 0)
					(length 5.08)
					(name "IO_L24N_T3_16"
						(effects
							(font
								(size 1.27 1.27)
							)
						)
					)
					(number "G30"
						(effects
							(font
								(size 1.27 1.27)
							)
						)
					)
				)
				(pin bidirectional line
					(at 0 -128.27 0)
					(length 5.08)
					(name "IO_25_16"
						(effects
							(font
								(size 1.27 1.27)
							)
						)
					)
					(number "G25"
						(effects
							(font
								(size 1.27 1.27)
							)
						)
					)
				)
				(pin bidirectional line
					(at 54.61 0 180)
					(length 5.08)
					(name "VCCO_17"
						(effects
							(font
								(size 1.27 1.27)
							)
						)
					)
					(number "A19"
						(effects
							(font
								(size 1.27 1.27)
							)
						)
					)
				)
				(pin passive line
					(at 54.61 0 180)
					(length 5.08)
					(hide yes)
					(name "VCCO_17"
						(effects
							(font
								(size 1.27 1.27)
							)
						)
					)
					(number "B16"
						(effects
							(font
								(size 1.27 1.27)
							)
						)
					)
				)
				(pin passive line
					(at 54.61 0 180)
					(length 5.08)
					(hide yes)
					(name "VCCO_17"
						(effects
							(font
								(size 1.27 1.27)
							)
						)
					)
					(number "D20"
						(effects
							(font
								(size 1.27 1.27)
							)
						)
					)
				)
				(pin passive line
					(at 54.61 0 180)
					(length 5.08)
					(hide yes)
					(name "VCCO_17"
						(effects
							(font
								(size 1.27 1.27)
							)
						)
					)
					(number "E17"
						(effects
							(font
								(size 1.27 1.27)
							)
						)
					)
				)
				(pin passive line
					(at 54.61 0 180)
					(length 5.08)
					(hide yes)
					(name "VCCO_17"
						(effects
							(font
								(size 1.27 1.27)
							)
						)
					)
					(number "G21"
						(effects
							(font
								(size 1.27 1.27)
							)
						)
					)
				)
				(pin passive line
					(at 54.61 0 180)
					(length 5.08)
					(hide yes)
					(name "VCCO_17"
						(effects
							(font
								(size 1.27 1.27)
							)
						)
					)
					(number "H18"
						(effects
							(font
								(size 1.27 1.27)
							)
						)
					)
				)
				(pin passive line
					(at 54.61 0 180)
					(length 5.08)
					(hide yes)
					(name "VCCO_17"
						(effects
							(font
								(size 1.27 1.27)
							)
						)
					)
					(number "L19"
						(effects
							(font
								(size 1.27 1.27)
							)
						)
					)
				)
				(pin bidirectional line
					(at 54.61 -3.81 180)
					(length 5.08)
					(name "IO_0_17"
						(effects
							(font
								(size 1.27 1.27)
							)
						)
					)
					(number "G19"
						(effects
							(font
								(size 1.27 1.27)
							)
						)
					)
				)
				(pin bidirectional line
					(at 54.61 -6.35 180)
					(length 5.08)
					(name "IO_L1P_T0_17"
						(effects
							(font
								(size 1.27 1.27)
							)
						)
					)
					(number "K18"
						(effects
							(font
								(size 1.27 1.27)
							)
						)
					)
				)
				(pin bidirectional line
					(at 54.61 -8.89 180)
					(length 5.08)
					(name "IO_L1N_T0_17"
						(effects
							(font
								(size 1.27 1.27)
							)
						)
					)
					(number "J18"
						(effects
							(font
								(size 1.27 1.27)
							)
						)
					)
				)
				(pin bidirectional line
					(at 54.61 -11.43 180)
					(length 5.08)
					(name "IO_L2P_T0_17"
						(effects
							(font
								(size 1.27 1.27)
							)
						)
					)
					(number "H20"
						(effects
							(font
								(size 1.27 1.27)
							)
						)
					)
				)
				(pin bidirectional line
					(at 54.61 -13.97 180)
					(length 5.08)
					(name "IO_L2N_T0_17"
						(effects
							(font
								(size 1.27 1.27)
							)
						)
					)
					(number "G20"
						(effects
							(font
								(size 1.27 1.27)
							)
						)
					)
				)
				(pin bidirectional line
					(at 54.61 -16.51 180)
					(length 5.08)
					(name "IO_L3P_T0_DQS_17"
						(effects
							(font
								(size 1.27 1.27)
							)
						)
					)
					(number "J17"
						(effects
							(font
								(size 1.27 1.27)
							)
						)
					)
				)
				(pin bidirectional line
					(at 54.61 -19.05 180)
					(length 5.08)
					(name "IO_L3N_T0_DQS_17"
						(effects
							(font
								(size 1.27 1.27)
							)
						)
					)
					(number "H17"
						(effects
							(font
								(size 1.27 1.27)
							)
						)
					)
				)
				(pin bidirectional line
					(at 54.61 -21.59 180)
					(length 5.08)
					(name "IO_L4P_T0_17"
						(effects
							(font
								(size 1.27 1.27)
							)
						)
					)
					(number "J19"
						(effects
							(font
								(size 1.27 1.27)
							)
						)
					)
				)
				(pin bidirectional line
					(at 54.61 -24.13 180)
					(length 5.08)
					(name "IO_L4N_T0_17"
						(effects
							(font
								(size 1.27 1.27)
							)
						)
					)
					(number "H19"
						(effects
							(font
								(size 1.27 1.27)
							)
						)
					)
				)
				(pin bidirectional line
					(at 54.61 -26.67 180)
					(length 5.08)
					(name "IO_L5P_T0_17"
						(effects
							(font
								(size 1.27 1.27)
							)
						)
					)
					(number "L17"
						(effects
							(font
								(size 1.27 1.27)
							)
						)
					)
				)
				(pin bidirectional line
					(at 54.61 -29.21 180)
					(length 5.08)
					(name "IO_L5N_T0_17"
						(effects
							(font
								(size 1.27 1.27)
							)
						)
					)
					(number "L18"
						(effects
							(font
								(size 1.27 1.27)
							)
						)
					)
				)
				(pin bidirectional line
					(at 54.61 -31.75 180)
					(length 5.08)
					(name "IO_L6P_T0_17"
						(effects
							(font
								(size 1.27 1.27)
							)
						)
					)
					(number "K19"
						(effects
							(font
								(size 1.27 1.27)
							)
						)
					)
				)
				(pin bidirectional line
					(at 54.61 -34.29 180)
					(length 5.08)
					(name "IO_L6N_T0_VREF_17"
						(effects
							(font
								(size 1.27 1.27)
							)
						)
					)
					(number "K20"
						(effects
							(font
								(size 1.27 1.27)
							)
						)
					)
				)
				(pin bidirectional line
					(at 54.61 -36.83 180)
					(length 5.08)
					(name "IO_L7P_T1_17"
						(effects
							(font
								(size 1.27 1.27)
							)
						)
					)
					(number "H21"
						(effects
							(font
								(size 1.27 1.27)
							)
						)
					)
				)
				(pin bidirectional line
					(at 54.61 -39.37 180)
					(length 5.08)
					(name "IO_L7N_T1_17"
						(effects
							(font
								(size 1.27 1.27)
							)
						)
					)
					(number "H22"
						(effects
							(font
								(size 1.27 1.27)
							)
						)
					)
				)
				(pin bidirectional line
					(at 54.61 -41.91 180)
					(length 5.08)
					(name "IO_L8P_T1_17"
						(effects
							(font
								(size 1.27 1.27)
							)
						)
					)
					(number "D21"
						(effects
							(font
								(size 1.27 1.27)
							)
						)
					)
				)
				(pin bidirectional line
					(at 54.61 -44.45 180)
					(length 5.08)
					(name "IO_L8N_T1_17"
						(effects
							(font
								(size 1.27 1.27)
							)
						)
					)
					(number "C21"
						(effects
							(font
								(size 1.27 1.27)
							)
						)
					)
				)
				(pin bidirectional line
					(at 54.61 -46.99 180)
					(length 5.08)
					(name "IO_L9P_T1_DQS_17"
						(effects
							(font
								(size 1.27 1.27)
							)
						)
					)
					(number "G22"
						(effects
							(font
								(size 1.27 1.27)
							)
						)
					)
				)
				(pin bidirectional line
					(at 54.61 -49.53 180)
					(length 5.08)
					(name "IO_L9N_T1_DQS_17"
						(effects
							(font
								(size 1.27 1.27)
							)
						)
					)
					(number "F22"
						(effects
							(font
								(size 1.27 1.27)
							)
						)
					)
				)
				(pin bidirectional line
					(at 54.61 -52.07 180)
					(length 5.08)
					(name "IO_L10P_T1_17"
						(effects
							(font
								(size 1.27 1.27)
							)
						)
					)
					(number "D22"
						(effects
							(font
								(size 1.27 1.27)
							)
						)
					)
				)
				(pin bidirectional line
					(at 54.61 -54.61 180)
					(length 5.08)
					(name "IO_L10N_T1_17"
						(effects
							(font
								(size 1.27 1.27)
							)
						)
					)
					(number "C22"
						(effects
							(font
								(size 1.27 1.27)
							)
						)
					)
				)
				(pin bidirectional line
					(at 54.61 -57.15 180)
					(length 5.08)
					(name "IO_L11P_T1_SRCC_17"
						(effects
							(font
								(size 1.27 1.27)
							)
						)
					)
					(number "F21"
						(effects
							(font
								(size 1.27 1.27)
							)
						)
					)
				)
				(pin bidirectional line
					(at 54.61 -59.69 180)
					(length 5.08)
					(name "IO_L11N_T1_SRCC_17"
						(effects
							(font
								(size 1.27 1.27)
							)
						)
					)
					(number "E21"
						(effects
							(font
								(size 1.27 1.27)
							)
						)
					)
				)
				(pin bidirectional line
					(at 54.61 -62.23 180)
					(length 5.08)
					(name "IO_L12P_T1_MRCC_17"
						(effects
							(font
								(size 1.27 1.27)
							)
						)
					)
					(number "F20"
						(effects
							(font
								(size 1.27 1.27)
							)
						)
					)
				)
				(pin bidirectional line
					(at 54.61 -64.77 180)
					(length 5.08)
					(name "IO_L12N_T1_MRCC_17"
						(effects
							(font
								(size 1.27 1.27)
							)
						)
					)
					(number "E20"
						(effects
							(font
								(size 1.27 1.27)
							)
						)
					)
				)
				(pin bidirectional line
					(at 54.61 -67.31 180)
					(length 5.08)
					(name "IO_L13P_T2_MRCC_17"
						(effects
							(font
								(size 1.27 1.27)
							)
						)
					)
					(number "D17"
						(effects
							(font
								(size 1.27 1.27)
							)
						)
					)
				)
				(pin bidirectional line
					(at 54.61 -69.85 180)
					(length 5.08)
					(name "IO_L13N_T2_MRCC_17"
						(effects
							(font
								(size 1.27 1.27)
							)
						)
					)
					(number "D18"
						(effects
							(font
								(size 1.27 1.27)
							)
						)
					)
				)
				(pin bidirectional line
					(at 54.61 -72.39 180)
					(length 5.08)
					(name "IO_L14P_T2_SRCC_17"
						(effects
							(font
								(size 1.27 1.27)
							)
						)
					)
					(number "E19"
						(effects
							(font
								(size 1.27 1.27)
							)
						)
					)
				)
				(pin bidirectional line
					(at 54.61 -74.93 180)
					(length 5.08)
					(name "IO_L14N_T2_SRCC_17"
						(effects
							(font
								(size 1.27 1.27)
							)
						)
					)
					(number "D19"
						(effects
							(font
								(size 1.27 1.27)
							)
						)
					)
				)
				(pin bidirectional line
					(at 54.61 -77.47 180)
					(length 5.08)
					(name "IO_L15P_T2_DQS_17"
						(effects
							(font
								(size 1.27 1.27)
							)
						)
					)
					(number "D16"
						(effects
							(font
								(size 1.27 1.27)
							)
						)
					)
				)
				(pin bidirectional line
					(at 54.61 -80.01 180)
					(length 5.08)
					(name "IO_L15N_T2_DQS_17"
						(effects
							(font
								(size 1.27 1.27)
							)
						)
					)
					(number "C16"
						(effects
							(font
								(size 1.27 1.27)
							)
						)
					)
				)
				(pin bidirectional line
					(at 54.61 -82.55 180)
					(length 5.08)
					(name "IO_L16P_T2_17"
						(effects
							(font
								(size 1.27 1.27)
							)
						)
					)
					(number "G18"
						(effects
							(font
								(size 1.27 1.27)
							)
						)
					)
				)
				(pin bidirectional line
					(at 54.61 -85.09 180)
					(length 5.08)
					(name "IO_L16N_T2_17"
						(effects
							(font
								(size 1.27 1.27)
							)
						)
					)
					(number "F18"
						(effects
							(font
								(size 1.27 1.27)
							)
						)
					)
				)
				(pin bidirectional line
					(at 54.61 -87.63 180)
					(length 5.08)
					(name "IO_L17P_T2_17"
						(effects
							(font
								(size 1.27 1.27)
							)
						)
					)
					(number "C17"
						(effects
							(font
								(size 1.27 1.27)
							)
						)
					)
				)
				(pin bidirectional line
					(at 54.61 -90.17 180)
					(length 5.08)
					(name "IO_L17N_T2_17"
						(effects
							(font
								(size 1.27 1.27)
							)
						)
					)
					(number "B17"
						(effects
							(font
								(size 1.27 1.27)
							)
						)
					)
				)
				(pin bidirectional line
					(at 54.61 -92.71 180)
					(length 5.08)
					(name "IO_L18P_T2_17"
						(effects
							(font
								(size 1.27 1.27)
							)
						)
					)
					(number "G17"
						(effects
							(font
								(size 1.27 1.27)
							)
						)
					)
				)
				(pin bidirectional line
					(at 54.61 -95.25 180)
					(length 5.08)
					(name "IO_L18N_T2_17"
						(effects
							(font
								(size 1.27 1.27)
							)
						)
					)
					(number "F17"
						(effects
							(font
								(size 1.27 1.27)
							)
						)
					)
				)
				(pin bidirectional line
					(at 54.61 -97.79 180)
					(length 5.08)
					(name "IO_L19P_T3_17"
						(effects
							(font
								(size 1.27 1.27)
							)
						)
					)
					(number "C20"
						(effects
							(font
								(size 1.27 1.27)
							)
						)
					)
				)
				(pin bidirectional line
					(at 54.61 -100.33 180)
					(length 5.08)
					(name "IO_L19N_T3_VREF_17"
						(effects
							(font
								(size 1.27 1.27)
							)
						)
					)
					(number "B20"
						(effects
							(font
								(size 1.27 1.27)
							)
						)
					)
				)
				(pin bidirectional line
					(at 54.61 -102.87 180)
					(length 5.08)
					(name "IO_L20P_T3_17"
						(effects
							(font
								(size 1.27 1.27)
							)
						)
					)
					(number "A16"
						(effects
							(font
								(size 1.27 1.27)
							)
						)
					)
				)
				(pin bidirectional line
					(at 54.61 -105.41 180)
					(length 5.08)
					(name "IO_L20N_T3_17"
						(effects
							(font
								(size 1.27 1.27)
							)
						)
					)
					(number "A17"
						(effects
							(font
								(size 1.27 1.27)
							)
						)
					)
				)
				(pin bidirectional line
					(at 54.61 -107.95 180)
					(length 5.08)
					(name "IO_L21P_T3_DQS_17"
						(effects
							(font
								(size 1.27 1.27)
							)
						)
					)
					(number "A20"
						(effects
							(font
								(size 1.27 1.27)
							)
						)
					)
				)
				(pin bidirectional line
					(at 54.61 -110.49 180)
					(length 5.08)
					(name "IO_L21N_T3_DQS_17"
						(effects
							(font
								(size 1.27 1.27)
							)
						)
					)
					(number "A21"
						(effects
							(font
								(size 1.27 1.27)
							)
						)
					)
				)
				(pin bidirectional line
					(at 54.61 -113.03 180)
					(length 5.08)
					(name "IO_L22P_T3_17"
						(effects
							(font
								(size 1.27 1.27)
							)
						)
					)
					(number "B18"
						(effects
							(font
								(size 1.27 1.27)
							)
						)
					)
				)
				(pin bidirectional line
					(at 54.61 -115.57 180)
					(length 5.08)
					(name "IO_L22N_T3_17"
						(effects
							(font
								(size 1.27 1.27)
							)
						)
					)
					(number "A18"
						(effects
							(font
								(size 1.27 1.27)
							)
						)
					)
				)
				(pin bidirectional line
					(at 54.61 -118.11 180)
					(length 5.08)
					(name "IO_L23P_T3_17"
						(effects
							(font
								(size 1.27 1.27)
							)
						)
					)
					(number "B22"
						(effects
							(font
								(size 1.27 1.27)
							)
						)
					)
				)
				(pin bidirectional line
					(at 54.61 -120.65 180)
					(length 5.08)
					(name "IO_L23N_T3_17"
						(effects
							(font
								(size 1.27 1.27)
							)
						)
					)
					(number "A22"
						(effects
							(font
								(size 1.27 1.27)
							)
						)
					)
				)
				(pin bidirectional line
					(at 54.61 -123.19 180)
					(length 5.08)
					(name "IO_L24P_T3_17"
						(effects
							(font
								(size 1.27 1.27)
							)
						)
					)
					(number "C19"
						(effects
							(font
								(size 1.27 1.27)
							)
						)
					)
				)
				(pin bidirectional line
					(at 54.61 -125.73 180)
					(length 5.08)
					(name "IO_L24N_T3_17"
						(effects
							(font
								(size 1.27 1.27)
							)
						)
					)
					(number "B19"
						(effects
							(font
								(size 1.27 1.27)
							)
						)
					)
				)
				(pin bidirectional line
					(at 54.61 -128.27 180)
					(length 5.08)
					(name "IO_25_17"
						(effects
							(font
								(size 1.27 1.27)
							)
						)
					)
					(number "E18"
						(effects
							(font
								(size 1.27 1.27)
							)
						)
					)
				)
			)
			(symbol "XC7K410T-2FFG900I_4_4_1"
				(rectangle
					(start 5.08 5.08)
					(end 48.26 -130.81)
					(stroke
						(width 0.254)
						(type default)
					)
					(fill
						(type background)
					)
				)
				(text "BANK 18"
					(at 17.78 2.54 0)
					(effects
						(font
							(size 1.27 1.27)
							(thickness 0.15)
						)
						(justify left bottom)
					)
				)
				(text "BANK 32"
					(at 29.21 2.54 0)
					(effects
						(font
							(size 1.27 1.27)
							(thickness 0.15)
						)
						(justify left bottom)
					)
				)
				(pin bidirectional line
					(at 0 0 0)
					(length 5.08)
					(name "VCCO_18"
						(effects
							(font
								(size 1.27 1.27)
							)
						)
					)
					(number "C13"
						(effects
							(font
								(size 1.27 1.27)
							)
						)
					)
				)
				(pin passive line
					(at 0 0 0)
					(length 5.08)
					(hide yes)
					(name "VCCO_18"
						(effects
							(font
								(size 1.27 1.27)
							)
						)
					)
					(number "D10"
						(effects
							(font
								(size 1.27 1.27)
							)
						)
					)
				)
				(pin passive line
					(at 0 0 0)
					(length 5.08)
					(hide yes)
					(name "VCCO_18"
						(effects
							(font
								(size 1.27 1.27)
							)
						)
					)
					(number "F14"
						(effects
							(font
								(size 1.27 1.27)
							)
						)
					)
				)
				(pin passive line
					(at 0 0 0)
					(length 5.08)
					(hide yes)
					(name "VCCO_18"
						(effects
							(font
								(size 1.27 1.27)
							)
						)
					)
					(number "G11"
						(effects
							(font
								(size 1.27 1.27)
							)
						)
					)
				)
				(pin passive line
					(at 0 0 0)
					(length 5.08)
					(hide yes)
					(name "VCCO_18"
						(effects
							(font
								(size 1.27 1.27)
							)
						)
					)
					(number "J15"
						(effects
							(font
								(size 1.27 1.27)
							)
						)
					)
				)
				(pin passive line
					(at 0 0 0)
					(length 5.08)
					(hide yes)
					(name "VCCO_18"
						(effects
							(font
								(size 1.27 1.27)
							)
						)
					)
					(number "K12"
						(effects
							(font
								(size 1.27 1.27)
							)
						)
					)
				)
				(pin bidirectional line
					(at 0 -3.81 0)
					(length 5.08)
					(name "IO_0_18"
						(effects
							(font
								(size 1.27 1.27)
							)
						)
					)
					(number "G12"
						(effects
							(font
								(size 1.27 1.27)
							)
						)
					)
				)
				(pin bidirectional line
					(at 0 -6.35 0)
					(length 5.08)
					(name "IO_L1P_T0_18"
						(effects
							(font
								(size 1.27 1.27)
							)
						)
					)
					(number "L16"
						(effects
							(font
								(size 1.27 1.27)
							)
						)
					)
				)
				(pin bidirectional line
					(at 0 -8.89 0)
					(length 5.08)
					(name "IO_L1N_T0_18"
						(effects
							(font
								(size 1.27 1.27)
							)
						)
					)
					(number "K16"
						(effects
							(font
								(size 1.27 1.27)
							)
						)
					)
				)
				(pin bidirectional line
					(at 0 -11.43 0)
					(length 5.08)
					(name "IO_L2P_T0_18"
						(effects
							(font
								(size 1.27 1.27)
							)
						)
					)
					(number "L15"
						(effects
							(font
								(size 1.27 1.27)
							)
						)
					)
				)
				(pin bidirectional line
					(at 0 -13.97 0)
					(length 5.08)
					(name "IO_L2N_T0_18"
						(effects
							(font
								(size 1.27 1.27)
							)
						)
					)
					(number "K15"
						(effects
							(font
								(size 1.27 1.27)
							)
						)
					)
				)
				(pin bidirectional line
					(at 0 -16.51 0)
					(length 5.08)
					(name "IO_L3P_T0_DQS_18"
						(effects
							(font
								(size 1.27 1.27)
							)
						)
					)
					(number "L12"
						(effects
							(font
								(size 1.27 1.27)
							)
						)
					)
				)
				(pin bidirectional line
					(at 0 -19.05 0)
					(length 5.08)
					(name "IO_L3N_T0_DQS_18"
						(effects
							(font
								(size 1.27 1.27)
							)
						)
					)
					(number "L13"
						(effects
							(font
								(size 1.27 1.27)
							)
						)
					)
				)
				(pin bidirectional line
					(at 0 -21.59 0)
					(length 5.08)
					(name "IO_L4P_T0_18"
						(effects
							(font
								(size 1.27 1.27)
							)
						)
					)
					(number "K13"
						(effects
							(font
								(size 1.27 1.27)
							)
						)
					)
				)
				(pin bidirectional line
					(at 0 -24.13 0)
					(length 5.08)
					(name "IO_L4N_T0_18"
						(effects
							(font
								(size 1.27 1.27)
							)
						)
					)
					(number "J13"
						(effects
							(font
								(size 1.27 1.27)
							)
						)
					)
				)
				(pin bidirectional line
					(at 0 -26.67 0)
					(length 5.08)
					(name "IO_L5P_T0_18"
						(effects
							(font
								(size 1.27 1.27)
							)
						)
					)
					(number "K14"
						(effects
							(font
								(size 1.27 1.27)
							)
						)
					)
				)
				(pin bidirectional line
					(at 0 -29.21 0)
					(length 5.08)
					(name "IO_L5N_T0_18"
						(effects
							(font
								(size 1.27 1.27)
							)
						)
					)
					(number "J14"
						(effects
							(font
								(size 1.27 1.27)
							)
						)
					)
				)
				(pin bidirectional line
					(at 0 -31.75 0)
					(length 5.08)
					(name "IO_L6P_T0_18"
						(effects
							(font
								(size 1.27 1.27)
							)
						)
					)
					(number "L11"
						(effects
							(font
								(size 1.27 1.27)
							)
						)
					)
				)
				(pin bidirectional line
					(at 0 -34.29 0)
					(length 5.08)
					(name "IO_L6N_T0_VREF_18"
						(effects
							(font
								(size 1.27 1.27)
							)
						)
					)
					(number "K11"
						(effects
							(font
								(size 1.27 1.27)
							)
						)
					)
				)
				(pin bidirectional line
					(at 0 -36.83 0)
					(length 5.08)
					(name "IO_L7P_T1_18"
						(effects
							(font
								(size 1.27 1.27)
							)
						)
					)
					(number "H15"
						(effects
							(font
								(size 1.27 1.27)
							)
						)
					)
				)
				(pin bidirectional line
					(at 0 -39.37 0)
					(length 5.08)
					(name "IO_L7N_T1_18"
						(effects
							(font
								(size 1.27 1.27)
							)
						)
					)
					(number "G15"
						(effects
							(font
								(size 1.27 1.27)
							)
						)
					)
				)
				(pin bidirectional line
					(at 0 -41.91 0)
					(length 5.08)
					(name "IO_L8P_T1_18"
						(effects
							(font
								(size 1.27 1.27)
							)
						)
					)
					(number "J11"
						(effects
							(font
								(size 1.27 1.27)
							)
						)
					)
				)
				(pin bidirectional line
					(at 0 -44.45 0)
					(length 5.08)
					(name "IO_L8N_T1_18"
						(effects
							(font
								(size 1.27 1.27)
							)
						)
					)
					(number "J12"
						(effects
							(font
								(size 1.27 1.27)
							)
						)
					)
				)
				(pin bidirectional line
					(at 0 -46.99 0)
					(length 5.08)
					(name "IO_L9P_T1_DQS_18"
						(effects
							(font
								(size 1.27 1.27)
							)
						)
					)
					(number "J16"
						(effects
							(font
								(size 1.27 1.27)
							)
						)
					)
				)
				(pin bidirectional line
					(at 0 -49.53 0)
					(length 5.08)
					(name "IO_L9N_T1_DQS_18"
						(effects
							(font
								(size 1.27 1.27)
							)
						)
					)
					(number "H16"
						(effects
							(font
								(size 1.27 1.27)
							)
						)
					)
				)
				(pin bidirectional line
					(at 0 -52.07 0)
					(length 5.08)
					(name "IO_L10P_T1_18"
						(effects
							(font
								(size 1.27 1.27)
							)
						)
					)
					(number "H11"
						(effects
							(font
								(size 1.27 1.27)
							)
						)
					)
				)
				(pin bidirectional line
					(at 0 -54.61 0)
					(length 5.08)
					(name "IO_L10N_T1_18"
						(effects
							(font
								(size 1.27 1.27)
							)
						)
					)
					(number "H12"
						(effects
							(font
								(size 1.27 1.27)
							)
						)
					)
				)
				(pin bidirectional line
					(at 0 -57.15 0)
					(length 5.08)
					(name "IO_L11P_T1_SRCC_18"
						(effects
							(font
								(size 1.27 1.27)
							)
						)
					)
					(number "H14"
						(effects
							(font
								(size 1.27 1.27)
							)
						)
					)
				)
				(pin bidirectional line
					(at 0 -59.69 0)
					(length 5.08)
					(name "IO_L11N_T1_SRCC_18"
						(effects
							(font
								(size 1.27 1.27)
							)
						)
					)
					(number "G14"
						(effects
							(font
								(size 1.27 1.27)
							)
						)
					)
				)
				(pin bidirectional line
					(at 0 -62.23 0)
					(length 5.08)
					(name "IO_L12P_T1_MRCC_18"
						(effects
							(font
								(size 1.27 1.27)
							)
						)
					)
					(number "G13"
						(effects
							(font
								(size 1.27 1.27)
							)
						)
					)
				)
				(pin bidirectional line
					(at 0 -64.77 0)
					(length 5.08)
					(name "IO_L12N_T1_MRCC_18"
						(effects
							(font
								(size 1.27 1.27)
							)
						)
					)
					(number "F13"
						(effects
							(font
								(size 1.27 1.27)
							)
						)
					)
				)
				(pin bidirectional line
					(at 0 -67.31 0)
					(length 5.08)
					(name "IO_L13P_T2_MRCC_18"
						(effects
							(font
								(size 1.27 1.27)
							)
						)
					)
					(number "D12"
						(effects
							(font
								(size 1.27 1.27)
							)
						)
					)
				)
				(pin bidirectional line
					(at 0 -69.85 0)
					(length 5.08)
					(name "IO_L13N_T2_MRCC_18"
						(effects
							(font
								(size 1.27 1.27)
							)
						)
					)
					(number "D13"
						(effects
							(font
								(size 1.27 1.27)
							)
						)
					)
				)
				(pin bidirectional line
					(at 0 -72.39 0)
					(length 5.08)
					(name "IO_L14P_T2_SRCC_18"
						(effects
							(font
								(size 1.27 1.27)
							)
						)
					)
					(number "F12"
						(effects
							(font
								(size 1.27 1.27)
							)
						)
					)
				)
				(pin bidirectional line
					(at 0 -74.93 0)
					(length 5.08)
					(name "IO_L14N_T2_SRCC_18"
						(effects
							(font
								(size 1.27 1.27)
							)
						)
					)
					(number "E13"
						(effects
							(font
								(size 1.27 1.27)
							)
						)
					)
				)
				(pin bidirectional line
					(at 0 -77.47 0)
					(length 5.08)
					(name "IO_L15P_T2_DQS_18"
						(effects
							(font
								(size 1.27 1.27)
							)
						)
					)
					(number "C12"
						(effects
							(font
								(size 1.27 1.27)
							)
						)
					)
				)
				(pin bidirectional line
					(at 0 -80.01 0)
					(length 5.08)
					(name "IO_L15N_T2_DQS_18"
						(effects
							(font
								(size 1.27 1.27)
							)
						)
					)
					(number "B12"
						(effects
							(font
								(size 1.27 1.27)
							)
						)
					)
				)
				(pin bidirectional line
					(at 0 -82.55 0)
					(length 5.08)
					(name "IO_L16P_T2_18"
						(effects
							(font
								(size 1.27 1.27)
							)
						)
					)
					(number "F11"
						(effects
							(font
								(size 1.27 1.27)
							)
						)
					)
				)
				(pin bidirectional line
					(at 0 -85.09 0)
					(length 5.08)
					(name "IO_L16N_T2_18"
						(effects
							(font
								(size 1.27 1.27)
							)
						)
					)
					(number "E11"
						(effects
							(font
								(size 1.27 1.27)
							)
						)
					)
				)
				(pin bidirectional line
					(at 0 -87.63 0)
					(length 5.08)
					(name "IO_L17P_T2_18"
						(effects
							(font
								(size 1.27 1.27)
							)
						)
					)
					(number "A11"
						(effects
							(font
								(size 1.27 1.27)
							)
						)
					)
				)
				(pin bidirectional line
					(at 0 -90.17 0)
					(length 5.08)
					(name "IO_L17N_T2_18"
						(effects
							(font
								(size 1.27 1.27)
							)
						)
					)
					(number "A12"
						(effects
							(font
								(size 1.27 1.27)
							)
						)
					)
				)
				(pin bidirectional line
					(at 0 -92.71 0)
					(length 5.08)
					(name "IO_L18P_T2_18"
						(effects
							(font
								(size 1.27 1.27)
							)
						)
					)
					(number "D11"
						(effects
							(font
								(size 1.27 1.27)
							)
						)
					)
				)
				(pin bidirectional line
					(at 0 -95.25 0)
					(length 5.08)
					(name "IO_L18N_T2_18"
						(effects
							(font
								(size 1.27 1.27)
							)
						)
					)
					(number "C11"
						(effects
							(font
								(size 1.27 1.27)
							)
						)
					)
				)
				(pin bidirectional line
					(at 0 -97.79 0)
					(length 5.08)
					(name "IO_L19P_T3_18"
						(effects
							(font
								(size 1.27 1.27)
							)
						)
					)
					(number "F15"
						(effects
							(font
								(size 1.27 1.27)
							)
						)
					)
				)
				(pin bidirectional line
					(at 0 -100.33 0)
					(length 5.08)
					(name "IO_L19N_T3_VREF_18"
						(effects
							(font
								(size 1.27 1.27)
							)
						)
					)
					(number "E16"
						(effects
							(font
								(size 1.27 1.27)
							)
						)
					)
				)
				(pin bidirectional line
					(at 0 -102.87 0)
					(length 5.08)
					(name "IO_L20P_T3_18"
						(effects
							(font
								(size 1.27 1.27)
							)
						)
					)
					(number "E14"
						(effects
							(font
								(size 1.27 1.27)
							)
						)
					)
				)
				(pin bidirectional line
					(at 0 -105.41 0)
					(length 5.08)
					(name "IO_L20N_T3_18"
						(effects
							(font
								(size 1.27 1.27)
							)
						)
					)
					(number "E15"
						(effects
							(font
								(size 1.27 1.27)
							)
						)
					)
				)
				(pin bidirectional line
					(at 0 -107.95 0)
					(length 5.08)
					(name "IO_L21P_T3_DQS_18"
						(effects
							(font
								(size 1.27 1.27)
							)
						)
					)
					(number "D14"
						(effects
							(font
								(size 1.27 1.27)
							)
						)
					)
				)
				(pin bidirectional line
					(at 0 -110.49 0)
					(length 5.08)
					(name "IO_L21N_T3_DQS_18"
						(effects
							(font
								(size 1.27 1.27)
							)
						)
					)
					(number "C14"
						(effects
							(font
								(size 1.27 1.27)
							)
						)
					)
				)
				(pin bidirectional line
					(at 0 -113.03 0)
					(length 5.08)
					(name "IO_L22P_T3_18"
						(effects
							(font
								(size 1.27 1.27)
							)
						)
					)
					(number "B13"
						(effects
							(font
								(size 1.27 1.27)
							)
						)
					)
				)
				(pin bidirectional line
					(at 0 -115.57 0)
					(length 5.08)
					(name "IO_L22N_T3_18"
						(effects
							(font
								(size 1.27 1.27)
							)
						)
					)
					(number "A13"
						(effects
							(font
								(size 1.27 1.27)
							)
						)
					)
				)
				(pin bidirectional line
					(at 0 -118.11 0)
					(length 5.08)
					(name "IO_L23P_T3_18"
						(effects
							(font
								(size 1.27 1.27)
							)
						)
					)
					(number "C15"
						(effects
							(font
								(size 1.27 1.27)
							)
						)
					)
				)
				(pin bidirectional line
					(at 0 -120.65 0)
					(length 5.08)
					(name "IO_L23N_T3_18"
						(effects
							(font
								(size 1.27 1.27)
							)
						)
					)
					(number "B15"
						(effects
							(font
								(size 1.27 1.27)
							)
						)
					)
				)
				(pin bidirectional line
					(at 0 -123.19 0)
					(length 5.08)
					(name "IO_L24P_T3_18"
						(effects
							(font
								(size 1.27 1.27)
							)
						)
					)
					(number "B14"
						(effects
							(font
								(size 1.27 1.27)
							)
						)
					)
				)
				(pin bidirectional line
					(at 0 -125.73 0)
					(length 5.08)
					(name "IO_L24N_T3_18"
						(effects
							(font
								(size 1.27 1.27)
							)
						)
					)
					(number "A15"
						(effects
							(font
								(size 1.27 1.27)
							)
						)
					)
				)
				(pin bidirectional line
					(at 0 -128.27 0)
					(length 5.08)
					(name "IO_25_18"
						(effects
							(font
								(size 1.27 1.27)
							)
						)
					)
					(number "F16"
						(effects
							(font
								(size 1.27 1.27)
							)
						)
					)
				)
				(pin bidirectional line
					(at 53.34 0 180)
					(length 5.08)
					(name "VCCO_32"
						(effects
							(font
								(size 1.27 1.27)
							)
						)
					)
					(number "AA19"
						(effects
							(font
								(size 1.27 1.27)
							)
						)
					)
				)
				(pin passive line
					(at 53.34 0 180)
					(length 5.08)
					(hide yes)
					(name "VCCO_32"
						(effects
							(font
								(size 1.27 1.27)
							)
						)
					)
					(number "AB16"
						(effects
							(font
								(size 1.27 1.27)
							)
						)
					)
				)
				(pin passive line
					(at 53.34 0 180)
					(length 5.08)
					(hide yes)
					(name "VCCO_32"
						(effects
							(font
								(size 1.27 1.27)
							)
						)
					)
					(number "AE17"
						(effects
							(font
								(size 1.27 1.27)
							)
						)
					)
				)
				(pin passive line
					(at 53.34 0 180)
					(length 5.08)
					(hide yes)
					(name "VCCO_32"
						(effects
							(font
								(size 1.27 1.27)
							)
						)
					)
					(number "AF14"
						(effects
							(font
								(size 1.27 1.27)
							)
						)
					)
				)
				(pin passive line
					(at 53.34 0 180)
					(length 5.08)
					(hide yes)
					(name "VCCO_32"
						(effects
							(font
								(size 1.27 1.27)
							)
						)
					)
					(number "AH18"
						(effects
							(font
								(size 1.27 1.27)
							)
						)
					)
				)
				(pin passive line
					(at 53.34 0 180)
					(length 5.08)
					(hide yes)
					(name "VCCO_32"
						(effects
							(font
								(size 1.27 1.27)
							)
						)
					)
					(number "AJ15"
						(effects
							(font
								(size 1.27 1.27)
							)
						)
					)
				)
				(pin bidirectional line
					(at 53.34 -3.81 180)
					(length 5.08)
					(name "IO_0_VRN_32"
						(effects
							(font
								(size 1.27 1.27)
							)
						)
					)
					(number "Y14"
						(effects
							(font
								(size 1.27 1.27)
							)
						)
					)
				)
				(pin bidirectional line
					(at 53.34 -6.35 180)
					(length 5.08)
					(name "IO_L1P_T0_32"
						(effects
							(font
								(size 1.27 1.27)
							)
						)
					)
					(number "AK16"
						(effects
							(font
								(size 1.27 1.27)
							)
						)
					)
				)
				(pin bidirectional line
					(at 53.34 -8.89 180)
					(length 5.08)
					(name "IO_L1N_T0_32"
						(effects
							(font
								(size 1.27 1.27)
							)
						)
					)
					(number "AK15"
						(effects
							(font
								(size 1.27 1.27)
							)
						)
					)
				)
				(pin bidirectional line
					(at 53.34 -11.43 180)
					(length 5.08)
					(name "IO_L2P_T0_32"
						(effects
							(font
								(size 1.27 1.27)
							)
						)
					)
					(number "AG15"
						(effects
							(font
								(size 1.27 1.27)
							)
						)
					)
				)
				(pin bidirectional line
					(at 53.34 -13.97 180)
					(length 5.08)
					(name "IO_L2N_T0_32"
						(effects
							(font
								(size 1.27 1.27)
							)
						)
					)
					(number "AH15"
						(effects
							(font
								(size 1.27 1.27)
							)
						)
					)
				)
				(pin bidirectional line
					(at 53.34 -16.51 180)
					(length 5.08)
					(name "IO_L3P_T0_DQS_32"
						(effects
							(font
								(size 1.27 1.27)
							)
						)
					)
					(number "AH16"
						(effects
							(font
								(size 1.27 1.27)
							)
						)
					)
				)
				(pin bidirectional line
					(at 53.34 -19.05 180)
					(length 5.08)
					(name "IO_L3N_T0_DQS_32"
						(effects
							(font
								(size 1.27 1.27)
							)
						)
					)
					(number "AJ16"
						(effects
							(font
								(size 1.27 1.27)
							)
						)
					)
				)
				(pin bidirectional line
					(at 53.34 -21.59 180)
					(length 5.08)
					(name "IO_L4P_T0_32"
						(effects
							(font
								(size 1.27 1.27)
							)
						)
					)
					(number "AF15"
						(effects
							(font
								(size 1.27 1.27)
							)
						)
					)
				)
				(pin bidirectional line
					(at 53.34 -24.13 180)
					(length 5.08)
					(name "IO_L4N_T0_32"
						(effects
							(font
								(size 1.27 1.27)
							)
						)
					)
					(number "AG14"
						(effects
							(font
								(size 1.27 1.27)
							)
						)
					)
				)
				(pin bidirectional line
					(at 53.34 -26.67 180)
					(length 5.08)
					(name "IO_L5P_T0_32"
						(effects
							(font
								(size 1.27 1.27)
							)
						)
					)
					(number "AH17"
						(effects
							(font
								(size 1.27 1.27)
							)
						)
					)
				)
				(pin bidirectional line
					(at 53.34 -29.21 180)
					(length 5.08)
					(name "IO_L5N_T0_32"
						(effects
							(font
								(size 1.27 1.27)
							)
						)
					)
					(number "AJ17"
						(effects
							(font
								(size 1.27 1.27)
							)
						)
					)
				)
				(pin bidirectional line
					(at 53.34 -31.75 180)
					(length 5.08)
					(name "IO_L6P_T0_32"
						(effects
							(font
								(size 1.27 1.27)
							)
						)
					)
					(number "AE16"
						(effects
							(font
								(size 1.27 1.27)
							)
						)
					)
				)
				(pin bidirectional line
					(at 53.34 -34.29 180)
					(length 5.08)
					(name "IO_L6N_T0_VREF_32"
						(effects
							(font
								(size 1.27 1.27)
							)
						)
					)
					(number "AF16"
						(effects
							(font
								(size 1.27 1.27)
							)
						)
					)
				)
				(pin bidirectional line
					(at 53.34 -36.83 180)
					(length 5.08)
					(name "IO_L7P_T1_32"
						(effects
							(font
								(size 1.27 1.27)
							)
						)
					)
					(number "AJ19"
						(effects
							(font
								(size 1.27 1.27)
							)
						)
					)
				)
				(pin bidirectional line
					(at 53.34 -39.37 180)
					(length 5.08)
					(name "IO_L7N_T1_32"
						(effects
							(font
								(size 1.27 1.27)
							)
						)
					)
					(number "AK19"
						(effects
							(font
								(size 1.27 1.27)
							)
						)
					)
				)
				(pin bidirectional line
					(at 53.34 -41.91 180)
					(length 5.08)
					(name "IO_L8P_T1_32"
						(effects
							(font
								(size 1.27 1.27)
							)
						)
					)
					(number "AG19"
						(effects
							(font
								(size 1.27 1.27)
							)
						)
					)
				)
				(pin bidirectional line
					(at 53.34 -44.45 180)
					(length 5.08)
					(name "IO_L8N_T1_32"
						(effects
							(font
								(size 1.27 1.27)
							)
						)
					)
					(number "AH19"
						(effects
							(font
								(size 1.27 1.27)
							)
						)
					)
				)
				(pin bidirectional line
					(at 53.34 -46.99 180)
					(length 5.08)
					(name "IO_L9P_T1_DQS_32"
						(effects
							(font
								(size 1.27 1.27)
							)
						)
					)
					(number "AJ18"
						(effects
							(font
								(size 1.27 1.27)
							)
						)
					)
				)
				(pin bidirectional line
					(at 53.34 -49.53 180)
					(length 5.08)
					(name "IO_L9N_T1_DQS_32"
						(effects
							(font
								(size 1.27 1.27)
							)
						)
					)
					(number "AK18"
						(effects
							(font
								(size 1.27 1.27)
							)
						)
					)
				)
				(pin bidirectional line
					(at 53.34 -52.07 180)
					(length 5.08)
					(name "IO_L10P_T1_32"
						(effects
							(font
								(size 1.27 1.27)
							)
						)
					)
					(number "AD19"
						(effects
							(font
								(size 1.27 1.27)
							)
						)
					)
				)
				(pin bidirectional line
					(at 53.34 -54.61 180)
					(length 5.08)
					(name "IO_L10N_T1_32"
						(effects
							(font
								(size 1.27 1.27)
							)
						)
					)
					(number "AE19"
						(effects
							(font
								(size 1.27 1.27)
							)
						)
					)
				)
				(pin bidirectional line
					(at 53.34 -57.15 180)
					(length 5.08)
					(name "IO_L11P_T1_SRCC_32"
						(effects
							(font
								(size 1.27 1.27)
							)
						)
					)
					(number "AF18"
						(effects
							(font
								(size 1.27 1.27)
							)
						)
					)
				)
				(pin bidirectional line
					(at 53.34 -59.69 180)
					(length 5.08)
					(name "IO_L11N_T1_SRCC_32"
						(effects
							(font
								(size 1.27 1.27)
							)
						)
					)
					(number "AG18"
						(effects
							(font
								(size 1.27 1.27)
							)
						)
					)
				)
				(pin bidirectional line
					(at 53.34 -62.23 180)
					(length 5.08)
					(name "IO_L12P_T1_MRCC_32"
						(effects
							(font
								(size 1.27 1.27)
							)
						)
					)
					(number "AF17"
						(effects
							(font
								(size 1.27 1.27)
							)
						)
					)
				)
				(pin bidirectional line
					(at 53.34 -64.77 180)
					(length 5.08)
					(name "IO_L12N_T1_MRCC_32"
						(effects
							(font
								(size 1.27 1.27)
							)
						)
					)
					(number "AG17"
						(effects
							(font
								(size 1.27 1.27)
							)
						)
					)
				)
				(pin bidirectional line
					(at 53.34 -67.31 180)
					(length 5.08)
					(name "IO_L13P_T2_MRCC_32"
						(effects
							(font
								(size 1.27 1.27)
							)
						)
					)
					(number "AD18"
						(effects
							(font
								(size 1.27 1.27)
							)
						)
					)
				)
				(pin bidirectional line
					(at 53.34 -69.85 180)
					(length 5.08)
					(name "IO_L13N_T2_MRCC_32"
						(effects
							(font
								(size 1.27 1.27)
							)
						)
					)
					(number "AE18"
						(effects
							(font
								(size 1.27 1.27)
							)
						)
					)
				)
				(pin bidirectional line
					(at 53.34 -72.39 180)
					(length 5.08)
					(name "IO_L14P_T2_SRCC_32"
						(effects
							(font
								(size 1.27 1.27)
							)
						)
					)
					(number "AD17"
						(effects
							(font
								(size 1.27 1.27)
							)
						)
					)
				)
				(pin bidirectional line
					(at 53.34 -74.93 180)
					(length 5.08)
					(name "IO_L14N_T2_SRCC_32"
						(effects
							(font
								(size 1.27 1.27)
							)
						)
					)
					(number "AD16"
						(effects
							(font
								(size 1.27 1.27)
							)
						)
					)
				)
				(pin bidirectional line
					(at 53.34 -77.47 180)
					(length 5.08)
					(name "IO_L15P_T2_DQS_32"
						(effects
							(font
								(size 1.27 1.27)
							)
						)
					)
					(number "Y19"
						(effects
							(font
								(size 1.27 1.27)
							)
						)
					)
				)
				(pin bidirectional line
					(at 53.34 -80.01 180)
					(length 5.08)
					(name "IO_L15N_T2_DQS_32"
						(effects
							(font
								(size 1.27 1.27)
							)
						)
					)
					(number "Y18"
						(effects
							(font
								(size 1.27 1.27)
							)
						)
					)
				)
				(pin bidirectional line
					(at 53.34 -82.55 180)
					(length 5.08)
					(name "IO_L16P_T2_32"
						(effects
							(font
								(size 1.27 1.27)
							)
						)
					)
					(number "AA18"
						(effects
							(font
								(size 1.27 1.27)
							)
						)
					)
				)
				(pin bidirectional line
					(at 53.34 -85.09 180)
					(length 5.08)
					(name "IO_L16N_T2_32"
						(effects
							(font
								(size 1.27 1.27)
							)
						)
					)
					(number "AB18"
						(effects
							(font
								(size 1.27 1.27)
							)
						)
					)
				)
				(pin bidirectional line
					(at 53.34 -87.63 180)
					(length 5.08)
					(name "IO_L17P_T2_32"
						(effects
							(font
								(size 1.27 1.27)
							)
						)
					)
					(number "AB19"
						(effects
							(font
								(size 1.27 1.27)
							)
						)
					)
				)
				(pin bidirectional line
					(at 53.34 -90.17 180)
					(length 5.08)
					(name "IO_L17N_T2_32"
						(effects
							(font
								(size 1.27 1.27)
							)
						)
					)
					(number "AC19"
						(effects
							(font
								(size 1.27 1.27)
							)
						)
					)
				)
				(pin bidirectional line
					(at 53.34 -92.71 180)
					(length 5.08)
					(name "IO_L18P_T2_32"
						(effects
							(font
								(size 1.27 1.27)
							)
						)
					)
					(number "AB17"
						(effects
							(font
								(size 1.27 1.27)
							)
						)
					)
				)
				(pin bidirectional line
					(at 53.34 -95.25 180)
					(length 5.08)
					(name "IO_L18N_T2_32"
						(effects
							(font
								(size 1.27 1.27)
							)
						)
					)
					(number "AC17"
						(effects
							(font
								(size 1.27 1.27)
							)
						)
					)
				)
				(pin bidirectional line
					(at 53.34 -97.79 180)
					(length 5.08)
					(name "IO_L19P_T3_32"
						(effects
							(font
								(size 1.27 1.27)
							)
						)
					)
					(number "AE15"
						(effects
							(font
								(size 1.27 1.27)
							)
						)
					)
				)
				(pin bidirectional line
					(at 53.34 -100.33 180)
					(length 5.08)
					(name "IO_L19N_T3_VREF_32"
						(effects
							(font
								(size 1.27 1.27)
							)
						)
					)
					(number "AE14"
						(effects
							(font
								(size 1.27 1.27)
							)
						)
					)
				)
				(pin bidirectional line
					(at 53.34 -102.87 180)
					(length 5.08)
					(name "IO_L20P_T3_32"
						(effects
							(font
								(size 1.27 1.27)
							)
						)
					)
					(number "AA15"
						(effects
							(font
								(size 1.27 1.27)
							)
						)
					)
				)
				(pin bidirectional line
					(at 53.34 -105.41 180)
					(length 5.08)
					(name "IO_L20N_T3_32"
						(effects
							(font
								(size 1.27 1.27)
							)
						)
					)
					(number "AB15"
						(effects
							(font
								(size 1.27 1.27)
							)
						)
					)
				)
				(pin bidirectional line
					(at 53.34 -107.95 180)
					(length 5.08)
					(name "IO_L21P_T3_DQS_32"
						(effects
							(font
								(size 1.27 1.27)
							)
						)
					)
					(number "AC16"
						(effects
							(font
								(size 1.27 1.27)
							)
						)
					)
				)
				(pin bidirectional line
					(at 53.34 -110.49 180)
					(length 5.08)
					(name "IO_L21N_T3_DQS_32"
						(effects
							(font
								(size 1.27 1.27)
							)
						)
					)
					(number "AC15"
						(effects
							(font
								(size 1.27 1.27)
							)
						)
					)
				)
				(pin bidirectional line
					(at 53.34 -113.03 180)
					(length 5.08)
					(name "IO_L22P_T3_32"
						(effects
							(font
								(size 1.27 1.27)
							)
						)
					)
					(number "AC14"
						(effects
							(font
								(size 1.27 1.27)
							)
						)
					)
				)
				(pin bidirectional line
					(at 53.34 -115.57 180)
					(length 5.08)
					(name "IO_L22N_T3_32"
						(effects
							(font
								(size 1.27 1.27)
							)
						)
					)
					(number "AD14"
						(effects
							(font
								(size 1.27 1.27)
							)
						)
					)
				)
				(pin bidirectional line
					(at 53.34 -118.11 180)
					(length 5.08)
					(name "IO_L23P_T3_32"
						(effects
							(font
								(size 1.27 1.27)
							)
						)
					)
					(number "AA17"
						(effects
							(font
								(size 1.27 1.27)
							)
						)
					)
				)
				(pin bidirectional line
					(at 53.34 -120.65 180)
					(length 5.08)
					(name "IO_L23N_T3_32"
						(effects
							(font
								(size 1.27 1.27)
							)
						)
					)
					(number "AA16"
						(effects
							(font
								(size 1.27 1.27)
							)
						)
					)
				)
				(pin bidirectional line
					(at 53.34 -123.19 180)
					(length 5.08)
					(name "IO_L24P_T3_32"
						(effects
							(font
								(size 1.27 1.27)
							)
						)
					)
					(number "Y16"
						(effects
							(font
								(size 1.27 1.27)
							)
						)
					)
				)
				(pin bidirectional line
					(at 53.34 -125.73 180)
					(length 5.08)
					(name "IO_L24N_T3_32"
						(effects
							(font
								(size 1.27 1.27)
							)
						)
					)
					(number "Y15"
						(effects
							(font
								(size 1.27 1.27)
							)
						)
					)
				)
				(pin bidirectional line
					(at 53.34 -128.27 180)
					(length 5.08)
					(name "IO_25_VRP_32"
						(effects
							(font
								(size 1.27 1.27)
							)
						)
					)
					(number "AB14"
						(effects
							(font
								(size 1.27 1.27)
							)
						)
					)
				)
			)
			(symbol "XC7K410T-2FFG900I_4_5_1"
				(rectangle
					(start 5.08 5.08)
					(end 49.53 -130.81)
					(stroke
						(width 0.254)
						(type default)
					)
					(fill
						(type background)
					)
				)
				(text "BANK 33"
					(at 17.78 2.54 0)
					(effects
						(font
							(size 1.27 1.27)
							(thickness 0.15)
						)
						(justify left bottom)
					)
				)
				(text "BANK 34"
					(at 30.48 2.54 0)
					(effects
						(font
							(size 1.27 1.27)
							(thickness 0.15)
						)
						(justify left bottom)
					)
				)
				(pin bidirectional line
					(at 0 0 0)
					(length 5.08)
					(name "VCCO_33"
						(effects
							(font
								(size 1.27 1.27)
							)
						)
					)
					(number "AA9"
						(effects
							(font
								(size 1.27 1.27)
							)
						)
					)
				)
				(pin passive line
					(at 0 0 0)
					(length 5.08)
					(hide yes)
					(name "VCCO_33"
						(effects
							(font
								(size 1.27 1.27)
							)
						)
					)
					(number "AC13"
						(effects
							(font
								(size 1.27 1.27)
							)
						)
					)
				)
				(pin passive line
					(at 0 0 0)
					(length 5.08)
					(hide yes)
					(name "VCCO_33"
						(effects
							(font
								(size 1.27 1.27)
							)
						)
					)
					(number "AD10"
						(effects
							(font
								(size 1.27 1.27)
							)
						)
					)
				)
				(pin passive line
					(at 0 0 0)
					(length 5.08)
					(hide yes)
					(name "VCCO_33"
						(effects
							(font
								(size 1.27 1.27)
							)
						)
					)
					(number "AG11"
						(effects
							(font
								(size 1.27 1.27)
							)
						)
					)
				)
				(pin passive line
					(at 0 0 0)
					(length 5.08)
					(hide yes)
					(name "VCCO_33"
						(effects
							(font
								(size 1.27 1.27)
							)
						)
					)
					(number "AK12"
						(effects
							(font
								(size 1.27 1.27)
							)
						)
					)
				)
				(pin passive line
					(at 0 0 0)
					(length 5.08)
					(hide yes)
					(name "VCCO_33"
						(effects
							(font
								(size 1.27 1.27)
							)
						)
					)
					(number "Y12"
						(effects
							(font
								(size 1.27 1.27)
							)
						)
					)
				)
				(pin bidirectional line
					(at 0 -3.81 0)
					(length 5.08)
					(name "IO_0_VRN_33"
						(effects
							(font
								(size 1.27 1.27)
							)
						)
					)
					(number "Y13"
						(effects
							(font
								(size 1.27 1.27)
							)
						)
					)
				)
				(pin bidirectional line
					(at 0 -6.35 0)
					(length 5.08)
					(name "IO_L1P_T0_33"
						(effects
							(font
								(size 1.27 1.27)
							)
						)
					)
					(number "AA12"
						(effects
							(font
								(size 1.27 1.27)
							)
						)
					)
				)
				(pin bidirectional line
					(at 0 -8.89 0)
					(length 5.08)
					(name "IO_L1N_T0_33"
						(effects
							(font
								(size 1.27 1.27)
							)
						)
					)
					(number "AB12"
						(effects
							(font
								(size 1.27 1.27)
							)
						)
					)
				)
				(pin bidirectional line
					(at 0 -11.43 0)
					(length 5.08)
					(name "IO_L2P_T0_33"
						(effects
							(font
								(size 1.27 1.27)
							)
						)
					)
					(number "AA8"
						(effects
							(font
								(size 1.27 1.27)
							)
						)
					)
				)
				(pin bidirectional line
					(at 0 -13.97 0)
					(length 5.08)
					(name "IO_L2N_T0_33"
						(effects
							(font
								(size 1.27 1.27)
							)
						)
					)
					(number "AB8"
						(effects
							(font
								(size 1.27 1.27)
							)
						)
					)
				)
				(pin bidirectional line
					(at 0 -16.51 0)
					(length 5.08)
					(name "IO_L3P_T0_DQS_33"
						(effects
							(font
								(size 1.27 1.27)
							)
						)
					)
					(number "AB9"
						(effects
							(font
								(size 1.27 1.27)
							)
						)
					)
				)
				(pin bidirectional line
					(at 0 -19.05 0)
					(length 5.08)
					(name "IO_L3N_T0_DQS_33"
						(effects
							(font
								(size 1.27 1.27)
							)
						)
					)
					(number "AC9"
						(effects
							(font
								(size 1.27 1.27)
							)
						)
					)
				)
				(pin bidirectional line
					(at 0 -21.59 0)
					(length 5.08)
					(name "IO_L4P_T0_33"
						(effects
							(font
								(size 1.27 1.27)
							)
						)
					)
					(number "Y11"
						(effects
							(font
								(size 1.27 1.27)
							)
						)
					)
				)
				(pin bidirectional line
					(at 0 -24.13 0)
					(length 5.08)
					(name "IO_L4N_T0_33"
						(effects
							(font
								(size 1.27 1.27)
							)
						)
					)
					(number "Y10"
						(effects
							(font
								(size 1.27 1.27)
							)
						)
					)
				)
				(pin bidirectional line
					(at 0 -26.67 0)
					(length 5.08)
					(name "IO_L5P_T0_33"
						(effects
							(font
								(size 1.27 1.27)
							)
						)
					)
					(number "AA11"
						(effects
							(font
								(size 1.27 1.27)
							)
						)
					)
				)
				(pin bidirectional line
					(at 0 -29.21 0)
					(length 5.08)
					(name "IO_L5N_T0_33"
						(effects
							(font
								(size 1.27 1.27)
							)
						)
					)
					(number "AA10"
						(effects
							(font
								(size 1.27 1.27)
							)
						)
					)
				)
				(pin bidirectional line
					(at 0 -31.75 0)
					(length 5.08)
					(name "IO_L6P_T0_33"
						(effects
							(font
								(size 1.27 1.27)
							)
						)
					)
					(number "AA13"
						(effects
							(font
								(size 1.27 1.27)
							)
						)
					)
				)
				(pin bidirectional line
					(at 0 -34.29 0)
					(length 5.08)
					(name "IO_L6N_T0_VREF_33"
						(effects
							(font
								(size 1.27 1.27)
							)
						)
					)
					(number "AB13"
						(effects
							(font
								(size 1.27 1.27)
							)
						)
					)
				)
				(pin bidirectional line
					(at 0 -36.83 0)
					(length 5.08)
					(name "IO_L7P_T1_33"
						(effects
							(font
								(size 1.27 1.27)
							)
						)
					)
					(number "AB10"
						(effects
							(font
								(size 1.27 1.27)
							)
						)
					)
				)
				(pin bidirectional line
					(at 0 -39.37 0)
					(length 5.08)
					(name "IO_L7N_T1_33"
						(effects
							(font
								(size 1.27 1.27)
							)
						)
					)
					(number "AC10"
						(effects
							(font
								(size 1.27 1.27)
							)
						)
					)
				)
				(pin bidirectional line
					(at 0 -41.91 0)
					(length 5.08)
					(name "IO_L8P_T1_33"
						(effects
							(font
								(size 1.27 1.27)
							)
						)
					)
					(number "AD8"
						(effects
							(font
								(size 1.27 1.27)
							)
						)
					)
				)
				(pin bidirectional line
					(at 0 -44.45 0)
					(length 5.08)
					(name "IO_L8N_T1_33"
						(effects
							(font
								(size 1.27 1.27)
							)
						)
					)
					(number "AE8"
						(effects
							(font
								(size 1.27 1.27)
							)
						)
					)
				)
				(pin bidirectional line
					(at 0 -46.99 0)
					(length 5.08)
					(name "IO_L9P_T1_DQS_33"
						(effects
							(font
								(size 1.27 1.27)
							)
						)
					)
					(number "AC12"
						(effects
							(font
								(size 1.27 1.27)
							)
						)
					)
				)
				(pin bidirectional line
					(at 0 -49.53 0)
					(length 5.08)
					(name "IO_L9N_T1_DQS_33"
						(effects
							(font
								(size 1.27 1.27)
							)
						)
					)
					(number "AC11"
						(effects
							(font
								(size 1.27 1.27)
							)
						)
					)
				)
				(pin bidirectional line
					(at 0 -52.07 0)
					(length 5.08)
					(name "IO_L10P_T1_33"
						(effects
							(font
								(size 1.27 1.27)
							)
						)
					)
					(number "AD9"
						(effects
							(font
								(size 1.27 1.27)
							)
						)
					)
				)
				(pin bidirectional line
					(at 0 -54.61 0)
					(length 5.08)
					(name "IO_L10N_T1_33"
						(effects
							(font
								(size 1.27 1.27)
							)
						)
					)
					(number "AE9"
						(effects
							(font
								(size 1.27 1.27)
							)
						)
					)
				)
				(pin bidirectional line
					(at 0 -57.15 0)
					(length 5.08)
					(name "IO_L11P_T1_SRCC_33"
						(effects
							(font
								(size 1.27 1.27)
							)
						)
					)
					(number "AE11"
						(effects
							(font
								(size 1.27 1.27)
							)
						)
					)
				)
				(pin bidirectional line
					(at 0 -59.69 0)
					(length 5.08)
					(name "IO_L11N_T1_SRCC_33"
						(effects
							(font
								(size 1.27 1.27)
							)
						)
					)
					(number "AF11"
						(effects
							(font
								(size 1.27 1.27)
							)
						)
					)
				)
				(pin bidirectional line
					(at 0 -62.23 0)
					(length 5.08)
					(name "IO_L12P_T1_MRCC_33"
						(effects
							(font
								(size 1.27 1.27)
							)
						)
					)
					(number "AD12"
						(effects
							(font
								(size 1.27 1.27)
							)
						)
					)
				)
				(pin bidirectional line
					(at 0 -64.77 0)
					(length 5.08)
					(name "IO_L12N_T1_MRCC_33"
						(effects
							(font
								(size 1.27 1.27)
							)
						)
					)
					(number "AD11"
						(effects
							(font
								(size 1.27 1.27)
							)
						)
					)
				)
				(pin bidirectional line
					(at 0 -67.31 0)
					(length 5.08)
					(name "IO_L13P_T2_MRCC_33"
						(effects
							(font
								(size 1.27 1.27)
							)
						)
					)
					(number "AG10"
						(effects
							(font
								(size 1.27 1.27)
							)
						)
					)
				)
				(pin bidirectional line
					(at 0 -69.85 0)
					(length 5.08)
					(name "IO_L13N_T2_MRCC_33"
						(effects
							(font
								(size 1.27 1.27)
							)
						)
					)
					(number "AH10"
						(effects
							(font
								(size 1.27 1.27)
							)
						)
					)
				)
				(pin bidirectional line
					(at 0 -72.39 0)
					(length 5.08)
					(name "IO_L14P_T2_SRCC_33"
						(effects
							(font
								(size 1.27 1.27)
							)
						)
					)
					(number "AE10"
						(effects
							(font
								(size 1.27 1.27)
							)
						)
					)
				)
				(pin bidirectional line
					(at 0 -74.93 0)
					(length 5.08)
					(name "IO_L14N_T2_SRCC_33"
						(effects
							(font
								(size 1.27 1.27)
							)
						)
					)
					(number "AF10"
						(effects
							(font
								(size 1.27 1.27)
							)
						)
					)
				)
				(pin bidirectional line
					(at 0 -77.47 0)
					(length 5.08)
					(name "IO_L15P_T2_DQS_33"
						(effects
							(font
								(size 1.27 1.27)
							)
						)
					)
					(number "AJ9"
						(effects
							(font
								(size 1.27 1.27)
							)
						)
					)
				)
				(pin bidirectional line
					(at 0 -80.01 0)
					(length 5.08)
					(name "IO_L15N_T2_DQS_33"
						(effects
							(font
								(size 1.27 1.27)
							)
						)
					)
					(number "AK9"
						(effects
							(font
								(size 1.27 1.27)
							)
						)
					)
				)
				(pin bidirectional line
					(at 0 -82.55 0)
					(length 5.08)
					(name "IO_L16P_T2_33"
						(effects
							(font
								(size 1.27 1.27)
							)
						)
					)
					(number "AG9"
						(effects
							(font
								(size 1.27 1.27)
							)
						)
					)
				)
				(pin bidirectional line
					(at 0 -85.09 0)
					(length 5.08)
					(name "IO_L16N_T2_33"
						(effects
							(font
								(size 1.27 1.27)
							)
						)
					)
					(number "AH9"
						(effects
							(font
								(size 1.27 1.27)
							)
						)
					)
				)
				(pin bidirectional line
					(at 0 -87.63 0)
					(length 5.08)
					(name "IO_L17P_T2_33"
						(effects
							(font
								(size 1.27 1.27)
							)
						)
					)
					(number "AK11"
						(effects
							(font
								(size 1.27 1.27)
							)
						)
					)
				)
				(pin bidirectional line
					(at 0 -90.17 0)
					(length 5.08)
					(name "IO_L17N_T2_33"
						(effects
							(font
								(size 1.27 1.27)
							)
						)
					)
					(number "AK10"
						(effects
							(font
								(size 1.27 1.27)
							)
						)
					)
				)
				(pin bidirectional line
					(at 0 -92.71 0)
					(length 5.08)
					(name "IO_L18P_T2_33"
						(effects
							(font
								(size 1.27 1.27)
							)
						)
					)
					(number "AH11"
						(effects
							(font
								(size 1.27 1.27)
							)
						)
					)
				)
				(pin bidirectional line
					(at 0 -95.25 0)
					(length 5.08)
					(name "IO_L18N_T2_33"
						(effects
							(font
								(size 1.27 1.27)
							)
						)
					)
					(number "AJ11"
						(effects
							(font
								(size 1.27 1.27)
							)
						)
					)
				)
				(pin bidirectional line
					(at 0 -97.79 0)
					(length 5.08)
					(name "IO_L19P_T3_33"
						(effects
							(font
								(size 1.27 1.27)
							)
						)
					)
					(number "AE13"
						(effects
							(font
								(size 1.27 1.27)
							)
						)
					)
				)
				(pin bidirectional line
					(at 0 -100.33 0)
					(length 5.08)
					(name "IO_L19N_T3_VREF_33"
						(effects
							(font
								(size 1.27 1.27)
							)
						)
					)
					(number "AF13"
						(effects
							(font
								(size 1.27 1.27)
							)
						)
					)
				)
				(pin bidirectional line
					(at 0 -102.87 0)
					(length 5.08)
					(name "IO_L20P_T3_33"
						(effects
							(font
								(size 1.27 1.27)
							)
						)
					)
					(number "AK14"
						(effects
							(font
								(size 1.27 1.27)
							)
						)
					)
				)
				(pin bidirectional line
					(at 0 -105.41 0)
					(length 5.08)
					(name "IO_L20N_T3_33"
						(effects
							(font
								(size 1.27 1.27)
							)
						)
					)
					(number "AK13"
						(effects
							(font
								(size 1.27 1.27)
							)
						)
					)
				)
				(pin bidirectional line
					(at 0 -107.95 0)
					(length 5.08)
					(name "IO_L21P_T3_DQS_33"
						(effects
							(font
								(size 1.27 1.27)
							)
						)
					)
					(number "AH14"
						(effects
							(font
								(size 1.27 1.27)
							)
						)
					)
				)
				(pin bidirectional line
					(at 0 -110.49 0)
					(length 5.08)
					(name "IO_L21N_T3_DQS_33"
						(effects
							(font
								(size 1.27 1.27)
							)
						)
					)
					(number "AJ14"
						(effects
							(font
								(size 1.27 1.27)
							)
						)
					)
				)
				(pin bidirectional line
					(at 0 -113.03 0)
					(length 5.08)
					(name "IO_L22P_T3_33"
						(effects
							(font
								(size 1.27 1.27)
							)
						)
					)
					(number "AJ13"
						(effects
							(font
								(size 1.27 1.27)
							)
						)
					)
				)
				(pin bidirectional line
					(at 0 -115.57 0)
					(length 5.08)
					(name "IO_L22N_T3_33"
						(effects
							(font
								(size 1.27 1.27)
							)
						)
					)
					(number "AJ12"
						(effects
							(font
								(size 1.27 1.27)
							)
						)
					)
				)
				(pin bidirectional line
					(at 0 -118.11 0)
					(length 5.08)
					(name "IO_L23P_T3_33"
						(effects
							(font
								(size 1.27 1.27)
							)
						)
					)
					(number "AF12"
						(effects
							(font
								(size 1.27 1.27)
							)
						)
					)
				)
				(pin bidirectional line
					(at 0 -120.65 0)
					(length 5.08)
					(name "IO_L23N_T3_33"
						(effects
							(font
								(size 1.27 1.27)
							)
						)
					)
					(number "AG12"
						(effects
							(font
								(size 1.27 1.27)
							)
						)
					)
				)
				(pin bidirectional line
					(at 0 -123.19 0)
					(length 5.08)
					(name "IO_L24P_T3_33"
						(effects
							(font
								(size 1.27 1.27)
							)
						)
					)
					(number "AG13"
						(effects
							(font
								(size 1.27 1.27)
							)
						)
					)
				)
				(pin bidirectional line
					(at 0 -125.73 0)
					(length 5.08)
					(name "IO_L24N_T3_33"
						(effects
							(font
								(size 1.27 1.27)
							)
						)
					)
					(number "AH12"
						(effects
							(font
								(size 1.27 1.27)
							)
						)
					)
				)
				(pin bidirectional line
					(at 0 -128.27 0)
					(length 5.08)
					(name "IO_25_VRP_33"
						(effects
							(font
								(size 1.27 1.27)
							)
						)
					)
					(number "AD13"
						(effects
							(font
								(size 1.27 1.27)
							)
						)
					)
				)
				(pin bidirectional line
					(at 54.61 0 180)
					(length 5.08)
					(name "VCCO_34"
						(effects
							(font
								(size 1.27 1.27)
							)
						)
					)
					(number "AC3"
						(effects
							(font
								(size 1.27 1.27)
							)
						)
					)
				)
				(pin passive line
					(at 54.61 0 180)
					(length 5.08)
					(hide yes)
					(name "VCCO_34"
						(effects
							(font
								(size 1.27 1.27)
							)
						)
					)
					(number "AE7"
						(effects
							(font
								(size 1.27 1.27)
							)
						)
					)
				)
				(pin passive line
					(at 54.61 0 180)
					(length 5.08)
					(hide yes)
					(name "VCCO_34"
						(effects
							(font
								(size 1.27 1.27)
							)
						)
					)
					(number "AF4"
						(effects
							(font
								(size 1.27 1.27)
							)
						)
					)
				)
				(pin passive line
					(at 54.61 0 180)
					(length 5.08)
					(hide yes)
					(name "VCCO_34"
						(effects
							(font
								(size 1.27 1.27)
							)
						)
					)
					(number "AG1"
						(effects
							(font
								(size 1.27 1.27)
							)
						)
					)
				)
				(pin passive line
					(at 54.61 0 180)
					(length 5.08)
					(hide yes)
					(name "VCCO_34"
						(effects
							(font
								(size 1.27 1.27)
							)
						)
					)
					(number "AH8"
						(effects
							(font
								(size 1.27 1.27)
							)
						)
					)
				)
				(pin passive line
					(at 54.61 0 180)
					(length 5.08)
					(hide yes)
					(name "VCCO_34"
						(effects
							(font
								(size 1.27 1.27)
							)
						)
					)
					(number "AJ5"
						(effects
							(font
								(size 1.27 1.27)
							)
						)
					)
				)
				(pin passive line
					(at 54.61 0 180)
					(length 5.08)
					(hide yes)
					(name "VCCO_34"
						(effects
							(font
								(size 1.27 1.27)
							)
						)
					)
					(number "AK2"
						(effects
							(font
								(size 1.27 1.27)
							)
						)
					)
				)
				(pin bidirectional line
					(at 54.61 -3.81 180)
					(length 5.08)
					(name "IO_0_VRN_34"
						(effects
							(font
								(size 1.27 1.27)
							)
						)
					)
					(number "AC6"
						(effects
							(font
								(size 1.27 1.27)
							)
						)
					)
				)
				(pin bidirectional line
					(at 54.61 -6.35 180)
					(length 5.08)
					(name "IO_L1P_T0_34"
						(effects
							(font
								(size 1.27 1.27)
							)
						)
					)
					(number "AD4"
						(effects
							(font
								(size 1.27 1.27)
							)
						)
					)
				)
				(pin bidirectional line
					(at 54.61 -8.89 180)
					(length 5.08)
					(name "IO_L1N_T0_34"
						(effects
							(font
								(size 1.27 1.27)
							)
						)
					)
					(number "AD3"
						(effects
							(font
								(size 1.27 1.27)
							)
						)
					)
				)
				(pin bidirectional line
					(at 54.61 -11.43 180)
					(length 5.08)
					(name "IO_L2P_T0_34"
						(effects
							(font
								(size 1.27 1.27)
							)
						)
					)
					(number "AC2"
						(effects
							(font
								(size 1.27 1.27)
							)
						)
					)
				)
				(pin bidirectional line
					(at 54.61 -13.97 180)
					(length 5.08)
					(name "IO_L2N_T0_34"
						(effects
							(font
								(size 1.27 1.27)
							)
						)
					)
					(number "AC1"
						(effects
							(font
								(size 1.27 1.27)
							)
						)
					)
				)
				(pin bidirectional line
					(at 54.61 -16.51 180)
					(length 5.08)
					(name "IO_L3P_T0_DQS_34"
						(effects
							(font
								(size 1.27 1.27)
							)
						)
					)
					(number "AD2"
						(effects
							(font
								(size 1.27 1.27)
							)
						)
					)
				)
				(pin bidirectional line
					(at 54.61 -19.05 180)
					(length 5.08)
					(name "IO_L3N_T0_DQS_34"
						(effects
							(font
								(size 1.27 1.27)
							)
						)
					)
					(number "AD1"
						(effects
							(font
								(size 1.27 1.27)
							)
						)
					)
				)
				(pin bidirectional line
					(at 54.61 -21.59 180)
					(length 5.08)
					(name "IO_L4P_T0_34"
						(effects
							(font
								(size 1.27 1.27)
							)
						)
					)
					(number "AC5"
						(effects
							(font
								(size 1.27 1.27)
							)
						)
					)
				)
				(pin bidirectional line
					(at 54.61 -24.13 180)
					(length 5.08)
					(name "IO_L4N_T0_34"
						(effects
							(font
								(size 1.27 1.27)
							)
						)
					)
					(number "AC4"
						(effects
							(font
								(size 1.27 1.27)
							)
						)
					)
				)
				(pin bidirectional line
					(at 54.61 -26.67 180)
					(length 5.08)
					(name "IO_L5P_T0_34"
						(effects
							(font
								(size 1.27 1.27)
							)
						)
					)
					(number "AD6"
						(effects
							(font
								(size 1.27 1.27)
							)
						)
					)
				)
				(pin bidirectional line
					(at 54.61 -29.21 180)
					(length 5.08)
					(name "IO_L5N_T0_34"
						(effects
							(font
								(size 1.27 1.27)
							)
						)
					)
					(number "AE6"
						(effects
							(font
								(size 1.27 1.27)
							)
						)
					)
				)
				(pin bidirectional line
					(at 54.61 -31.75 180)
					(length 5.08)
					(name "IO_L6P_T0_34"
						(effects
							(font
								(size 1.27 1.27)
							)
						)
					)
					(number "AC7"
						(effects
							(font
								(size 1.27 1.27)
							)
						)
					)
				)
				(pin bidirectional line
					(at 54.61 -34.29 180)
					(length 5.08)
					(name "IO_L6N_T0_VREF_34"
						(effects
							(font
								(size 1.27 1.27)
							)
						)
					)
					(number "AD7"
						(effects
							(font
								(size 1.27 1.27)
							)
						)
					)
				)
				(pin bidirectional line
					(at 54.61 -36.83 180)
					(length 5.08)
					(name "IO_L7P_T1_34"
						(effects
							(font
								(size 1.27 1.27)
							)
						)
					)
					(number "AF3"
						(effects
							(font
								(size 1.27 1.27)
							)
						)
					)
				)
				(pin bidirectional line
					(at 54.61 -39.37 180)
					(length 5.08)
					(name "IO_L7N_T1_34"
						(effects
							(font
								(size 1.27 1.27)
							)
						)
					)
					(number "AF2"
						(effects
							(font
								(size 1.27 1.27)
							)
						)
					)
				)
				(pin bidirectional line
					(at 54.61 -41.91 180)
					(length 5.08)
					(name "IO_L8P_T1_34"
						(effects
							(font
								(size 1.27 1.27)
							)
						)
					)
					(number "AE1"
						(effects
							(font
								(size 1.27 1.27)
							)
						)
					)
				)
				(pin bidirectional line
					(at 54.61 -44.45 180)
					(length 5.08)
					(name "IO_L8N_T1_34"
						(effects
							(font
								(size 1.27 1.27)
							)
						)
					)
					(number "AF1"
						(effects
							(font
								(size 1.27 1.27)
							)
						)
					)
				)
				(pin bidirectional line
					(at 54.61 -46.99 180)
					(length 5.08)
					(name "IO_L9P_T1_DQS_34"
						(effects
							(font
								(size 1.27 1.27)
							)
						)
					)
					(number "AG4"
						(effects
							(font
								(size 1.27 1.27)
							)
						)
					)
				)
				(pin bidirectional line
					(at 54.61 -49.53 180)
					(length 5.08)
					(name "IO_L9N_T1_DQS_34"
						(effects
							(font
								(size 1.27 1.27)
							)
						)
					)
					(number "AG3"
						(effects
							(font
								(size 1.27 1.27)
							)
						)
					)
				)
				(pin bidirectional line
					(at 54.61 -52.07 180)
					(length 5.08)
					(name "IO_L10P_T1_34"
						(effects
							(font
								(size 1.27 1.27)
							)
						)
					)
					(number "AE4"
						(effects
							(font
								(size 1.27 1.27)
							)
						)
					)
				)
				(pin bidirectional line
					(at 54.61 -54.61 180)
					(length 5.08)
					(name "IO_L10N_T1_34"
						(effects
							(font
								(size 1.27 1.27)
							)
						)
					)
					(number "AE3"
						(effects
							(font
								(size 1.27 1.27)
							)
						)
					)
				)
				(pin bidirectional line
					(at 54.61 -57.15 180)
					(length 5.08)
					(name "IO_L11P_T1_SRCC_34"
						(effects
							(font
								(size 1.27 1.27)
							)
						)
					)
					(number "AE5"
						(effects
							(font
								(size 1.27 1.27)
							)
						)
					)
				)
				(pin bidirectional line
					(at 54.61 -59.69 180)
					(length 5.08)
					(name "IO_L11N_T1_SRCC_34"
						(effects
							(font
								(size 1.27 1.27)
							)
						)
					)
					(number "AF5"
						(effects
							(font
								(size 1.27 1.27)
							)
						)
					)
				)
				(pin bidirectional line
					(at 54.61 -62.23 180)
					(length 5.08)
					(name "IO_L12P_T1_MRCC_34"
						(effects
							(font
								(size 1.27 1.27)
							)
						)
					)
					(number "AF6"
						(effects
							(font
								(size 1.27 1.27)
							)
						)
					)
				)
				(pin bidirectional line
					(at 54.61 -64.77 180)
					(length 5.08)
					(name "IO_L12N_T1_MRCC_34"
						(effects
							(font
								(size 1.27 1.27)
							)
						)
					)
					(number "AG5"
						(effects
							(font
								(size 1.27 1.27)
							)
						)
					)
				)
				(pin bidirectional line
					(at 54.61 -67.31 180)
					(length 5.08)
					(name "IO_L13P_T2_MRCC_34"
						(effects
							(font
								(size 1.27 1.27)
							)
						)
					)
					(number "AH4"
						(effects
							(font
								(size 1.27 1.27)
							)
						)
					)
				)
				(pin bidirectional line
					(at 54.61 -69.85 180)
					(length 5.08)
					(name "IO_L13N_T2_MRCC_34"
						(effects
							(font
								(size 1.27 1.27)
							)
						)
					)
					(number "AJ4"
						(effects
							(font
								(size 1.27 1.27)
							)
						)
					)
				)
				(pin bidirectional line
					(at 54.61 -72.39 180)
					(length 5.08)
					(name "IO_L14P_T2_SRCC_34"
						(effects
							(font
								(size 1.27 1.27)
							)
						)
					)
					(number "AH6"
						(effects
							(font
								(size 1.27 1.27)
							)
						)
					)
				)
				(pin bidirectional line
					(at 54.61 -74.93 180)
					(length 5.08)
					(name "IO_L14N_T2_SRCC_34"
						(effects
							(font
								(size 1.27 1.27)
							)
						)
					)
					(number "AH5"
						(effects
							(font
								(size 1.27 1.27)
							)
						)
					)
				)
				(pin bidirectional line
					(at 54.61 -77.47 180)
					(length 5.08)
					(name "IO_L15P_T2_DQS_34"
						(effects
							(font
								(size 1.27 1.27)
							)
						)
					)
					(number "AG2"
						(effects
							(font
								(size 1.27 1.27)
							)
						)
					)
				)
				(pin bidirectional line
					(at 54.61 -80.01 180)
					(length 5.08)
					(name "IO_L15N_T2_DQS_34"
						(effects
							(font
								(size 1.27 1.27)
							)
						)
					)
					(number "AH1"
						(effects
							(font
								(size 1.27 1.27)
							)
						)
					)
				)
				(pin bidirectional line
					(at 54.61 -82.55 180)
					(length 5.08)
					(name "IO_L16P_T2_34"
						(effects
							(font
								(size 1.27 1.27)
							)
						)
					)
					(number "AH2"
						(effects
							(font
								(size 1.27 1.27)
							)
						)
					)
				)
				(pin bidirectional line
					(at 54.61 -85.09 180)
					(length 5.08)
					(name "IO_L16N_T2_34"
						(effects
							(font
								(size 1.27 1.27)
							)
						)
					)
					(number "AJ2"
						(effects
							(font
								(size 1.27 1.27)
							)
						)
					)
				)
				(pin bidirectional line
					(at 54.61 -87.63 180)
					(length 5.08)
					(name "IO_L17P_T2_34"
						(effects
							(font
								(size 1.27 1.27)
							)
						)
					)
					(number "AJ1"
						(effects
							(font
								(size 1.27 1.27)
							)
						)
					)
				)
				(pin bidirectional line
					(at 54.61 -90.17 180)
					(length 5.08)
					(name "IO_L17N_T2_34"
						(effects
							(font
								(size 1.27 1.27)
							)
						)
					)
					(number "AK1"
						(effects
							(font
								(size 1.27 1.27)
							)
						)
					)
				)
				(pin bidirectional line
					(at 54.61 -92.71 180)
					(length 5.08)
					(name "IO_L18P_T2_34"
						(effects
							(font
								(size 1.27 1.27)
							)
						)
					)
					(number "AJ3"
						(effects
							(font
								(size 1.27 1.27)
							)
						)
					)
				)
				(pin bidirectional line
					(at 54.61 -95.25 180)
					(length 5.08)
					(name "IO_L18N_T2_34"
						(effects
							(font
								(size 1.27 1.27)
							)
						)
					)
					(number "AK3"
						(effects
							(font
								(size 1.27 1.27)
							)
						)
					)
				)
				(pin bidirectional line
					(at 54.61 -97.79 180)
					(length 5.08)
					(name "IO_L19P_T3_34"
						(effects
							(font
								(size 1.27 1.27)
							)
						)
					)
					(number "AF8"
						(effects
							(font
								(size 1.27 1.27)
							)
						)
					)
				)
				(pin bidirectional line
					(at 54.61 -100.33 180)
					(length 5.08)
					(name "IO_L19N_T3_VREF_34"
						(effects
							(font
								(size 1.27 1.27)
							)
						)
					)
					(number "AG8"
						(effects
							(font
								(size 1.27 1.27)
							)
						)
					)
				)
				(pin bidirectional line
					(at 54.61 -102.87 180)
					(length 5.08)
					(name "IO_L20P_T3_34"
						(effects
							(font
								(size 1.27 1.27)
							)
						)
					)
					(number "AF7"
						(effects
							(font
								(size 1.27 1.27)
							)
						)
					)
				)
				(pin bidirectional line
					(at 54.61 -105.41 180)
					(length 5.08)
					(name "IO_L20N_T3_34"
						(effects
							(font
								(size 1.27 1.27)
							)
						)
					)
					(number "AG7"
						(effects
							(font
								(size 1.27 1.27)
							)
						)
					)
				)
				(pin bidirectional line
					(at 54.61 -107.95 180)
					(length 5.08)
					(name "IO_L21P_T3_DQS_34"
						(effects
							(font
								(size 1.27 1.27)
							)
						)
					)
					(number "AH7"
						(effects
							(font
								(size 1.27 1.27)
							)
						)
					)
				)
				(pin bidirectional line
					(at 54.61 -110.49 180)
					(length 5.08)
					(name "IO_L21N_T3_DQS_34"
						(effects
							(font
								(size 1.27 1.27)
							)
						)
					)
					(number "AJ7"
						(effects
							(font
								(size 1.27 1.27)
							)
						)
					)
				)
				(pin bidirectional line
					(at 54.61 -113.03 180)
					(length 5.08)
					(name "IO_L22P_T3_34"
						(effects
							(font
								(size 1.27 1.27)
							)
						)
					)
					(number "AJ6"
						(effects
							(font
								(size 1.27 1.27)
							)
						)
					)
				)
				(pin bidirectional line
					(at 54.61 -115.57 180)
					(length 5.08)
					(name "IO_L22N_T3_34"
						(effects
							(font
								(size 1.27 1.27)
							)
						)
					)
					(number "AK6"
						(effects
							(font
								(size 1.27 1.27)
							)
						)
					)
				)
				(pin bidirectional line
					(at 54.61 -118.11 180)
					(length 5.08)
					(name "IO_L23P_T3_34"
						(effects
							(font
								(size 1.27 1.27)
							)
						)
					)
					(number "AJ8"
						(effects
							(font
								(size 1.27 1.27)
							)
						)
					)
				)
				(pin bidirectional line
					(at 54.61 -120.65 180)
					(length 5.08)
					(name "IO_L23N_T3_34"
						(effects
							(font
								(size 1.27 1.27)
							)
						)
					)
					(number "AK8"
						(effects
							(font
								(size 1.27 1.27)
							)
						)
					)
				)
				(pin bidirectional line
					(at 54.61 -123.19 180)
					(length 5.08)
					(name "IO_L24P_T3_34"
						(effects
							(font
								(size 1.27 1.27)
							)
						)
					)
					(number "AK5"
						(effects
							(font
								(size 1.27 1.27)
							)
						)
					)
				)
				(pin bidirectional line
					(at 54.61 -125.73 180)
					(length 5.08)
					(name "IO_L24N_T3_34"
						(effects
							(font
								(size 1.27 1.27)
							)
						)
					)
					(number "AK4"
						(effects
							(font
								(size 1.27 1.27)
							)
						)
					)
				)
				(pin bidirectional line
					(at 54.61 -128.27 180)
					(length 5.08)
					(name "IO_25_VRP_34"
						(effects
							(font
								(size 1.27 1.27)
							)
						)
					)
					(number "AB7"
						(effects
							(font
								(size 1.27 1.27)
							)
						)
					)
				)
			)
			(symbol "XC7K410T-2FFG900I_4_6_1"
				(rectangle
					(start 5.08 5.08)
					(end 43.18 -53.34)
					(stroke
						(width 0.254)
						(type default)
					)
					(fill
						(type background)
					)
				)
				(text "GTX 115"
					(at 8.89 2.54 0)
					(effects
						(font
							(size 1.27 1.27)
							(thickness 0.15)
						)
						(justify left bottom)
					)
				)
				(text "GTX 116"
					(at 29.21 2.54 0)
					(effects
						(font
							(size 1.27 1.27)
							(thickness 0.15)
						)
						(justify left bottom)
					)
				)
				(pin bidirectional line
					(at 0 0 0)
					(length 5.08)
					(name "MGTXTXP0_115"
						(effects
							(font
								(size 1.27 1.27)
							)
						)
					)
					(number "Y2"
						(effects
							(font
								(size 1.27 1.27)
							)
						)
					)
				)
				(pin bidirectional line
					(at 0 -2.54 0)
					(length 5.08)
					(name "MGTXTXN0_115"
						(effects
							(font
								(size 1.27 1.27)
							)
						)
					)
					(number "Y1"
						(effects
							(font
								(size 1.27 1.27)
							)
						)
					)
				)
				(pin bidirectional line
					(at 0 -5.08 0)
					(length 5.08)
					(name "MGTXTXP1_115"
						(effects
							(font
								(size 1.27 1.27)
							)
						)
					)
					(number "V2"
						(effects
							(font
								(size 1.27 1.27)
							)
						)
					)
				)
				(pin bidirectional line
					(at 0 -7.62 0)
					(length 5.08)
					(name "MGTXTXN1_115"
						(effects
							(font
								(size 1.27 1.27)
							)
						)
					)
					(number "V1"
						(effects
							(font
								(size 1.27 1.27)
							)
						)
					)
				)
				(pin bidirectional line
					(at 0 -10.16 0)
					(length 5.08)
					(name "MGTXTXP2_115"
						(effects
							(font
								(size 1.27 1.27)
							)
						)
					)
					(number "U4"
						(effects
							(font
								(size 1.27 1.27)
							)
						)
					)
				)
				(pin bidirectional line
					(at 0 -12.7 0)
					(length 5.08)
					(name "MGTXTXN2_115"
						(effects
							(font
								(size 1.27 1.27)
							)
						)
					)
					(number "U3"
						(effects
							(font
								(size 1.27 1.27)
							)
						)
					)
				)
				(pin bidirectional line
					(at 0 -15.24 0)
					(length 5.08)
					(name "MGTXTXP3_115"
						(effects
							(font
								(size 1.27 1.27)
							)
						)
					)
					(number "T2"
						(effects
							(font
								(size 1.27 1.27)
							)
						)
					)
				)
				(pin bidirectional line
					(at 0 -17.78 0)
					(length 5.08)
					(name "MGTXTXN3_115"
						(effects
							(font
								(size 1.27 1.27)
							)
						)
					)
					(number "T1"
						(effects
							(font
								(size 1.27 1.27)
							)
						)
					)
				)
				(pin bidirectional line
					(at 0 -21.59 0)
					(length 5.08)
					(name "MGTXRXP0_115"
						(effects
							(font
								(size 1.27 1.27)
							)
						)
					)
					(number "AA4"
						(effects
							(font
								(size 1.27 1.27)
							)
						)
					)
				)
				(pin bidirectional line
					(at 0 -24.13 0)
					(length 5.08)
					(name "MGTXRXN0_115"
						(effects
							(font
								(size 1.27 1.27)
							)
						)
					)
					(number "AA3"
						(effects
							(font
								(size 1.27 1.27)
							)
						)
					)
				)
				(pin bidirectional line
					(at 0 -26.67 0)
					(length 5.08)
					(name "MGTXRXP1_115"
						(effects
							(font
								(size 1.27 1.27)
							)
						)
					)
					(number "Y6"
						(effects
							(font
								(size 1.27 1.27)
							)
						)
					)
				)
				(pin bidirectional line
					(at 0 -29.21 0)
					(length 5.08)
					(name "MGTXRXN1_115"
						(effects
							(font
								(size 1.27 1.27)
							)
						)
					)
					(number "Y5"
						(effects
							(font
								(size 1.27 1.27)
							)
						)
					)
				)
				(pin bidirectional line
					(at 0 -31.75 0)
					(length 5.08)
					(name "MGTXRXP2_115"
						(effects
							(font
								(size 1.27 1.27)
							)
						)
					)
					(number "W4"
						(effects
							(font
								(size 1.27 1.27)
							)
						)
					)
				)
				(pin bidirectional line
					(at 0 -34.29 0)
					(length 5.08)
					(name "MGTXRXN2_115"
						(effects
							(font
								(size 1.27 1.27)
							)
						)
					)
					(number "W3"
						(effects
							(font
								(size 1.27 1.27)
							)
						)
					)
				)
				(pin bidirectional line
					(at 0 -36.83 0)
					(length 5.08)
					(name "MGTXRXP3_115"
						(effects
							(font
								(size 1.27 1.27)
							)
						)
					)
					(number "V6"
						(effects
							(font
								(size 1.27 1.27)
							)
						)
					)
				)
				(pin bidirectional line
					(at 0 -39.37 0)
					(length 5.08)
					(name "MGTXRXN3_115"
						(effects
							(font
								(size 1.27 1.27)
							)
						)
					)
					(number "V5"
						(effects
							(font
								(size 1.27 1.27)
							)
						)
					)
				)
				(pin bidirectional line
					(at 0 -43.18 0)
					(length 5.08)
					(name "MGTREFCLK0P_115"
						(effects
							(font
								(size 1.27 1.27)
							)
						)
					)
					(number "R8"
						(effects
							(font
								(size 1.27 1.27)
							)
						)
					)
				)
				(pin bidirectional line
					(at 0 -45.72 0)
					(length 5.08)
					(name "MGTREFCLK0N_115"
						(effects
							(font
								(size 1.27 1.27)
							)
						)
					)
					(number "R7"
						(effects
							(font
								(size 1.27 1.27)
							)
						)
					)
				)
				(pin bidirectional line
					(at 0 -48.26 0)
					(length 5.08)
					(name "MGTREFCLK1P_115"
						(effects
							(font
								(size 1.27 1.27)
							)
						)
					)
					(number "U8"
						(effects
							(font
								(size 1.27 1.27)
							)
						)
					)
				)
				(pin bidirectional line
					(at 0 -50.8 0)
					(length 5.08)
					(name "MGTREFCLK1N_115"
						(effects
							(font
								(size 1.27 1.27)
							)
						)
					)
					(number "U7"
						(effects
							(font
								(size 1.27 1.27)
							)
						)
					)
				)
				(pin bidirectional line
					(at 48.26 0 180)
					(length 5.08)
					(name "MGTXTXP0_116"
						(effects
							(font
								(size 1.27 1.27)
							)
						)
					)
					(number "P2"
						(effects
							(font
								(size 1.27 1.27)
							)
						)
					)
				)
				(pin bidirectional line
					(at 48.26 -2.54 180)
					(length 5.08)
					(name "MGTXTXN0_116"
						(effects
							(font
								(size 1.27 1.27)
							)
						)
					)
					(number "P1"
						(effects
							(font
								(size 1.27 1.27)
							)
						)
					)
				)
				(pin bidirectional line
					(at 48.26 -5.08 180)
					(length 5.08)
					(name "MGTXTXP1_116"
						(effects
							(font
								(size 1.27 1.27)
							)
						)
					)
					(number "N4"
						(effects
							(font
								(size 1.27 1.27)
							)
						)
					)
				)
				(pin bidirectional line
					(at 48.26 -7.62 180)
					(length 5.08)
					(name "MGTXTXN1_116"
						(effects
							(font
								(size 1.27 1.27)
							)
						)
					)
					(number "N3"
						(effects
							(font
								(size 1.27 1.27)
							)
						)
					)
				)
				(pin bidirectional line
					(at 48.26 -10.16 180)
					(length 5.08)
					(name "MGTXTXP2_116"
						(effects
							(font
								(size 1.27 1.27)
							)
						)
					)
					(number "M2"
						(effects
							(font
								(size 1.27 1.27)
							)
						)
					)
				)
				(pin bidirectional line
					(at 48.26 -12.7 180)
					(length 5.08)
					(name "MGTXTXN2_116"
						(effects
							(font
								(size 1.27 1.27)
							)
						)
					)
					(number "M1"
						(effects
							(font
								(size 1.27 1.27)
							)
						)
					)
				)
				(pin bidirectional line
					(at 48.26 -15.24 180)
					(length 5.08)
					(name "MGTXTXP3_116"
						(effects
							(font
								(size 1.27 1.27)
							)
						)
					)
					(number "L4"
						(effects
							(font
								(size 1.27 1.27)
							)
						)
					)
				)
				(pin bidirectional line
					(at 48.26 -17.78 180)
					(length 5.08)
					(name "MGTXTXN3_116"
						(effects
							(font
								(size 1.27 1.27)
							)
						)
					)
					(number "L3"
						(effects
							(font
								(size 1.27 1.27)
							)
						)
					)
				)
				(pin bidirectional line
					(at 48.26 -21.59 180)
					(length 5.08)
					(name "MGTXRXP0_116"
						(effects
							(font
								(size 1.27 1.27)
							)
						)
					)
					(number "T6"
						(effects
							(font
								(size 1.27 1.27)
							)
						)
					)
				)
				(pin bidirectional line
					(at 48.26 -24.13 180)
					(length 5.08)
					(name "MGTXRXN0_116"
						(effects
							(font
								(size 1.27 1.27)
							)
						)
					)
					(number "T5"
						(effects
							(font
								(size 1.27 1.27)
							)
						)
					)
				)
				(pin bidirectional line
					(at 48.26 -26.67 180)
					(length 5.08)
					(name "MGTXRXP1_116"
						(effects
							(font
								(size 1.27 1.27)
							)
						)
					)
					(number "R4"
						(effects
							(font
								(size 1.27 1.27)
							)
						)
					)
				)
				(pin bidirectional line
					(at 48.26 -29.21 180)
					(length 5.08)
					(name "MGTXRXN1_116"
						(effects
							(font
								(size 1.27 1.27)
							)
						)
					)
					(number "R3"
						(effects
							(font
								(size 1.27 1.27)
							)
						)
					)
				)
				(pin bidirectional line
					(at 48.26 -31.75 180)
					(length 5.08)
					(name "MGTXRXP2_116"
						(effects
							(font
								(size 1.27 1.27)
							)
						)
					)
					(number "P6"
						(effects
							(font
								(size 1.27 1.27)
							)
						)
					)
				)
				(pin bidirectional line
					(at 48.26 -34.29 180)
					(length 5.08)
					(name "MGTXRXN2_116"
						(effects
							(font
								(size 1.27 1.27)
							)
						)
					)
					(number "P5"
						(effects
							(font
								(size 1.27 1.27)
							)
						)
					)
				)
				(pin bidirectional line
					(at 48.26 -36.83 180)
					(length 5.08)
					(name "MGTXRXP3_116"
						(effects
							(font
								(size 1.27 1.27)
							)
						)
					)
					(number "M6"
						(effects
							(font
								(size 1.27 1.27)
							)
						)
					)
				)
				(pin bidirectional line
					(at 48.26 -39.37 180)
					(length 5.08)
					(name "MGTXRXN3_116"
						(effects
							(font
								(size 1.27 1.27)
							)
						)
					)
					(number "M5"
						(effects
							(font
								(size 1.27 1.27)
							)
						)
					)
				)
				(pin bidirectional line
					(at 48.26 -43.18 180)
					(length 5.08)
					(name "MGTREFCLK0P_116"
						(effects
							(font
								(size 1.27 1.27)
							)
						)
					)
					(number "L8"
						(effects
							(font
								(size 1.27 1.27)
							)
						)
					)
				)
				(pin bidirectional line
					(at 48.26 -45.72 180)
					(length 5.08)
					(name "MGTREFCLK0N_116"
						(effects
							(font
								(size 1.27 1.27)
							)
						)
					)
					(number "L7"
						(effects
							(font
								(size 1.27 1.27)
							)
						)
					)
				)
				(pin bidirectional line
					(at 48.26 -48.26 180)
					(length 5.08)
					(name "MGTREFCLK1P_116"
						(effects
							(font
								(size 1.27 1.27)
							)
						)
					)
					(number "N8"
						(effects
							(font
								(size 1.27 1.27)
							)
						)
					)
				)
				(pin bidirectional line
					(at 48.26 -50.8 180)
					(length 5.08)
					(name "MGTREFCLK1N_116"
						(effects
							(font
								(size 1.27 1.27)
							)
						)
					)
					(number "N7"
						(effects
							(font
								(size 1.27 1.27)
							)
						)
					)
				)
			)
			(symbol "XC7K410T-2FFG900I_4_7_1"
				(rectangle
					(start 5.08 5.08)
					(end 43.18 -53.34)
					(stroke
						(width 0.254)
						(type default)
					)
					(fill
						(type background)
					)
				)
				(text "GTX 117"
					(at 8.89 2.54 0)
					(effects
						(font
							(size 1.27 1.27)
							(thickness 0.15)
						)
						(justify left bottom)
					)
				)
				(text "GTX 118"
					(at 29.21 2.54 0)
					(effects
						(font
							(size 1.27 1.27)
							(thickness 0.15)
						)
						(justify left bottom)
					)
				)
				(pin bidirectional line
					(at 0 0 0)
					(length 5.08)
					(name "MGTXTXP0_117"
						(effects
							(font
								(size 1.27 1.27)
							)
						)
					)
					(number "K2"
						(effects
							(font
								(size 1.27 1.27)
							)
						)
					)
				)
				(pin bidirectional line
					(at 0 -2.54 0)
					(length 5.08)
					(name "MGTXTXN0_117"
						(effects
							(font
								(size 1.27 1.27)
							)
						)
					)
					(number "K1"
						(effects
							(font
								(size 1.27 1.27)
							)
						)
					)
				)
				(pin bidirectional line
					(at 0 -5.08 0)
					(length 5.08)
					(name "MGTXTXP1_117"
						(effects
							(font
								(size 1.27 1.27)
							)
						)
					)
					(number "J4"
						(effects
							(font
								(size 1.27 1.27)
							)
						)
					)
				)
				(pin bidirectional line
					(at 0 -7.62 0)
					(length 5.08)
					(name "MGTXTXN1_117"
						(effects
							(font
								(size 1.27 1.27)
							)
						)
					)
					(number "J3"
						(effects
							(font
								(size 1.27 1.27)
							)
						)
					)
				)
				(pin bidirectional line
					(at 0 -10.16 0)
					(length 5.08)
					(name "MGTXTXP2_117"
						(effects
							(font
								(size 1.27 1.27)
							)
						)
					)
					(number "H2"
						(effects
							(font
								(size 1.27 1.27)
							)
						)
					)
				)
				(pin bidirectional line
					(at 0 -12.7 0)
					(length 5.08)
					(name "MGTXTXN2_117"
						(effects
							(font
								(size 1.27 1.27)
							)
						)
					)
					(number "H1"
						(effects
							(font
								(size 1.27 1.27)
							)
						)
					)
				)
				(pin bidirectional line
					(at 0 -15.24 0)
					(length 5.08)
					(name "MGTXTXP3_117"
						(effects
							(font
								(size 1.27 1.27)
							)
						)
					)
					(number "F2"
						(effects
							(font
								(size 1.27 1.27)
							)
						)
					)
				)
				(pin bidirectional line
					(at 0 -17.78 0)
					(length 5.08)
					(name "MGTXTXN3_117"
						(effects
							(font
								(size 1.27 1.27)
							)
						)
					)
					(number "F1"
						(effects
							(font
								(size 1.27 1.27)
							)
						)
					)
				)
				(pin bidirectional line
					(at 0 -21.59 0)
					(length 5.08)
					(name "MGTXRXP0_117"
						(effects
							(font
								(size 1.27 1.27)
							)
						)
					)
					(number "K6"
						(effects
							(font
								(size 1.27 1.27)
							)
						)
					)
				)
				(pin bidirectional line
					(at 0 -24.13 0)
					(length 5.08)
					(name "MGTXRXN0_117"
						(effects
							(font
								(size 1.27 1.27)
							)
						)
					)
					(number "K5"
						(effects
							(font
								(size 1.27 1.27)
							)
						)
					)
				)
				(pin bidirectional line
					(at 0 -26.67 0)
					(length 5.08)
					(name "MGTXRXP1_117"
						(effects
							(font
								(size 1.27 1.27)
							)
						)
					)
					(number "H6"
						(effects
							(font
								(size 1.27 1.27)
							)
						)
					)
				)
				(pin bidirectional line
					(at 0 -29.21 0)
					(length 5.08)
					(name "MGTXRXN1_117"
						(effects
							(font
								(size 1.27 1.27)
							)
						)
					)
					(number "H5"
						(effects
							(font
								(size 1.27 1.27)
							)
						)
					)
				)
				(pin bidirectional line
					(at 0 -31.75 0)
					(length 5.08)
					(name "MGTXRXP2_117"
						(effects
							(font
								(size 1.27 1.27)
							)
						)
					)
					(number "G4"
						(effects
							(font
								(size 1.27 1.27)
							)
						)
					)
				)
				(pin bidirectional line
					(at 0 -34.29 0)
					(length 5.08)
					(name "MGTXRXN2_117"
						(effects
							(font
								(size 1.27 1.27)
							)
						)
					)
					(number "G3"
						(effects
							(font
								(size 1.27 1.27)
							)
						)
					)
				)
				(pin bidirectional line
					(at 0 -36.83 0)
					(length 5.08)
					(name "MGTXRXP3_117"
						(effects
							(font
								(size 1.27 1.27)
							)
						)
					)
					(number "F6"
						(effects
							(font
								(size 1.27 1.27)
							)
						)
					)
				)
				(pin bidirectional line
					(at 0 -39.37 0)
					(length 5.08)
					(name "MGTXRXN3_117"
						(effects
							(font
								(size 1.27 1.27)
							)
						)
					)
					(number "F5"
						(effects
							(font
								(size 1.27 1.27)
							)
						)
					)
				)
				(pin bidirectional line
					(at 0 -43.18 0)
					(length 5.08)
					(name "MGTREFCLK0P_117"
						(effects
							(font
								(size 1.27 1.27)
							)
						)
					)
					(number "G8"
						(effects
							(font
								(size 1.27 1.27)
							)
						)
					)
				)
				(pin bidirectional line
					(at 0 -45.72 0)
					(length 5.08)
					(name "MGTREFCLK0N_117"
						(effects
							(font
								(size 1.27 1.27)
							)
						)
					)
					(number "G7"
						(effects
							(font
								(size 1.27 1.27)
							)
						)
					)
				)
				(pin bidirectional line
					(at 0 -48.26 0)
					(length 5.08)
					(name "MGTREFCLK1P_117"
						(effects
							(font
								(size 1.27 1.27)
							)
						)
					)
					(number "J8"
						(effects
							(font
								(size 1.27 1.27)
							)
						)
					)
				)
				(pin bidirectional line
					(at 0 -50.8 0)
					(length 5.08)
					(name "MGTREFCLK1N_117"
						(effects
							(font
								(size 1.27 1.27)
							)
						)
					)
					(number "J7"
						(effects
							(font
								(size 1.27 1.27)
							)
						)
					)
				)
				(pin bidirectional line
					(at 48.26 0 180)
					(length 5.08)
					(name "MGTXTXP0_118"
						(effects
							(font
								(size 1.27 1.27)
							)
						)
					)
					(number "D2"
						(effects
							(font
								(size 1.27 1.27)
							)
						)
					)
				)
				(pin bidirectional line
					(at 48.26 -2.54 180)
					(length 5.08)
					(name "MGTXTXN0_118"
						(effects
							(font
								(size 1.27 1.27)
							)
						)
					)
					(number "D1"
						(effects
							(font
								(size 1.27 1.27)
							)
						)
					)
				)
				(pin bidirectional line
					(at 48.26 -5.08 180)
					(length 5.08)
					(name "MGTXTXP1_118"
						(effects
							(font
								(size 1.27 1.27)
							)
						)
					)
					(number "C4"
						(effects
							(font
								(size 1.27 1.27)
							)
						)
					)
				)
				(pin bidirectional line
					(at 48.26 -7.62 180)
					(length 5.08)
					(name "MGTXTXN1_118"
						(effects
							(font
								(size 1.27 1.27)
							)
						)
					)
					(number "C3"
						(effects
							(font
								(size 1.27 1.27)
							)
						)
					)
				)
				(pin bidirectional line
					(at 48.26 -10.16 180)
					(length 5.08)
					(name "MGTXTXP2_118"
						(effects
							(font
								(size 1.27 1.27)
							)
						)
					)
					(number "B2"
						(effects
							(font
								(size 1.27 1.27)
							)
						)
					)
				)
				(pin bidirectional line
					(at 48.26 -12.7 180)
					(length 5.08)
					(name "MGTXTXN2_118"
						(effects
							(font
								(size 1.27 1.27)
							)
						)
					)
					(number "B1"
						(effects
							(font
								(size 1.27 1.27)
							)
						)
					)
				)
				(pin bidirectional line
					(at 48.26 -15.24 180)
					(length 5.08)
					(name "MGTXTXP3_118"
						(effects
							(font
								(size 1.27 1.27)
							)
						)
					)
					(number "A4"
						(effects
							(font
								(size 1.27 1.27)
							)
						)
					)
				)
				(pin bidirectional line
					(at 48.26 -17.78 180)
					(length 5.08)
					(name "MGTXTXN3_118"
						(effects
							(font
								(size 1.27 1.27)
							)
						)
					)
					(number "A3"
						(effects
							(font
								(size 1.27 1.27)
							)
						)
					)
				)
				(pin bidirectional line
					(at 48.26 -21.59 180)
					(length 5.08)
					(name "MGTXRXP0_118"
						(effects
							(font
								(size 1.27 1.27)
							)
						)
					)
					(number "E4"
						(effects
							(font
								(size 1.27 1.27)
							)
						)
					)
				)
				(pin bidirectional line
					(at 48.26 -24.13 180)
					(length 5.08)
					(name "MGTXRXN0_118"
						(effects
							(font
								(size 1.27 1.27)
							)
						)
					)
					(number "E3"
						(effects
							(font
								(size 1.27 1.27)
							)
						)
					)
				)
				(pin bidirectional line
					(at 48.26 -26.67 180)
					(length 5.08)
					(name "MGTXRXP1_118"
						(effects
							(font
								(size 1.27 1.27)
							)
						)
					)
					(number "D6"
						(effects
							(font
								(size 1.27 1.27)
							)
						)
					)
				)
				(pin bidirectional line
					(at 48.26 -29.21 180)
					(length 5.08)
					(name "MGTXRXN1_118"
						(effects
							(font
								(size 1.27 1.27)
							)
						)
					)
					(number "D5"
						(effects
							(font
								(size 1.27 1.27)
							)
						)
					)
				)
				(pin bidirectional line
					(at 48.26 -31.75 180)
					(length 5.08)
					(name "MGTXRXP2_118"
						(effects
							(font
								(size 1.27 1.27)
							)
						)
					)
					(number "B6"
						(effects
							(font
								(size 1.27 1.27)
							)
						)
					)
				)
				(pin bidirectional line
					(at 48.26 -34.29 180)
					(length 5.08)
					(name "MGTXRXN2_118"
						(effects
							(font
								(size 1.27 1.27)
							)
						)
					)
					(number "B5"
						(effects
							(font
								(size 1.27 1.27)
							)
						)
					)
				)
				(pin bidirectional line
					(at 48.26 -36.83 180)
					(length 5.08)
					(name "MGTXRXP3_118"
						(effects
							(font
								(size 1.27 1.27)
							)
						)
					)
					(number "A8"
						(effects
							(font
								(size 1.27 1.27)
							)
						)
					)
				)
				(pin bidirectional line
					(at 48.26 -39.37 180)
					(length 5.08)
					(name "MGTXRXN3_118"
						(effects
							(font
								(size 1.27 1.27)
							)
						)
					)
					(number "A7"
						(effects
							(font
								(size 1.27 1.27)
							)
						)
					)
				)
				(pin bidirectional line
					(at 48.26 -43.18 180)
					(length 5.08)
					(name "MGTREFCLK0P_118"
						(effects
							(font
								(size 1.27 1.27)
							)
						)
					)
					(number "C8"
						(effects
							(font
								(size 1.27 1.27)
							)
						)
					)
				)
				(pin bidirectional line
					(at 48.26 -45.72 180)
					(length 5.08)
					(name "MGTREFCLK0N_118"
						(effects
							(font
								(size 1.27 1.27)
							)
						)
					)
					(number "C7"
						(effects
							(font
								(size 1.27 1.27)
							)
						)
					)
				)
				(pin bidirectional line
					(at 48.26 -48.26 180)
					(length 5.08)
					(name "MGTREFCLK1P_118"
						(effects
							(font
								(size 1.27 1.27)
							)
						)
					)
					(number "E8"
						(effects
							(font
								(size 1.27 1.27)
							)
						)
					)
				)
				(pin bidirectional line
					(at 48.26 -50.8 180)
					(length 5.08)
					(name "MGTREFCLK1N_118"
						(effects
							(font
								(size 1.27 1.27)
							)
						)
					)
					(number "E7"
						(effects
							(font
								(size 1.27 1.27)
							)
						)
					)
				)
			)
			(symbol "XC7K410T-2FFG900I_4_8_1"
				(rectangle
					(start 5.08 2.54)
					(end 24.13 -13.97)
					(stroke
						(width 0.254)
						(type default)
					)
					(fill
						(type background)
					)
				)
				(pin bidirectional line
					(at 0 0 0)
					(length 5.08)
					(name "MGTAVCC"
						(effects
							(font
								(size 1.27 1.27)
							)
						)
					)
					(number "B7"
						(effects
							(font
								(size 1.27 1.27)
							)
						)
					)
				)
				(pin passive line
					(at 0 0 0)
					(length 5.08)
					(hide yes)
					(name "MGTAVCC"
						(effects
							(font
								(size 1.27 1.27)
							)
						)
					)
					(number "D7"
						(effects
							(font
								(size 1.27 1.27)
							)
						)
					)
				)
				(pin passive line
					(at 0 0 0)
					(length 5.08)
					(hide yes)
					(name "MGTAVCC"
						(effects
							(font
								(size 1.27 1.27)
							)
						)
					)
					(number "F7"
						(effects
							(font
								(size 1.27 1.27)
							)
						)
					)
				)
				(pin passive line
					(at 0 0 0)
					(length 5.08)
					(hide yes)
					(name "MGTAVCC"
						(effects
							(font
								(size 1.27 1.27)
							)
						)
					)
					(number "H7"
						(effects
							(font
								(size 1.27 1.27)
							)
						)
					)
				)
				(pin passive line
					(at 0 0 0)
					(length 5.08)
					(hide yes)
					(name "MGTAVCC"
						(effects
							(font
								(size 1.27 1.27)
							)
						)
					)
					(number "K7"
						(effects
							(font
								(size 1.27 1.27)
							)
						)
					)
				)
				(pin passive line
					(at 0 0 0)
					(length 5.08)
					(hide yes)
					(name "MGTAVCC"
						(effects
							(font
								(size 1.27 1.27)
							)
						)
					)
					(number "M7"
						(effects
							(font
								(size 1.27 1.27)
							)
						)
					)
				)
				(pin passive line
					(at 0 0 0)
					(length 5.08)
					(hide yes)
					(name "MGTAVCC"
						(effects
							(font
								(size 1.27 1.27)
							)
						)
					)
					(number "P7"
						(effects
							(font
								(size 1.27 1.27)
							)
						)
					)
				)
				(pin bidirectional line
					(at 0 -2.54 0)
					(length 5.08)
					(name "MGTVCCAUX"
						(effects
							(font
								(size 1.27 1.27)
							)
						)
					)
					(number "T7"
						(effects
							(font
								(size 1.27 1.27)
							)
						)
					)
				)
				(pin passive line
					(at 0 -2.54 0)
					(length 5.08)
					(hide yes)
					(name "MGTVCCAUX"
						(effects
							(font
								(size 1.27 1.27)
							)
						)
					)
					(number "V7"
						(effects
							(font
								(size 1.27 1.27)
							)
						)
					)
				)
				(pin bidirectional line
					(at 0 -6.35 0)
					(length 5.08)
					(name "MGTAVTTRCAL_115"
						(effects
							(font
								(size 1.27 1.27)
							)
						)
					)
					(number "W7"
						(effects
							(font
								(size 1.27 1.27)
							)
						)
					)
				)
				(pin bidirectional line
					(at 0 -8.89 0)
					(length 5.08)
					(name "MGTAVTT"
						(effects
							(font
								(size 1.27 1.27)
							)
						)
					)
					(number "B3"
						(effects
							(font
								(size 1.27 1.27)
							)
						)
					)
				)
				(pin passive line
					(at 0 -8.89 0)
					(length 5.08)
					(hide yes)
					(name "MGTAVTT"
						(effects
							(font
								(size 1.27 1.27)
							)
						)
					)
					(number "C5"
						(effects
							(font
								(size 1.27 1.27)
							)
						)
					)
				)
				(pin passive line
					(at 0 -8.89 0)
					(length 5.08)
					(hide yes)
					(name "MGTAVTT"
						(effects
							(font
								(size 1.27 1.27)
							)
						)
					)
					(number "D3"
						(effects
							(font
								(size 1.27 1.27)
							)
						)
					)
				)
				(pin passive line
					(at 0 -8.89 0)
					(length 5.08)
					(hide yes)
					(name "MGTAVTT"
						(effects
							(font
								(size 1.27 1.27)
							)
						)
					)
					(number "E5"
						(effects
							(font
								(size 1.27 1.27)
							)
						)
					)
				)
				(pin passive line
					(at 0 -8.89 0)
					(length 5.08)
					(hide yes)
					(name "MGTAVTT"
						(effects
							(font
								(size 1.27 1.27)
							)
						)
					)
					(number "F3"
						(effects
							(font
								(size 1.27 1.27)
							)
						)
					)
				)
				(pin passive line
					(at 0 -8.89 0)
					(length 5.08)
					(hide yes)
					(name "MGTAVTT"
						(effects
							(font
								(size 1.27 1.27)
							)
						)
					)
					(number "G5"
						(effects
							(font
								(size 1.27 1.27)
							)
						)
					)
				)
				(pin passive line
					(at 0 -8.89 0)
					(length 5.08)
					(hide yes)
					(name "MGTAVTT"
						(effects
							(font
								(size 1.27 1.27)
							)
						)
					)
					(number "H3"
						(effects
							(font
								(size 1.27 1.27)
							)
						)
					)
				)
				(pin passive line
					(at 0 -8.89 0)
					(length 5.08)
					(hide yes)
					(name "MGTAVTT"
						(effects
							(font
								(size 1.27 1.27)
							)
						)
					)
					(number "J5"
						(effects
							(font
								(size 1.27 1.27)
							)
						)
					)
				)
				(pin passive line
					(at 0 -8.89 0)
					(length 5.08)
					(hide yes)
					(name "MGTAVTT"
						(effects
							(font
								(size 1.27 1.27)
							)
						)
					)
					(number "K3"
						(effects
							(font
								(size 1.27 1.27)
							)
						)
					)
				)
				(pin passive line
					(at 0 -8.89 0)
					(length 5.08)
					(hide yes)
					(name "MGTAVTT"
						(effects
							(font
								(size 1.27 1.27)
							)
						)
					)
					(number "L5"
						(effects
							(font
								(size 1.27 1.27)
							)
						)
					)
				)
				(pin passive line
					(at 0 -8.89 0)
					(length 5.08)
					(hide yes)
					(name "MGTAVTT"
						(effects
							(font
								(size 1.27 1.27)
							)
						)
					)
					(number "M3"
						(effects
							(font
								(size 1.27 1.27)
							)
						)
					)
				)
				(pin passive line
					(at 0 -8.89 0)
					(length 5.08)
					(hide yes)
					(name "MGTAVTT"
						(effects
							(font
								(size 1.27 1.27)
							)
						)
					)
					(number "N5"
						(effects
							(font
								(size 1.27 1.27)
							)
						)
					)
				)
				(pin passive line
					(at 0 -8.89 0)
					(length 5.08)
					(hide yes)
					(name "MGTAVTT"
						(effects
							(font
								(size 1.27 1.27)
							)
						)
					)
					(number "P3"
						(effects
							(font
								(size 1.27 1.27)
							)
						)
					)
				)
				(pin passive line
					(at 0 -8.89 0)
					(length 5.08)
					(hide yes)
					(name "MGTAVTT"
						(effects
							(font
								(size 1.27 1.27)
							)
						)
					)
					(number "R5"
						(effects
							(font
								(size 1.27 1.27)
							)
						)
					)
				)
				(pin passive line
					(at 0 -8.89 0)
					(length 5.08)
					(hide yes)
					(name "MGTAVTT"
						(effects
							(font
								(size 1.27 1.27)
							)
						)
					)
					(number "T3"
						(effects
							(font
								(size 1.27 1.27)
							)
						)
					)
				)
				(pin passive line
					(at 0 -8.89 0)
					(length 5.08)
					(hide yes)
					(name "MGTAVTT"
						(effects
							(font
								(size 1.27 1.27)
							)
						)
					)
					(number "U5"
						(effects
							(font
								(size 1.27 1.27)
							)
						)
					)
				)
				(pin passive line
					(at 0 -8.89 0)
					(length 5.08)
					(hide yes)
					(name "MGTAVTT"
						(effects
							(font
								(size 1.27 1.27)
							)
						)
					)
					(number "V3"
						(effects
							(font
								(size 1.27 1.27)
							)
						)
					)
				)
				(pin passive line
					(at 0 -8.89 0)
					(length 5.08)
					(hide yes)
					(name "MGTAVTT"
						(effects
							(font
								(size 1.27 1.27)
							)
						)
					)
					(number "W5"
						(effects
							(font
								(size 1.27 1.27)
							)
						)
					)
				)
				(pin bidirectional line
					(at 0 -11.43 0)
					(length 5.08)
					(name "MGTRREF_115"
						(effects
							(font
								(size 1.27 1.27)
							)
						)
					)
					(number "W8"
						(effects
							(font
								(size 1.27 1.27)
							)
						)
					)
				)
			)
			(symbol "XC7K410T-2FFG900I_4_9_1"
				(rectangle
					(start 5.08 2.54)
					(end 27.94 -29.21)
					(stroke
						(width 0.254)
						(type default)
					)
					(fill
						(type background)
					)
				)
				(pin bidirectional line
					(at 0 0 0)
					(length 5.08)
					(name "VCCO_0"
						(effects
							(font
								(size 1.27 1.27)
							)
						)
					)
					(number "AB6"
						(effects
							(font
								(size 1.27 1.27)
							)
						)
					)
				)
				(pin passive line
					(at 0 0 0)
					(length 5.08)
					(hide yes)
					(name "VCCO_0"
						(effects
							(font
								(size 1.27 1.27)
							)
						)
					)
					(number "T9"
						(effects
							(font
								(size 1.27 1.27)
							)
						)
					)
				)
				(pin bidirectional line
					(at 0 -3.81 0)
					(length 5.08)
					(name "CCLK_0"
						(effects
							(font
								(size 1.27 1.27)
							)
						)
					)
					(number "B10"
						(effects
							(font
								(size 1.27 1.27)
							)
						)
					)
				)
				(pin bidirectional line
					(at 0 -6.35 0)
					(length 5.08)
					(name "M0_0"
						(effects
							(font
								(size 1.27 1.27)
							)
						)
					)
					(number "AB5"
						(effects
							(font
								(size 1.27 1.27)
							)
						)
					)
				)
				(pin bidirectional line
					(at 0 -8.89 0)
					(length 5.08)
					(name "M1_0"
						(effects
							(font
								(size 1.27 1.27)
							)
						)
					)
					(number "AB2"
						(effects
							(font
								(size 1.27 1.27)
							)
						)
					)
				)
				(pin bidirectional line
					(at 0 -11.43 0)
					(length 5.08)
					(name "M2_0"
						(effects
							(font
								(size 1.27 1.27)
							)
						)
					)
					(number "AB1"
						(effects
							(font
								(size 1.27 1.27)
							)
						)
					)
				)
				(pin bidirectional line
					(at 0 -15.24 0)
					(length 5.08)
					(name "TDI_0"
						(effects
							(font
								(size 1.27 1.27)
							)
						)
					)
					(number "H10"
						(effects
							(font
								(size 1.27 1.27)
							)
						)
					)
				)
				(pin bidirectional line
					(at 0 -17.78 0)
					(length 5.08)
					(name "TDO_0"
						(effects
							(font
								(size 1.27 1.27)
							)
						)
					)
					(number "G10"
						(effects
							(font
								(size 1.27 1.27)
							)
						)
					)
				)
				(pin bidirectional line
					(at 0 -20.32 0)
					(length 5.08)
					(name "TMS_0"
						(effects
							(font
								(size 1.27 1.27)
							)
						)
					)
					(number "F10"
						(effects
							(font
								(size 1.27 1.27)
							)
						)
					)
				)
				(pin bidirectional line
					(at 0 -22.86 0)
					(length 5.08)
					(name "TCK_0"
						(effects
							(font
								(size 1.27 1.27)
							)
						)
					)
					(number "E10"
						(effects
							(font
								(size 1.27 1.27)
							)
						)
					)
				)
				(pin bidirectional line
					(at 0 -26.67 0)
					(length 5.08)
					(name "CFGBVS_0"
						(effects
							(font
								(size 1.27 1.27)
							)
						)
					)
					(number "L10"
						(effects
							(font
								(size 1.27 1.27)
							)
						)
					)
				)
				(pin bidirectional line
					(at 33.02 0 180)
					(length 5.08)
					(name "DONE_0"
						(effects
							(font
								(size 1.27 1.27)
							)
						)
					)
					(number "M10"
						(effects
							(font
								(size 1.27 1.27)
							)
						)
					)
				)
				(pin bidirectional line
					(at 33.02 -2.54 180)
					(length 5.08)
					(name "INIT_B_0"
						(effects
							(font
								(size 1.27 1.27)
							)
						)
					)
					(number "A10"
						(effects
							(font
								(size 1.27 1.27)
							)
						)
					)
				)
				(pin bidirectional line
					(at 33.02 -5.08 180)
					(length 5.08)
					(name "PROGRAM_B_0"
						(effects
							(font
								(size 1.27 1.27)
							)
						)
					)
					(number "K10"
						(effects
							(font
								(size 1.27 1.27)
							)
						)
					)
				)
				(pin bidirectional line
					(at 33.02 -8.89 180)
					(length 5.08)
					(name "VP_0"
						(effects
							(font
								(size 1.27 1.27)
							)
						)
					)
					(number "R15"
						(effects
							(font
								(size 1.27 1.27)
							)
						)
					)
				)
				(pin bidirectional line
					(at 33.02 -11.43 180)
					(length 5.08)
					(name "VN_0"
						(effects
							(font
								(size 1.27 1.27)
							)
						)
					)
					(number "T14"
						(effects
							(font
								(size 1.27 1.27)
							)
						)
					)
				)
				(pin bidirectional line
					(at 33.02 -15.24 180)
					(length 5.08)
					(name "VREFP_0"
						(effects
							(font
								(size 1.27 1.27)
							)
						)
					)
					(number "T15"
						(effects
							(font
								(size 1.27 1.27)
							)
						)
					)
				)
				(pin bidirectional line
					(at 33.02 -17.78 180)
					(length 5.08)
					(name "VREFN_0"
						(effects
							(font
								(size 1.27 1.27)
							)
						)
					)
					(number "R14"
						(effects
							(font
								(size 1.27 1.27)
							)
						)
					)
				)
				(pin bidirectional line
					(at 33.02 -21.59 180)
					(length 5.08)
					(name "DXP_0"
						(effects
							(font
								(size 1.27 1.27)
							)
						)
					)
					(number "U15"
						(effects
							(font
								(size 1.27 1.27)
							)
						)
					)
				)
				(pin bidirectional line
					(at 33.02 -24.13 180)
					(length 5.08)
					(name "DXN_0"
						(effects
							(font
								(size 1.27 1.27)
							)
						)
					)
					(number "U14"
						(effects
							(font
								(size 1.27 1.27)
							)
						)
					)
				)
			)
			(symbol "XC7K410T-2FFG900I_4_10_1"
				(rectangle
					(start 5.08 2.54)
					(end 20.32 -21.59)
					(stroke
						(width 0.254)
						(type default)
					)
					(fill
						(type background)
					)
				)
				(pin bidirectional line
					(at 0 0 0)
					(length 5.08)
					(name "VCCAUX"
						(effects
							(font
								(size 1.27 1.27)
							)
						)
					)
					(number "P13"
						(effects
							(font
								(size 1.27 1.27)
							)
						)
					)
				)
				(pin passive line
					(at 0 0 0)
					(length 5.08)
					(hide yes)
					(name "VCCAUX"
						(effects
							(font
								(size 1.27 1.27)
							)
						)
					)
					(number "T13"
						(effects
							(font
								(size 1.27 1.27)
							)
						)
					)
				)
				(pin passive line
					(at 0 0 0)
					(length 5.08)
					(hide yes)
					(name "VCCAUX"
						(effects
							(font
								(size 1.27 1.27)
							)
						)
					)
					(number "V13"
						(effects
							(font
								(size 1.27 1.27)
							)
						)
					)
				)
				(pin passive line
					(at 0 0 0)
					(length 5.08)
					(hide yes)
					(name "VCCAUX"
						(effects
							(font
								(size 1.27 1.27)
							)
						)
					)
					(number "V15"
						(effects
							(font
								(size 1.27 1.27)
							)
						)
					)
				)
				(pin passive line
					(at 0 0 0)
					(length 5.08)
					(hide yes)
					(name "VCCAUX"
						(effects
							(font
								(size 1.27 1.27)
							)
						)
					)
					(number "W14"
						(effects
							(font
								(size 1.27 1.27)
							)
						)
					)
				)
				(pin bidirectional line
					(at 0 -2.54 0)
					(length 5.08)
					(name "VCCAUX_IO_G0"
						(effects
							(font
								(size 1.27 1.27)
							)
						)
					)
					(number "V11"
						(effects
							(font
								(size 1.27 1.27)
							)
						)
					)
				)
				(pin passive line
					(at 0 -2.54 0)
					(length 5.08)
					(hide yes)
					(name "VCCAUX_IO_G0"
						(effects
							(font
								(size 1.27 1.27)
							)
						)
					)
					(number "W10"
						(effects
							(font
								(size 1.27 1.27)
							)
						)
					)
				)
				(pin passive line
					(at 0 -2.54 0)
					(length 5.08)
					(hide yes)
					(name "VCCAUX_IO_G0"
						(effects
							(font
								(size 1.27 1.27)
							)
						)
					)
					(number "W12"
						(effects
							(font
								(size 1.27 1.27)
							)
						)
					)
				)
				(pin bidirectional line
					(at 0 -5.08 0)
					(length 5.08)
					(name "VCCADC_0"
						(effects
							(font
								(size 1.27 1.27)
							)
						)
					)
					(number "P15"
						(effects
							(font
								(size 1.27 1.27)
							)
						)
					)
				)
				(pin bidirectional line
					(at 0 -7.62 0)
					(length 5.08)
					(name "VCCBRAM"
						(effects
							(font
								(size 1.27 1.27)
							)
						)
					)
					(number "N16"
						(effects
							(font
								(size 1.27 1.27)
							)
						)
					)
				)
				(pin passive line
					(at 0 -7.62 0)
					(length 5.08)
					(hide yes)
					(name "VCCBRAM"
						(effects
							(font
								(size 1.27 1.27)
							)
						)
					)
					(number "R16"
						(effects
							(font
								(size 1.27 1.27)
							)
						)
					)
				)
				(pin passive line
					(at 0 -7.62 0)
					(length 5.08)
					(hide yes)
					(name "VCCBRAM"
						(effects
							(font
								(size 1.27 1.27)
							)
						)
					)
					(number "U16"
						(effects
							(font
								(size 1.27 1.27)
							)
						)
					)
				)
				(pin passive line
					(at 0 -7.62 0)
					(length 5.08)
					(hide yes)
					(name "VCCBRAM"
						(effects
							(font
								(size 1.27 1.27)
							)
						)
					)
					(number "W16"
						(effects
							(font
								(size 1.27 1.27)
							)
						)
					)
				)
				(pin bidirectional line
					(at 0 -10.16 0)
					(length 5.08)
					(name "VCCINT"
						(effects
							(font
								(size 1.27 1.27)
							)
						)
					)
					(number "M11"
						(effects
							(font
								(size 1.27 1.27)
							)
						)
					)
				)
				(pin passive line
					(at 0 -10.16 0)
					(length 5.08)
					(hide yes)
					(name "VCCINT"
						(effects
							(font
								(size 1.27 1.27)
							)
						)
					)
					(number "M13"
						(effects
							(font
								(size 1.27 1.27)
							)
						)
					)
				)
				(pin passive line
					(at 0 -10.16 0)
					(length 5.08)
					(hide yes)
					(name "VCCINT"
						(effects
							(font
								(size 1.27 1.27)
							)
						)
					)
					(number "M15"
						(effects
							(font
								(size 1.27 1.27)
							)
						)
					)
				)
				(pin passive line
					(at 0 -10.16 0)
					(length 5.08)
					(hide yes)
					(name "VCCINT"
						(effects
							(font
								(size 1.27 1.27)
							)
						)
					)
					(number "M17"
						(effects
							(font
								(size 1.27 1.27)
							)
						)
					)
				)
				(pin passive line
					(at 0 -10.16 0)
					(length 5.08)
					(hide yes)
					(name "VCCINT"
						(effects
							(font
								(size 1.27 1.27)
							)
						)
					)
					(number "N10"
						(effects
							(font
								(size 1.27 1.27)
							)
						)
					)
				)
				(pin passive line
					(at 0 -10.16 0)
					(length 5.08)
					(hide yes)
					(name "VCCINT"
						(effects
							(font
								(size 1.27 1.27)
							)
						)
					)
					(number "N12"
						(effects
							(font
								(size 1.27 1.27)
							)
						)
					)
				)
				(pin passive line
					(at 0 -10.16 0)
					(length 5.08)
					(hide yes)
					(name "VCCINT"
						(effects
							(font
								(size 1.27 1.27)
							)
						)
					)
					(number "N14"
						(effects
							(font
								(size 1.27 1.27)
							)
						)
					)
				)
				(pin passive line
					(at 0 -10.16 0)
					(length 5.08)
					(hide yes)
					(name "VCCINT"
						(effects
							(font
								(size 1.27 1.27)
							)
						)
					)
					(number "N18"
						(effects
							(font
								(size 1.27 1.27)
							)
						)
					)
				)
				(pin passive line
					(at 0 -10.16 0)
					(length 5.08)
					(hide yes)
					(name "VCCINT"
						(effects
							(font
								(size 1.27 1.27)
							)
						)
					)
					(number "P11"
						(effects
							(font
								(size 1.27 1.27)
							)
						)
					)
				)
				(pin passive line
					(at 0 -10.16 0)
					(length 5.08)
					(hide yes)
					(name "VCCINT"
						(effects
							(font
								(size 1.27 1.27)
							)
						)
					)
					(number "P17"
						(effects
							(font
								(size 1.27 1.27)
							)
						)
					)
				)
				(pin passive line
					(at 0 -10.16 0)
					(length 5.08)
					(hide yes)
					(name "VCCINT"
						(effects
							(font
								(size 1.27 1.27)
							)
						)
					)
					(number "R10"
						(effects
							(font
								(size 1.27 1.27)
							)
						)
					)
				)
				(pin passive line
					(at 0 -10.16 0)
					(length 5.08)
					(hide yes)
					(name "VCCINT"
						(effects
							(font
								(size 1.27 1.27)
							)
						)
					)
					(number "R12"
						(effects
							(font
								(size 1.27 1.27)
							)
						)
					)
				)
				(pin passive line
					(at 0 -10.16 0)
					(length 5.08)
					(hide yes)
					(name "VCCINT"
						(effects
							(font
								(size 1.27 1.27)
							)
						)
					)
					(number "R18"
						(effects
							(font
								(size 1.27 1.27)
							)
						)
					)
				)
				(pin passive line
					(at 0 -10.16 0)
					(length 5.08)
					(hide yes)
					(name "VCCINT"
						(effects
							(font
								(size 1.27 1.27)
							)
						)
					)
					(number "T11"
						(effects
							(font
								(size 1.27 1.27)
							)
						)
					)
				)
				(pin passive line
					(at 0 -10.16 0)
					(length 5.08)
					(hide yes)
					(name "VCCINT"
						(effects
							(font
								(size 1.27 1.27)
							)
						)
					)
					(number "T17"
						(effects
							(font
								(size 1.27 1.27)
							)
						)
					)
				)
				(pin passive line
					(at 0 -10.16 0)
					(length 5.08)
					(hide yes)
					(name "VCCINT"
						(effects
							(font
								(size 1.27 1.27)
							)
						)
					)
					(number "U10"
						(effects
							(font
								(size 1.27 1.27)
							)
						)
					)
				)
				(pin passive line
					(at 0 -10.16 0)
					(length 5.08)
					(hide yes)
					(name "VCCINT"
						(effects
							(font
								(size 1.27 1.27)
							)
						)
					)
					(number "U12"
						(effects
							(font
								(size 1.27 1.27)
							)
						)
					)
				)
				(pin passive line
					(at 0 -10.16 0)
					(length 5.08)
					(hide yes)
					(name "VCCINT"
						(effects
							(font
								(size 1.27 1.27)
							)
						)
					)
					(number "U18"
						(effects
							(font
								(size 1.27 1.27)
							)
						)
					)
				)
				(pin passive line
					(at 0 -10.16 0)
					(length 5.08)
					(hide yes)
					(name "VCCINT"
						(effects
							(font
								(size 1.27 1.27)
							)
						)
					)
					(number "V17"
						(effects
							(font
								(size 1.27 1.27)
							)
						)
					)
				)
				(pin passive line
					(at 0 -10.16 0)
					(length 5.08)
					(hide yes)
					(name "VCCINT"
						(effects
							(font
								(size 1.27 1.27)
							)
						)
					)
					(number "W18"
						(effects
							(font
								(size 1.27 1.27)
							)
						)
					)
				)
				(pin bidirectional line
					(at 0 -12.7 0)
					(length 5.08)
					(name "VCCBATT_0"
						(effects
							(font
								(size 1.27 1.27)
							)
						)
					)
					(number "C10"
						(effects
							(font
								(size 1.27 1.27)
							)
						)
					)
				)
				(pin bidirectional line
					(at 0 -16.51 0)
					(length 5.08)
					(name "GNDADC_0"
						(effects
							(font
								(size 1.27 1.27)
							)
						)
					)
					(number "P14"
						(effects
							(font
								(size 1.27 1.27)
							)
						)
					)
				)
				(pin bidirectional line
					(at 0 -19.05 0)
					(length 5.08)
					(name "GND"
						(effects
							(font
								(size 1.27 1.27)
							)
						)
					)
					(number "A1"
						(effects
							(font
								(size 1.27 1.27)
							)
						)
					)
				)
				(pin passive line
					(at 0 -19.05 0)
					(length 5.08)
					(hide yes)
					(name "GND"
						(effects
							(font
								(size 1.27 1.27)
							)
						)
					)
					(number "A14"
						(effects
							(font
								(size 1.27 1.27)
							)
						)
					)
				)
				(pin passive line
					(at 0 -19.05 0)
					(length 5.08)
					(hide yes)
					(name "GND"
						(effects
							(font
								(size 1.27 1.27)
							)
						)
					)
					(number "A2"
						(effects
							(font
								(size 1.27 1.27)
							)
						)
					)
				)
				(pin passive line
					(at 0 -19.05 0)
					(length 5.08)
					(hide yes)
					(name "GND"
						(effects
							(font
								(size 1.27 1.27)
							)
						)
					)
					(number "A24"
						(effects
							(font
								(size 1.27 1.27)
							)
						)
					)
				)
				(pin passive line
					(at 0 -19.05 0)
					(length 5.08)
					(hide yes)
					(name "GND"
						(effects
							(font
								(size 1.27 1.27)
							)
						)
					)
					(number "A5"
						(effects
							(font
								(size 1.27 1.27)
							)
						)
					)
				)
				(pin passive line
					(at 0 -19.05 0)
					(length 5.08)
					(hide yes)
					(name "GND"
						(effects
							(font
								(size 1.27 1.27)
							)
						)
					)
					(number "A6"
						(effects
							(font
								(size 1.27 1.27)
							)
						)
					)
				)
				(pin passive line
					(at 0 -19.05 0)
					(length 5.08)
					(hide yes)
					(name "GND"
						(effects
							(font
								(size 1.27 1.27)
							)
						)
					)
					(number "A9"
						(effects
							(font
								(size 1.27 1.27)
							)
						)
					)
				)
				(pin passive line
					(at 0 -19.05 0)
					(length 5.08)
					(hide yes)
					(name "GND"
						(effects
							(font
								(size 1.27 1.27)
							)
						)
					)
					(number "AA1"
						(effects
							(font
								(size 1.27 1.27)
							)
						)
					)
				)
				(pin passive line
					(at 0 -19.05 0)
					(length 5.08)
					(hide yes)
					(name "GND"
						(effects
							(font
								(size 1.27 1.27)
							)
						)
					)
					(number "AA14"
						(effects
							(font
								(size 1.27 1.27)
							)
						)
					)
				)
				(pin passive line
					(at 0 -19.05 0)
					(length 5.08)
					(hide yes)
					(name "GND"
						(effects
							(font
								(size 1.27 1.27)
							)
						)
					)
					(number "AA2"
						(effects
							(font
								(size 1.27 1.27)
							)
						)
					)
				)
				(pin passive line
					(at 0 -19.05 0)
					(length 5.08)
					(hide yes)
					(name "GND"
						(effects
							(font
								(size 1.27 1.27)
							)
						)
					)
					(number "AA24"
						(effects
							(font
								(size 1.27 1.27)
							)
						)
					)
				)
				(pin passive line
					(at 0 -19.05 0)
					(length 5.08)
					(hide yes)
					(name "GND"
						(effects
							(font
								(size 1.27 1.27)
							)
						)
					)
					(number "AA5"
						(effects
							(font
								(size 1.27 1.27)
							)
						)
					)
				)
				(pin passive line
					(at 0 -19.05 0)
					(length 5.08)
					(hide yes)
					(name "GND"
						(effects
							(font
								(size 1.27 1.27)
							)
						)
					)
					(number "AA6"
						(effects
							(font
								(size 1.27 1.27)
							)
						)
					)
				)
				(pin passive line
					(at 0 -19.05 0)
					(length 5.08)
					(hide yes)
					(name "GND"
						(effects
							(font
								(size 1.27 1.27)
							)
						)
					)
					(number "AA7"
						(effects
							(font
								(size 1.27 1.27)
							)
						)
					)
				)
				(pin passive line
					(at 0 -19.05 0)
					(length 5.08)
					(hide yes)
					(name "GND"
						(effects
							(font
								(size 1.27 1.27)
							)
						)
					)
					(number "AB11"
						(effects
							(font
								(size 1.27 1.27)
							)
						)
					)
				)
				(pin passive line
					(at 0 -19.05 0)
					(length 5.08)
					(hide yes)
					(name "GND"
						(effects
							(font
								(size 1.27 1.27)
							)
						)
					)
					(number "AB21"
						(effects
							(font
								(size 1.27 1.27)
							)
						)
					)
				)
				(pin passive line
					(at 0 -19.05 0)
					(length 5.08)
					(hide yes)
					(name "GND"
						(effects
							(font
								(size 1.27 1.27)
							)
						)
					)
					(number "AB3"
						(effects
							(font
								(size 1.27 1.27)
							)
						)
					)
				)
				(pin passive line
					(at 0 -19.05 0)
					(length 5.08)
					(hide yes)
					(name "GND"
						(effects
							(font
								(size 1.27 1.27)
							)
						)
					)
					(number "AB4"
						(effects
							(font
								(size 1.27 1.27)
							)
						)
					)
				)
				(pin passive line
					(at 0 -19.05 0)
					(length 5.08)
					(hide yes)
					(name "GND"
						(effects
							(font
								(size 1.27 1.27)
							)
						)
					)
					(number "AC18"
						(effects
							(font
								(size 1.27 1.27)
							)
						)
					)
				)
				(pin passive line
					(at 0 -19.05 0)
					(length 5.08)
					(hide yes)
					(name "GND"
						(effects
							(font
								(size 1.27 1.27)
							)
						)
					)
					(number "AC28"
						(effects
							(font
								(size 1.27 1.27)
							)
						)
					)
				)
				(pin passive line
					(at 0 -19.05 0)
					(length 5.08)
					(hide yes)
					(name "GND"
						(effects
							(font
								(size 1.27 1.27)
							)
						)
					)
					(number "AC8"
						(effects
							(font
								(size 1.27 1.27)
							)
						)
					)
				)
				(pin passive line
					(at 0 -19.05 0)
					(length 5.08)
					(hide yes)
					(name "GND"
						(effects
							(font
								(size 1.27 1.27)
							)
						)
					)
					(number "AD15"
						(effects
							(font
								(size 1.27 1.27)
							)
						)
					)
				)
				(pin passive line
					(at 0 -19.05 0)
					(length 5.08)
					(hide yes)
					(name "GND"
						(effects
							(font
								(size 1.27 1.27)
							)
						)
					)
					(number "AD25"
						(effects
							(font
								(size 1.27 1.27)
							)
						)
					)
				)
				(pin passive line
					(at 0 -19.05 0)
					(length 5.08)
					(hide yes)
					(name "GND"
						(effects
							(font
								(size 1.27 1.27)
							)
						)
					)
					(number "AD5"
						(effects
							(font
								(size 1.27 1.27)
							)
						)
					)
				)
				(pin passive line
					(at 0 -19.05 0)
					(length 5.08)
					(hide yes)
					(name "GND"
						(effects
							(font
								(size 1.27 1.27)
							)
						)
					)
					(number "AE12"
						(effects
							(font
								(size 1.27 1.27)
							)
						)
					)
				)
				(pin passive line
					(at 0 -19.05 0)
					(length 5.08)
					(hide yes)
					(name "GND"
						(effects
							(font
								(size 1.27 1.27)
							)
						)
					)
					(number "AE2"
						(effects
							(font
								(size 1.27 1.27)
							)
						)
					)
				)
				(pin passive line
					(at 0 -19.05 0)
					(length 5.08)
					(hide yes)
					(name "GND"
						(effects
							(font
								(size 1.27 1.27)
							)
						)
					)
					(number "AE22"
						(effects
							(font
								(size 1.27 1.27)
							)
						)
					)
				)
				(pin passive line
					(at 0 -19.05 0)
					(length 5.08)
					(hide yes)
					(name "GND"
						(effects
							(font
								(size 1.27 1.27)
							)
						)
					)
					(number "AF19"
						(effects
							(font
								(size 1.27 1.27)
							)
						)
					)
				)
				(pin passive line
					(at 0 -19.05 0)
					(length 5.08)
					(hide yes)
					(name "GND"
						(effects
							(font
								(size 1.27 1.27)
							)
						)
					)
					(number "AF29"
						(effects
							(font
								(size 1.27 1.27)
							)
						)
					)
				)
				(pin passive line
					(at 0 -19.05 0)
					(length 5.08)
					(hide yes)
					(name "GND"
						(effects
							(font
								(size 1.27 1.27)
							)
						)
					)
					(number "AF9"
						(effects
							(font
								(size 1.27 1.27)
							)
						)
					)
				)
				(pin passive line
					(at 0 -19.05 0)
					(length 5.08)
					(hide yes)
					(name "GND"
						(effects
							(font
								(size 1.27 1.27)
							)
						)
					)
					(number "AG16"
						(effects
							(font
								(size 1.27 1.27)
							)
						)
					)
				)
				(pin passive line
					(at 0 -19.05 0)
					(length 5.08)
					(hide yes)
					(name "GND"
						(effects
							(font
								(size 1.27 1.27)
							)
						)
					)
					(number "AG26"
						(effects
							(font
								(size 1.27 1.27)
							)
						)
					)
				)
				(pin passive line
					(at 0 -19.05 0)
					(length 5.08)
					(hide yes)
					(name "GND"
						(effects
							(font
								(size 1.27 1.27)
							)
						)
					)
					(number "AG6"
						(effects
							(font
								(size 1.27 1.27)
							)
						)
					)
				)
				(pin passive line
					(at 0 -19.05 0)
					(length 5.08)
					(hide yes)
					(name "GND"
						(effects
							(font
								(size 1.27 1.27)
							)
						)
					)
					(number "AH13"
						(effects
							(font
								(size 1.27 1.27)
							)
						)
					)
				)
				(pin passive line
					(at 0 -19.05 0)
					(length 5.08)
					(hide yes)
					(name "GND"
						(effects
							(font
								(size 1.27 1.27)
							)
						)
					)
					(number "AH23"
						(effects
							(font
								(size 1.27 1.27)
							)
						)
					)
				)
				(pin passive line
					(at 0 -19.05 0)
					(length 5.08)
					(hide yes)
					(name "GND"
						(effects
							(font
								(size 1.27 1.27)
							)
						)
					)
					(number "AH3"
						(effects
							(font
								(size 1.27 1.27)
							)
						)
					)
				)
				(pin passive line
					(at 0 -19.05 0)
					(length 5.08)
					(hide yes)
					(name "GND"
						(effects
							(font
								(size 1.27 1.27)
							)
						)
					)
					(number "AJ10"
						(effects
							(font
								(size 1.27 1.27)
							)
						)
					)
				)
				(pin passive line
					(at 0 -19.05 0)
					(length 5.08)
					(hide yes)
					(name "GND"
						(effects
							(font
								(size 1.27 1.27)
							)
						)
					)
					(number "AJ20"
						(effects
							(font
								(size 1.27 1.27)
							)
						)
					)
				)
				(pin passive line
					(at 0 -19.05 0)
					(length 5.08)
					(hide yes)
					(name "GND"
						(effects
							(font
								(size 1.27 1.27)
							)
						)
					)
					(number "AJ30"
						(effects
							(font
								(size 1.27 1.27)
							)
						)
					)
				)
				(pin passive line
					(at 0 -19.05 0)
					(length 5.08)
					(hide yes)
					(name "GND"
						(effects
							(font
								(size 1.27 1.27)
							)
						)
					)
					(number "AK17"
						(effects
							(font
								(size 1.27 1.27)
							)
						)
					)
				)
				(pin passive line
					(at 0 -19.05 0)
					(length 5.08)
					(hide yes)
					(name "GND"
						(effects
							(font
								(size 1.27 1.27)
							)
						)
					)
					(number "AK27"
						(effects
							(font
								(size 1.27 1.27)
							)
						)
					)
				)
				(pin passive line
					(at 0 -19.05 0)
					(length 5.08)
					(hide yes)
					(name "GND"
						(effects
							(font
								(size 1.27 1.27)
							)
						)
					)
					(number "AK7"
						(effects
							(font
								(size 1.27 1.27)
							)
						)
					)
				)
				(pin passive line
					(at 0 -19.05 0)
					(length 5.08)
					(hide yes)
					(name "GND"
						(effects
							(font
								(size 1.27 1.27)
							)
						)
					)
					(number "B11"
						(effects
							(font
								(size 1.27 1.27)
							)
						)
					)
				)
				(pin passive line
					(at 0 -19.05 0)
					(length 5.08)
					(hide yes)
					(name "GND"
						(effects
							(font
								(size 1.27 1.27)
							)
						)
					)
					(number "B21"
						(effects
							(font
								(size 1.27 1.27)
							)
						)
					)
				)
				(pin passive line
					(at 0 -19.05 0)
					(length 5.08)
					(hide yes)
					(name "GND"
						(effects
							(font
								(size 1.27 1.27)
							)
						)
					)
					(number "B4"
						(effects
							(font
								(size 1.27 1.27)
							)
						)
					)
				)
				(pin passive line
					(at 0 -19.05 0)
					(length 5.08)
					(hide yes)
					(name "GND"
						(effects
							(font
								(size 1.27 1.27)
							)
						)
					)
					(number "B8"
						(effects
							(font
								(size 1.27 1.27)
							)
						)
					)
				)
				(pin passive line
					(at 0 -19.05 0)
					(length 5.08)
					(hide yes)
					(name "GND"
						(effects
							(font
								(size 1.27 1.27)
							)
						)
					)
					(number "B9"
						(effects
							(font
								(size 1.27 1.27)
							)
						)
					)
				)
				(pin passive line
					(at 0 -19.05 0)
					(length 5.08)
					(hide yes)
					(name "GND"
						(effects
							(font
								(size 1.27 1.27)
							)
						)
					)
					(number "C1"
						(effects
							(font
								(size 1.27 1.27)
							)
						)
					)
				)
				(pin passive line
					(at 0 -19.05 0)
					(length 5.08)
					(hide yes)
					(name "GND"
						(effects
							(font
								(size 1.27 1.27)
							)
						)
					)
					(number "C18"
						(effects
							(font
								(size 1.27 1.27)
							)
						)
					)
				)
				(pin passive line
					(at 0 -19.05 0)
					(length 5.08)
					(hide yes)
					(name "GND"
						(effects
							(font
								(size 1.27 1.27)
							)
						)
					)
					(number "C2"
						(effects
							(font
								(size 1.27 1.27)
							)
						)
					)
				)
				(pin passive line
					(at 0 -19.05 0)
					(length 5.08)
					(hide yes)
					(name "GND"
						(effects
							(font
								(size 1.27 1.27)
							)
						)
					)
					(number "C28"
						(effects
							(font
								(size 1.27 1.27)
							)
						)
					)
				)
				(pin passive line
					(at 0 -19.05 0)
					(length 5.08)
					(hide yes)
					(name "GND"
						(effects
							(font
								(size 1.27 1.27)
							)
						)
					)
					(number "C6"
						(effects
							(font
								(size 1.27 1.27)
							)
						)
					)
				)
				(pin passive line
					(at 0 -19.05 0)
					(length 5.08)
					(hide yes)
					(name "GND"
						(effects
							(font
								(size 1.27 1.27)
							)
						)
					)
					(number "C9"
						(effects
							(font
								(size 1.27 1.27)
							)
						)
					)
				)
				(pin passive line
					(at 0 -19.05 0)
					(length 5.08)
					(hide yes)
					(name "GND"
						(effects
							(font
								(size 1.27 1.27)
							)
						)
					)
					(number "D15"
						(effects
							(font
								(size 1.27 1.27)
							)
						)
					)
				)
				(pin passive line
					(at 0 -19.05 0)
					(length 5.08)
					(hide yes)
					(name "GND"
						(effects
							(font
								(size 1.27 1.27)
							)
						)
					)
					(number "D25"
						(effects
							(font
								(size 1.27 1.27)
							)
						)
					)
				)
				(pin passive line
					(at 0 -19.05 0)
					(length 5.08)
					(hide yes)
					(name "GND"
						(effects
							(font
								(size 1.27 1.27)
							)
						)
					)
					(number "D4"
						(effects
							(font
								(size 1.27 1.27)
							)
						)
					)
				)
				(pin passive line
					(at 0 -19.05 0)
					(length 5.08)
					(hide yes)
					(name "GND"
						(effects
							(font
								(size 1.27 1.27)
							)
						)
					)
					(number "D8"
						(effects
							(font
								(size 1.27 1.27)
							)
						)
					)
				)
				(pin passive line
					(at 0 -19.05 0)
					(length 5.08)
					(hide yes)
					(name "GND"
						(effects
							(font
								(size 1.27 1.27)
							)
						)
					)
					(number "D9"
						(effects
							(font
								(size 1.27 1.27)
							)
						)
					)
				)
				(pin passive line
					(at 0 -19.05 0)
					(length 5.08)
					(hide yes)
					(name "GND"
						(effects
							(font
								(size 1.27 1.27)
							)
						)
					)
					(number "E1"
						(effects
							(font
								(size 1.27 1.27)
							)
						)
					)
				)
				(pin passive line
					(at 0 -19.05 0)
					(length 5.08)
					(hide yes)
					(name "GND"
						(effects
							(font
								(size 1.27 1.27)
							)
						)
					)
					(number "E12"
						(effects
							(font
								(size 1.27 1.27)
							)
						)
					)
				)
				(pin passive line
					(at 0 -19.05 0)
					(length 5.08)
					(hide yes)
					(name "GND"
						(effects
							(font
								(size 1.27 1.27)
							)
						)
					)
					(number "E2"
						(effects
							(font
								(size 1.27 1.27)
							)
						)
					)
				)
				(pin passive line
					(at 0 -19.05 0)
					(length 5.08)
					(hide yes)
					(name "GND"
						(effects
							(font
								(size 1.27 1.27)
							)
						)
					)
					(number "E22"
						(effects
							(font
								(size 1.27 1.27)
							)
						)
					)
				)
				(pin passive line
					(at 0 -19.05 0)
					(length 5.08)
					(hide yes)
					(name "GND"
						(effects
							(font
								(size 1.27 1.27)
							)
						)
					)
					(number "E6"
						(effects
							(font
								(size 1.27 1.27)
							)
						)
					)
				)
				(pin passive line
					(at 0 -19.05 0)
					(length 5.08)
					(hide yes)
					(name "GND"
						(effects
							(font
								(size 1.27 1.27)
							)
						)
					)
					(number "E9"
						(effects
							(font
								(size 1.27 1.27)
							)
						)
					)
				)
				(pin passive line
					(at 0 -19.05 0)
					(length 5.08)
					(hide yes)
					(name "GND"
						(effects
							(font
								(size 1.27 1.27)
							)
						)
					)
					(number "F19"
						(effects
							(font
								(size 1.27 1.27)
							)
						)
					)
				)
				(pin passive line
					(at 0 -19.05 0)
					(length 5.08)
					(hide yes)
					(name "GND"
						(effects
							(font
								(size 1.27 1.27)
							)
						)
					)
					(number "F29"
						(effects
							(font
								(size 1.27 1.27)
							)
						)
					)
				)
				(pin passive line
					(at 0 -19.05 0)
					(length 5.08)
					(hide yes)
					(name "GND"
						(effects
							(font
								(size 1.27 1.27)
							)
						)
					)
					(number "F4"
						(effects
							(font
								(size 1.27 1.27)
							)
						)
					)
				)
				(pin passive line
					(at 0 -19.05 0)
					(length 5.08)
					(hide yes)
					(name "GND"
						(effects
							(font
								(size 1.27 1.27)
							)
						)
					)
					(number "F8"
						(effects
							(font
								(size 1.27 1.27)
							)
						)
					)
				)
				(pin passive line
					(at 0 -19.05 0)
					(length 5.08)
					(hide yes)
					(name "GND"
						(effects
							(font
								(size 1.27 1.27)
							)
						)
					)
					(number "F9"
						(effects
							(font
								(size 1.27 1.27)
							)
						)
					)
				)
				(pin passive line
					(at 0 -19.05 0)
					(length 5.08)
					(hide yes)
					(name "GND"
						(effects
							(font
								(size 1.27 1.27)
							)
						)
					)
					(number "G1"
						(effects
							(font
								(size 1.27 1.27)
							)
						)
					)
				)
				(pin passive line
					(at 0 -19.05 0)
					(length 5.08)
					(hide yes)
					(name "GND"
						(effects
							(font
								(size 1.27 1.27)
							)
						)
					)
					(number "G16"
						(effects
							(font
								(size 1.27 1.27)
							)
						)
					)
				)
				(pin passive line
					(at 0 -19.05 0)
					(length 5.08)
					(hide yes)
					(name "GND"
						(effects
							(font
								(size 1.27 1.27)
							)
						)
					)
					(number "G2"
						(effects
							(font
								(size 1.27 1.27)
							)
						)
					)
				)
				(pin passive line
					(at 0 -19.05 0)
					(length 5.08)
					(hide yes)
					(name "GND"
						(effects
							(font
								(size 1.27 1.27)
							)
						)
					)
					(number "G26"
						(effects
							(font
								(size 1.27 1.27)
							)
						)
					)
				)
				(pin passive line
					(at 0 -19.05 0)
					(length 5.08)
					(hide yes)
					(name "GND"
						(effects
							(font
								(size 1.27 1.27)
							)
						)
					)
					(number "G6"
						(effects
							(font
								(size 1.27 1.27)
							)
						)
					)
				)
				(pin passive line
					(at 0 -19.05 0)
					(length 5.08)
					(hide yes)
					(name "GND"
						(effects
							(font
								(size 1.27 1.27)
							)
						)
					)
					(number "G9"
						(effects
							(font
								(size 1.27 1.27)
							)
						)
					)
				)
				(pin passive line
					(at 0 -19.05 0)
					(length 5.08)
					(hide yes)
					(name "GND"
						(effects
							(font
								(size 1.27 1.27)
							)
						)
					)
					(number "H13"
						(effects
							(font
								(size 1.27 1.27)
							)
						)
					)
				)
				(pin passive line
					(at 0 -19.05 0)
					(length 5.08)
					(hide yes)
					(name "GND"
						(effects
							(font
								(size 1.27 1.27)
							)
						)
					)
					(number "H23"
						(effects
							(font
								(size 1.27 1.27)
							)
						)
					)
				)
				(pin passive line
					(at 0 -19.05 0)
					(length 5.08)
					(hide yes)
					(name "GND"
						(effects
							(font
								(size 1.27 1.27)
							)
						)
					)
					(number "H4"
						(effects
							(font
								(size 1.27 1.27)
							)
						)
					)
				)
				(pin passive line
					(at 0 -19.05 0)
					(length 5.08)
					(hide yes)
					(name "GND"
						(effects
							(font
								(size 1.27 1.27)
							)
						)
					)
					(number "H8"
						(effects
							(font
								(size 1.27 1.27)
							)
						)
					)
				)
				(pin passive line
					(at 0 -19.05 0)
					(length 5.08)
					(hide yes)
					(name "GND"
						(effects
							(font
								(size 1.27 1.27)
							)
						)
					)
					(number "H9"
						(effects
							(font
								(size 1.27 1.27)
							)
						)
					)
				)
				(pin passive line
					(at 0 -19.05 0)
					(length 5.08)
					(hide yes)
					(name "GND"
						(effects
							(font
								(size 1.27 1.27)
							)
						)
					)
					(number "J1"
						(effects
							(font
								(size 1.27 1.27)
							)
						)
					)
				)
				(pin passive line
					(at 0 -19.05 0)
					(length 5.08)
					(hide yes)
					(name "GND"
						(effects
							(font
								(size 1.27 1.27)
							)
						)
					)
					(number "J10"
						(effects
							(font
								(size 1.27 1.27)
							)
						)
					)
				)
				(pin passive line
					(at 0 -19.05 0)
					(length 5.08)
					(hide yes)
					(name "GND"
						(effects
							(font
								(size 1.27 1.27)
							)
						)
					)
					(number "J2"
						(effects
							(font
								(size 1.27 1.27)
							)
						)
					)
				)
				(pin passive line
					(at 0 -19.05 0)
					(length 5.08)
					(hide yes)
					(name "GND"
						(effects
							(font
								(size 1.27 1.27)
							)
						)
					)
					(number "J20"
						(effects
							(font
								(size 1.27 1.27)
							)
						)
					)
				)
				(pin passive line
					(at 0 -19.05 0)
					(length 5.08)
					(hide yes)
					(name "GND"
						(effects
							(font
								(size 1.27 1.27)
							)
						)
					)
					(number "J30"
						(effects
							(font
								(size 1.27 1.27)
							)
						)
					)
				)
				(pin passive line
					(at 0 -19.05 0)
					(length 5.08)
					(hide yes)
					(name "GND"
						(effects
							(font
								(size 1.27 1.27)
							)
						)
					)
					(number "J6"
						(effects
							(font
								(size 1.27 1.27)
							)
						)
					)
				)
				(pin passive line
					(at 0 -19.05 0)
					(length 5.08)
					(hide yes)
					(name "GND"
						(effects
							(font
								(size 1.27 1.27)
							)
						)
					)
					(number "J9"
						(effects
							(font
								(size 1.27 1.27)
							)
						)
					)
				)
				(pin passive line
					(at 0 -19.05 0)
					(length 5.08)
					(hide yes)
					(name "GND"
						(effects
							(font
								(size 1.27 1.27)
							)
						)
					)
					(number "K17"
						(effects
							(font
								(size 1.27 1.27)
							)
						)
					)
				)
				(pin passive line
					(at 0 -19.05 0)
					(length 5.08)
					(hide yes)
					(name "GND"
						(effects
							(font
								(size 1.27 1.27)
							)
						)
					)
					(number "K27"
						(effects
							(font
								(size 1.27 1.27)
							)
						)
					)
				)
				(pin passive line
					(at 0 -19.05 0)
					(length 5.08)
					(hide yes)
					(name "GND"
						(effects
							(font
								(size 1.27 1.27)
							)
						)
					)
					(number "K4"
						(effects
							(font
								(size 1.27 1.27)
							)
						)
					)
				)
				(pin passive line
					(at 0 -19.05 0)
					(length 5.08)
					(hide yes)
					(name "GND"
						(effects
							(font
								(size 1.27 1.27)
							)
						)
					)
					(number "K8"
						(effects
							(font
								(size 1.27 1.27)
							)
						)
					)
				)
				(pin passive line
					(at 0 -19.05 0)
					(length 5.08)
					(hide yes)
					(name "GND"
						(effects
							(font
								(size 1.27 1.27)
							)
						)
					)
					(number "K9"
						(effects
							(font
								(size 1.27 1.27)
							)
						)
					)
				)
				(pin passive line
					(at 0 -19.05 0)
					(length 5.08)
					(hide yes)
					(name "GND"
						(effects
							(font
								(size 1.27 1.27)
							)
						)
					)
					(number "L1"
						(effects
							(font
								(size 1.27 1.27)
							)
						)
					)
				)
				(pin passive line
					(at 0 -19.05 0)
					(length 5.08)
					(hide yes)
					(name "GND"
						(effects
							(font
								(size 1.27 1.27)
							)
						)
					)
					(number "L14"
						(effects
							(font
								(size 1.27 1.27)
							)
						)
					)
				)
				(pin passive line
					(at 0 -19.05 0)
					(length 5.08)
					(hide yes)
					(name "GND"
						(effects
							(font
								(size 1.27 1.27)
							)
						)
					)
					(number "L2"
						(effects
							(font
								(size 1.27 1.27)
							)
						)
					)
				)
				(pin passive line
					(at 0 -19.05 0)
					(length 5.08)
					(hide yes)
					(name "GND"
						(effects
							(font
								(size 1.27 1.27)
							)
						)
					)
					(number "L24"
						(effects
							(font
								(size 1.27 1.27)
							)
						)
					)
				)
				(pin passive line
					(at 0 -19.05 0)
					(length 5.08)
					(hide yes)
					(name "GND"
						(effects
							(font
								(size 1.27 1.27)
							)
						)
					)
					(number "L6"
						(effects
							(font
								(size 1.27 1.27)
							)
						)
					)
				)
				(pin passive line
					(at 0 -19.05 0)
					(length 5.08)
					(hide yes)
					(name "GND"
						(effects
							(font
								(size 1.27 1.27)
							)
						)
					)
					(number "L9"
						(effects
							(font
								(size 1.27 1.27)
							)
						)
					)
				)
				(pin passive line
					(at 0 -19.05 0)
					(length 5.08)
					(hide yes)
					(name "GND"
						(effects
							(font
								(size 1.27 1.27)
							)
						)
					)
					(number "M12"
						(effects
							(font
								(size 1.27 1.27)
							)
						)
					)
				)
				(pin passive line
					(at 0 -19.05 0)
					(length 5.08)
					(hide yes)
					(name "GND"
						(effects
							(font
								(size 1.27 1.27)
							)
						)
					)
					(number "M14"
						(effects
							(font
								(size 1.27 1.27)
							)
						)
					)
				)
				(pin passive line
					(at 0 -19.05 0)
					(length 5.08)
					(hide yes)
					(name "GND"
						(effects
							(font
								(size 1.27 1.27)
							)
						)
					)
					(number "M16"
						(effects
							(font
								(size 1.27 1.27)
							)
						)
					)
				)
				(pin passive line
					(at 0 -19.05 0)
					(length 5.08)
					(hide yes)
					(name "GND"
						(effects
							(font
								(size 1.27 1.27)
							)
						)
					)
					(number "M18"
						(effects
							(font
								(size 1.27 1.27)
							)
						)
					)
				)
				(pin passive line
					(at 0 -19.05 0)
					(length 5.08)
					(hide yes)
					(name "GND"
						(effects
							(font
								(size 1.27 1.27)
							)
						)
					)
					(number "M21"
						(effects
							(font
								(size 1.27 1.27)
							)
						)
					)
				)
				(pin passive line
					(at 0 -19.05 0)
					(length 5.08)
					(hide yes)
					(name "GND"
						(effects
							(font
								(size 1.27 1.27)
							)
						)
					)
					(number "M4"
						(effects
							(font
								(size 1.27 1.27)
							)
						)
					)
				)
				(pin passive line
					(at 0 -19.05 0)
					(length 5.08)
					(hide yes)
					(name "GND"
						(effects
							(font
								(size 1.27 1.27)
							)
						)
					)
					(number "M8"
						(effects
							(font
								(size 1.27 1.27)
							)
						)
					)
				)
				(pin passive line
					(at 0 -19.05 0)
					(length 5.08)
					(hide yes)
					(name "GND"
						(effects
							(font
								(size 1.27 1.27)
							)
						)
					)
					(number "M9"
						(effects
							(font
								(size 1.27 1.27)
							)
						)
					)
				)
				(pin passive line
					(at 0 -19.05 0)
					(length 5.08)
					(hide yes)
					(name "GND"
						(effects
							(font
								(size 1.27 1.27)
							)
						)
					)
					(number "N1"
						(effects
							(font
								(size 1.27 1.27)
							)
						)
					)
				)
				(pin passive line
					(at 0 -19.05 0)
					(length 5.08)
					(hide yes)
					(name "GND"
						(effects
							(font
								(size 1.27 1.27)
							)
						)
					)
					(number "N11"
						(effects
							(font
								(size 1.27 1.27)
							)
						)
					)
				)
				(pin passive line
					(at 0 -19.05 0)
					(length 5.08)
					(hide yes)
					(name "GND"
						(effects
							(font
								(size 1.27 1.27)
							)
						)
					)
					(number "N13"
						(effects
							(font
								(size 1.27 1.27)
							)
						)
					)
				)
				(pin passive line
					(at 0 -19.05 0)
					(length 5.08)
					(hide yes)
					(name "GND"
						(effects
							(font
								(size 1.27 1.27)
							)
						)
					)
					(number "N15"
						(effects
							(font
								(size 1.27 1.27)
							)
						)
					)
				)
				(pin passive line
					(at 0 -19.05 0)
					(length 5.08)
					(hide yes)
					(name "GND"
						(effects
							(font
								(size 1.27 1.27)
							)
						)
					)
					(number "N17"
						(effects
							(font
								(size 1.27 1.27)
							)
						)
					)
				)
				(pin passive line
					(at 0 -19.05 0)
					(length 5.08)
					(hide yes)
					(name "GND"
						(effects
							(font
								(size 1.27 1.27)
							)
						)
					)
					(number "N2"
						(effects
							(font
								(size 1.27 1.27)
							)
						)
					)
				)
				(pin passive line
					(at 0 -19.05 0)
					(length 5.08)
					(hide yes)
					(name "GND"
						(effects
							(font
								(size 1.27 1.27)
							)
						)
					)
					(number "N28"
						(effects
							(font
								(size 1.27 1.27)
							)
						)
					)
				)
				(pin passive line
					(at 0 -19.05 0)
					(length 5.08)
					(hide yes)
					(name "GND"
						(effects
							(font
								(size 1.27 1.27)
							)
						)
					)
					(number "N6"
						(effects
							(font
								(size 1.27 1.27)
							)
						)
					)
				)
				(pin passive line
					(at 0 -19.05 0)
					(length 5.08)
					(hide yes)
					(name "GND"
						(effects
							(font
								(size 1.27 1.27)
							)
						)
					)
					(number "N9"
						(effects
							(font
								(size 1.27 1.27)
							)
						)
					)
				)
				(pin passive line
					(at 0 -19.05 0)
					(length 5.08)
					(hide yes)
					(name "GND"
						(effects
							(font
								(size 1.27 1.27)
							)
						)
					)
					(number "P10"
						(effects
							(font
								(size 1.27 1.27)
							)
						)
					)
				)
				(pin passive line
					(at 0 -19.05 0)
					(length 5.08)
					(hide yes)
					(name "GND"
						(effects
							(font
								(size 1.27 1.27)
							)
						)
					)
					(number "P12"
						(effects
							(font
								(size 1.27 1.27)
							)
						)
					)
				)
				(pin passive line
					(at 0 -19.05 0)
					(length 5.08)
					(hide yes)
					(name "GND"
						(effects
							(font
								(size 1.27 1.27)
							)
						)
					)
					(number "P16"
						(effects
							(font
								(size 1.27 1.27)
							)
						)
					)
				)
				(pin passive line
					(at 0 -19.05 0)
					(length 5.08)
					(hide yes)
					(name "GND"
						(effects
							(font
								(size 1.27 1.27)
							)
						)
					)
					(number "P18"
						(effects
							(font
								(size 1.27 1.27)
							)
						)
					)
				)
				(pin passive line
					(at 0 -19.05 0)
					(length 5.08)
					(hide yes)
					(name "GND"
						(effects
							(font
								(size 1.27 1.27)
							)
						)
					)
					(number "P25"
						(effects
							(font
								(size 1.27 1.27)
							)
						)
					)
				)
				(pin passive line
					(at 0 -19.05 0)
					(length 5.08)
					(hide yes)
					(name "GND"
						(effects
							(font
								(size 1.27 1.27)
							)
						)
					)
					(number "P4"
						(effects
							(font
								(size 1.27 1.27)
							)
						)
					)
				)
				(pin passive line
					(at 0 -19.05 0)
					(length 5.08)
					(hide yes)
					(name "GND"
						(effects
							(font
								(size 1.27 1.27)
							)
						)
					)
					(number "P8"
						(effects
							(font
								(size 1.27 1.27)
							)
						)
					)
				)
				(pin passive line
					(at 0 -19.05 0)
					(length 5.08)
					(hide yes)
					(name "GND"
						(effects
							(font
								(size 1.27 1.27)
							)
						)
					)
					(number "P9"
						(effects
							(font
								(size 1.27 1.27)
							)
						)
					)
				)
				(pin passive line
					(at 0 -19.05 0)
					(length 5.08)
					(hide yes)
					(name "GND"
						(effects
							(font
								(size 1.27 1.27)
							)
						)
					)
					(number "R1"
						(effects
							(font
								(size 1.27 1.27)
							)
						)
					)
				)
				(pin passive line
					(at 0 -19.05 0)
					(length 5.08)
					(hide yes)
					(name "GND"
						(effects
							(font
								(size 1.27 1.27)
							)
						)
					)
					(number "R11"
						(effects
							(font
								(size 1.27 1.27)
							)
						)
					)
				)
				(pin passive line
					(at 0 -19.05 0)
					(length 5.08)
					(hide yes)
					(name "GND"
						(effects
							(font
								(size 1.27 1.27)
							)
						)
					)
					(number "R13"
						(effects
							(font
								(size 1.27 1.27)
							)
						)
					)
				)
				(pin passive line
					(at 0 -19.05 0)
					(length 5.08)
					(hide yes)
					(name "GND"
						(effects
							(font
								(size 1.27 1.27)
							)
						)
					)
					(number "R17"
						(effects
							(font
								(size 1.27 1.27)
							)
						)
					)
				)
				(pin passive line
					(at 0 -19.05 0)
					(length 5.08)
					(hide yes)
					(name "GND"
						(effects
							(font
								(size 1.27 1.27)
							)
						)
					)
					(number "R2"
						(effects
							(font
								(size 1.27 1.27)
							)
						)
					)
				)
				(pin passive line
					(at 0 -19.05 0)
					(length 5.08)
					(hide yes)
					(name "GND"
						(effects
							(font
								(size 1.27 1.27)
							)
						)
					)
					(number "R22"
						(effects
							(font
								(size 1.27 1.27)
							)
						)
					)
				)
				(pin passive line
					(at 0 -19.05 0)
					(length 5.08)
					(hide yes)
					(name "GND"
						(effects
							(font
								(size 1.27 1.27)
							)
						)
					)
					(number "R6"
						(effects
							(font
								(size 1.27 1.27)
							)
						)
					)
				)
				(pin passive line
					(at 0 -19.05 0)
					(length 5.08)
					(hide yes)
					(name "GND"
						(effects
							(font
								(size 1.27 1.27)
							)
						)
					)
					(number "R9"
						(effects
							(font
								(size 1.27 1.27)
							)
						)
					)
				)
				(pin passive line
					(at 0 -19.05 0)
					(length 5.08)
					(hide yes)
					(name "GND"
						(effects
							(font
								(size 1.27 1.27)
							)
						)
					)
					(number "T10"
						(effects
							(font
								(size 1.27 1.27)
							)
						)
					)
				)
				(pin passive line
					(at 0 -19.05 0)
					(length 5.08)
					(hide yes)
					(name "GND"
						(effects
							(font
								(size 1.27 1.27)
							)
						)
					)
					(number "T12"
						(effects
							(font
								(size 1.27 1.27)
							)
						)
					)
				)
				(pin passive line
					(at 0 -19.05 0)
					(length 5.08)
					(hide yes)
					(name "GND"
						(effects
							(font
								(size 1.27 1.27)
							)
						)
					)
					(number "T16"
						(effects
							(font
								(size 1.27 1.27)
							)
						)
					)
				)
				(pin passive line
					(at 0 -19.05 0)
					(length 5.08)
					(hide yes)
					(name "GND"
						(effects
							(font
								(size 1.27 1.27)
							)
						)
					)
					(number "T18"
						(effects
							(font
								(size 1.27 1.27)
							)
						)
					)
				)
				(pin passive line
					(at 0 -19.05 0)
					(length 5.08)
					(hide yes)
					(name "GND"
						(effects
							(font
								(size 1.27 1.27)
							)
						)
					)
					(number "T19"
						(effects
							(font
								(size 1.27 1.27)
							)
						)
					)
				)
				(pin passive line
					(at 0 -19.05 0)
					(length 5.08)
					(hide yes)
					(name "GND"
						(effects
							(font
								(size 1.27 1.27)
							)
						)
					)
					(number "T29"
						(effects
							(font
								(size 1.27 1.27)
							)
						)
					)
				)
				(pin passive line
					(at 0 -19.05 0)
					(length 5.08)
					(hide yes)
					(name "GND"
						(effects
							(font
								(size 1.27 1.27)
							)
						)
					)
					(number "T4"
						(effects
							(font
								(size 1.27 1.27)
							)
						)
					)
				)
				(pin passive line
					(at 0 -19.05 0)
					(length 5.08)
					(hide yes)
					(name "GND"
						(effects
							(font
								(size 1.27 1.27)
							)
						)
					)
					(number "T8"
						(effects
							(font
								(size 1.27 1.27)
							)
						)
					)
				)
				(pin passive line
					(at 0 -19.05 0)
					(length 5.08)
					(hide yes)
					(name "GND"
						(effects
							(font
								(size 1.27 1.27)
							)
						)
					)
					(number "U1"
						(effects
							(font
								(size 1.27 1.27)
							)
						)
					)
				)
				(pin passive line
					(at 0 -19.05 0)
					(length 5.08)
					(hide yes)
					(name "GND"
						(effects
							(font
								(size 1.27 1.27)
							)
						)
					)
					(number "U11"
						(effects
							(font
								(size 1.27 1.27)
							)
						)
					)
				)
				(pin passive line
					(at 0 -19.05 0)
					(length 5.08)
					(hide yes)
					(name "GND"
						(effects
							(font
								(size 1.27 1.27)
							)
						)
					)
					(number "U13"
						(effects
							(font
								(size 1.27 1.27)
							)
						)
					)
				)
				(pin passive line
					(at 0 -19.05 0)
					(length 5.08)
					(hide yes)
					(name "GND"
						(effects
							(font
								(size 1.27 1.27)
							)
						)
					)
					(number "U17"
						(effects
							(font
								(size 1.27 1.27)
							)
						)
					)
				)
				(pin passive line
					(at 0 -19.05 0)
					(length 5.08)
					(hide yes)
					(name "GND"
						(effects
							(font
								(size 1.27 1.27)
							)
						)
					)
					(number "U2"
						(effects
							(font
								(size 1.27 1.27)
							)
						)
					)
				)
				(pin passive line
					(at 0 -19.05 0)
					(length 5.08)
					(hide yes)
					(name "GND"
						(effects
							(font
								(size 1.27 1.27)
							)
						)
					)
					(number "U26"
						(effects
							(font
								(size 1.27 1.27)
							)
						)
					)
				)
				(pin passive line
					(at 0 -19.05 0)
					(length 5.08)
					(hide yes)
					(name "GND"
						(effects
							(font
								(size 1.27 1.27)
							)
						)
					)
					(number "U6"
						(effects
							(font
								(size 1.27 1.27)
							)
						)
					)
				)
				(pin passive line
					(at 0 -19.05 0)
					(length 5.08)
					(hide yes)
					(name "GND"
						(effects
							(font
								(size 1.27 1.27)
							)
						)
					)
					(number "U9"
						(effects
							(font
								(size 1.27 1.27)
							)
						)
					)
				)
				(pin passive line
					(at 0 -19.05 0)
					(length 5.08)
					(hide yes)
					(name "GND"
						(effects
							(font
								(size 1.27 1.27)
							)
						)
					)
					(number "V10"
						(effects
							(font
								(size 1.27 1.27)
							)
						)
					)
				)
				(pin passive line
					(at 0 -19.05 0)
					(length 5.08)
					(hide yes)
					(name "GND"
						(effects
							(font
								(size 1.27 1.27)
							)
						)
					)
					(number "V12"
						(effects
							(font
								(size 1.27 1.27)
							)
						)
					)
				)
				(pin passive line
					(at 0 -19.05 0)
					(length 5.08)
					(hide yes)
					(name "GND"
						(effects
							(font
								(size 1.27 1.27)
							)
						)
					)
					(number "V14"
						(effects
							(font
								(size 1.27 1.27)
							)
						)
					)
				)
				(pin passive line
					(at 0 -19.05 0)
					(length 5.08)
					(hide yes)
					(name "GND"
						(effects
							(font
								(size 1.27 1.27)
							)
						)
					)
					(number "V16"
						(effects
							(font
								(size 1.27 1.27)
							)
						)
					)
				)
				(pin passive line
					(at 0 -19.05 0)
					(length 5.08)
					(hide yes)
					(name "GND"
						(effects
							(font
								(size 1.27 1.27)
							)
						)
					)
					(number "V18"
						(effects
							(font
								(size 1.27 1.27)
							)
						)
					)
				)
				(pin passive line
					(at 0 -19.05 0)
					(length 5.08)
					(hide yes)
					(name "GND"
						(effects
							(font
								(size 1.27 1.27)
							)
						)
					)
					(number "V23"
						(effects
							(font
								(size 1.27 1.27)
							)
						)
					)
				)
				(pin passive line
					(at 0 -19.05 0)
					(length 5.08)
					(hide yes)
					(name "GND"
						(effects
							(font
								(size 1.27 1.27)
							)
						)
					)
					(number "V4"
						(effects
							(font
								(size 1.27 1.27)
							)
						)
					)
				)
				(pin passive line
					(at 0 -19.05 0)
					(length 5.08)
					(hide yes)
					(name "GND"
						(effects
							(font
								(size 1.27 1.27)
							)
						)
					)
					(number "V8"
						(effects
							(font
								(size 1.27 1.27)
							)
						)
					)
				)
				(pin passive line
					(at 0 -19.05 0)
					(length 5.08)
					(hide yes)
					(name "GND"
						(effects
							(font
								(size 1.27 1.27)
							)
						)
					)
					(number "V9"
						(effects
							(font
								(size 1.27 1.27)
							)
						)
					)
				)
				(pin passive line
					(at 0 -19.05 0)
					(length 5.08)
					(hide yes)
					(name "GND"
						(effects
							(font
								(size 1.27 1.27)
							)
						)
					)
					(number "W1"
						(effects
							(font
								(size 1.27 1.27)
							)
						)
					)
				)
				(pin passive line
					(at 0 -19.05 0)
					(length 5.08)
					(hide yes)
					(name "GND"
						(effects
							(font
								(size 1.27 1.27)
							)
						)
					)
					(number "W11"
						(effects
							(font
								(size 1.27 1.27)
							)
						)
					)
				)
				(pin passive line
					(at 0 -19.05 0)
					(length 5.08)
					(hide yes)
					(name "GND"
						(effects
							(font
								(size 1.27 1.27)
							)
						)
					)
					(number "W13"
						(effects
							(font
								(size 1.27 1.27)
							)
						)
					)
				)
				(pin passive line
					(at 0 -19.05 0)
					(length 5.08)
					(hide yes)
					(name "GND"
						(effects
							(font
								(size 1.27 1.27)
							)
						)
					)
					(number "W15"
						(effects
							(font
								(size 1.27 1.27)
							)
						)
					)
				)
				(pin passive line
					(at 0 -19.05 0)
					(length 5.08)
					(hide yes)
					(name "GND"
						(effects
							(font
								(size 1.27 1.27)
							)
						)
					)
					(number "W17"
						(effects
							(font
								(size 1.27 1.27)
							)
						)
					)
				)
				(pin passive line
					(at 0 -19.05 0)
					(length 5.08)
					(hide yes)
					(name "GND"
						(effects
							(font
								(size 1.27 1.27)
							)
						)
					)
					(number "W2"
						(effects
							(font
								(size 1.27 1.27)
							)
						)
					)
				)
				(pin passive line
					(at 0 -19.05 0)
					(length 5.08)
					(hide yes)
					(name "GND"
						(effects
							(font
								(size 1.27 1.27)
							)
						)
					)
					(number "W20"
						(effects
							(font
								(size 1.27 1.27)
							)
						)
					)
				)
				(pin passive line
					(at 0 -19.05 0)
					(length 5.08)
					(hide yes)
					(name "GND"
						(effects
							(font
								(size 1.27 1.27)
							)
						)
					)
					(number "W30"
						(effects
							(font
								(size 1.27 1.27)
							)
						)
					)
				)
				(pin passive line
					(at 0 -19.05 0)
					(length 5.08)
					(hide yes)
					(name "GND"
						(effects
							(font
								(size 1.27 1.27)
							)
						)
					)
					(number "W6"
						(effects
							(font
								(size 1.27 1.27)
							)
						)
					)
				)
				(pin passive line
					(at 0 -19.05 0)
					(length 5.08)
					(hide yes)
					(name "GND"
						(effects
							(font
								(size 1.27 1.27)
							)
						)
					)
					(number "W9"
						(effects
							(font
								(size 1.27 1.27)
							)
						)
					)
				)
				(pin passive line
					(at 0 -19.05 0)
					(length 5.08)
					(hide yes)
					(name "GND"
						(effects
							(font
								(size 1.27 1.27)
							)
						)
					)
					(number "Y17"
						(effects
							(font
								(size 1.27 1.27)
							)
						)
					)
				)
				(pin passive line
					(at 0 -19.05 0)
					(length 5.08)
					(hide yes)
					(name "GND"
						(effects
							(font
								(size 1.27 1.27)
							)
						)
					)
					(number "Y27"
						(effects
							(font
								(size 1.27 1.27)
							)
						)
					)
				)
				(pin passive line
					(at 0 -19.05 0)
					(length 5.08)
					(hide yes)
					(name "GND"
						(effects
							(font
								(size 1.27 1.27)
							)
						)
					)
					(number "Y3"
						(effects
							(font
								(size 1.27 1.27)
							)
						)
					)
				)
				(pin passive line
					(at 0 -19.05 0)
					(length 5.08)
					(hide yes)
					(name "GND"
						(effects
							(font
								(size 1.27 1.27)
							)
						)
					)
					(number "Y4"
						(effects
							(font
								(size 1.27 1.27)
							)
						)
					)
				)
				(pin passive line
					(at 0 -19.05 0)
					(length 5.08)
					(hide yes)
					(name "GND"
						(effects
							(font
								(size 1.27 1.27)
							)
						)
					)
					(number "Y7"
						(effects
							(font
								(size 1.27 1.27)
							)
						)
					)
				)
				(pin passive line
					(at 0 -19.05 0)
					(length 5.08)
					(hide yes)
					(name "GND"
						(effects
							(font
								(size 1.27 1.27)
							)
						)
					)
					(number "Y8"
						(effects
							(font
								(size 1.27 1.27)
							)
						)
					)
				)
				(pin passive line
					(at 0 -19.05 0)
					(length 5.08)
					(hide yes)
					(name "GND"
						(effects
							(font
								(size 1.27 1.27)
							)
						)
					)
					(number "Y9"
						(effects
							(font
								(size 1.27 1.27)
							)
						)
					)
				)
			)
		)
	(symbol "antmicroB2BConnectors:ASP-184329-01_CUSTOM_mounting_holes"
			(exclude_from_sim no)
			(in_bom yes)
			(on_board yes)
			(property "Reference" "J"
				(at 45.72 -6.35 0)
				(effects
					(font
						(size 1.27 1.27)
						(thickness 0.15)
					)
					(justify left bottom)
				)
			)
			(property "Value" "ASP-184329-01_CUSTOM_mounting_holes"
				(at 45.72 -8.89 0)
				(effects
					(font
						(size 1.27 1.27)
						(thickness 0.15)
					)
					(justify left bottom)
					(hide yes)
				)
			)
			(property "Footprint" "antmicro-footprints:ASP-184329-01_mounting_holes"
				(at 45.72 -11.43 0)
				(effects
					(font
						(size 1.27 1.27)
						(thickness 0.15)
					)
					(justify left bottom)
					(hide yes)
				)
			)
			(property "Datasheet" "https://www.mouser.com/datasheet/2/527/asp_184329_01_mkt-2854128.pdf"
				(at 45.72 -13.97 0)
				(effects
					(font
						(size 1.27 1.27)
						(thickness 0.15)
					)
					(justify left bottom)
					(hide yes)
				)
			)
			(property "Description" "Mezzanine Connector, Array, Female, 1.27 mm, 14 Rows, 560 Contacts, Surface Mount"
				(at 0 0 0)
				(effects
					(font
						(size 1.27 1.27)
					)
					(hide yes)
				)
			)
			(property "Manufacturer" "Samtec"
				(at 45.72 -16.51 0)
				(effects
					(font
						(size 1.27 1.27)
						(thickness 0.15)
					)
					(justify left bottom)
					(hide yes)
				)
			)
			(property "MPN" "ASP-184329-01"
				(at 45.72 -19.05 0)
				(effects
					(font
						(size 1.27 1.27)
						(thickness 0.15)
					)
					(justify left bottom)
				)
			)
			(property "Author" "Antmicro"
				(at 45.72 -21.59 0)
				(effects
					(font
						(size 1.27 1.27)
						(thickness 0.15)
					)
					(justify left bottom)
					(hide yes)
				)
			)
			(property "License" "Apache-2.0"
				(at 45.72 -24.13 0)
				(effects
					(font
						(size 1.27 1.27)
						(thickness 0.15)
					)
					(justify left bottom)
					(hide yes)
				)
			)
			(property "ki_locked" ""
				(at 0 0 0)
				(effects
					(font
						(size 1.27 1.27)
					)
				)
			)
			(property "ki_keywords" "CONNECTOR"
				(at 0 0 0)
				(effects
					(font
						(size 1.27 1.27)
					)
					(hide yes)
				)
			)
			(symbol "ASP-184329-01_CUSTOM_mounting_holes_1_0"
				(text "POWER"
					(at 15.24 3.81 0)
					(effects
						(font
							(size 1.27 1.27)
						)
					)
				)
			)
			(symbol "ASP-184329-01_CUSTOM_mounting_holes_1_1"
				(rectangle
					(start 3.81 6.35)
					(end 26.67 -17.78)
					(stroke
						(width 0.254)
						(type default)
					)
					(fill
						(type background)
					)
				)
				(pin passive line
					(at 0 0 0)
					(length 3.81)
					(hide yes)
					(name "12P0V"
						(effects
							(font
								(size 1.27 1.27)
							)
						)
					)
					(number "C35"
						(effects
							(font
								(size 1.27 1.27)
							)
						)
					)
				)
				(pin passive line
					(at 0 0 0)
					(length 3.81)
					(hide yes)
					(name "12P0V"
						(effects
							(font
								(size 1.27 1.27)
							)
						)
					)
					(number "C37"
						(effects
							(font
								(size 1.27 1.27)
							)
						)
					)
				)
				(pin passive line
					(at 0 0 0)
					(length 3.81)
					(name "12P0V"
						(effects
							(font
								(size 1.27 1.27)
							)
						)
					)
					(number "L36"
						(effects
							(font
								(size 1.27 1.27)
							)
						)
					)
				)
				(pin passive line
					(at 0 0 0)
					(length 3.81)
					(hide yes)
					(name "12P0V"
						(effects
							(font
								(size 1.27 1.27)
							)
						)
					)
					(number "L37"
						(effects
							(font
								(size 1.27 1.27)
							)
						)
					)
				)
				(pin passive line
					(at 0 0 0)
					(length 3.81)
					(hide yes)
					(name "12P0V"
						(effects
							(font
								(size 1.27 1.27)
							)
						)
					)
					(number "L40"
						(effects
							(font
								(size 1.27 1.27)
							)
						)
					)
				)
				(pin passive line
					(at 0 -2.54 0)
					(length 3.81)
					(name "3P3V"
						(effects
							(font
								(size 1.27 1.27)
							)
						)
					)
					(number "C39"
						(effects
							(font
								(size 1.27 1.27)
							)
						)
					)
				)
				(pin passive line
					(at 0 -2.54 0)
					(length 3.81)
					(hide yes)
					(name "3P3V"
						(effects
							(font
								(size 1.27 1.27)
							)
						)
					)
					(number "D36"
						(effects
							(font
								(size 1.27 1.27)
							)
						)
					)
				)
				(pin passive line
					(at 0 -2.54 0)
					(length 3.81)
					(hide yes)
					(name "3P3V"
						(effects
							(font
								(size 1.27 1.27)
							)
						)
					)
					(number "D38"
						(effects
							(font
								(size 1.27 1.27)
							)
						)
					)
				)
				(pin passive line
					(at 0 -2.54 0)
					(length 3.81)
					(hide yes)
					(name "3P3V"
						(effects
							(font
								(size 1.27 1.27)
							)
						)
					)
					(number "D40"
						(effects
							(font
								(size 1.27 1.27)
							)
						)
					)
				)
				(pin passive line
					(at 0 -2.54 0)
					(length 3.81)
					(hide yes)
					(name "3P3V"
						(effects
							(font
								(size 1.27 1.27)
							)
						)
					)
					(number "Z40"
						(effects
							(font
								(size 1.27 1.27)
							)
						)
					)
				)
				(pin passive line
					(at 0 -5.08 0)
					(length 3.81)
					(hide yes)
					(name "VADJ"
						(effects
							(font
								(size 1.27 1.27)
							)
						)
					)
					(number "E39"
						(effects
							(font
								(size 1.27 1.27)
							)
						)
					)
				)
				(pin passive line
					(at 0 -5.08 0)
					(length 3.81)
					(hide yes)
					(name "VADJ"
						(effects
							(font
								(size 1.27 1.27)
							)
						)
					)
					(number "F40"
						(effects
							(font
								(size 1.27 1.27)
							)
						)
					)
				)
				(pin passive line
					(at 0 -5.08 0)
					(length 3.81)
					(name "VADJ"
						(effects
							(font
								(size 1.27 1.27)
							)
						)
					)
					(number "G39"
						(effects
							(font
								(size 1.27 1.27)
							)
						)
					)
				)
				(pin passive line
					(at 0 -5.08 0)
					(length 3.81)
					(hide yes)
					(name "VADJ"
						(effects
							(font
								(size 1.27 1.27)
							)
						)
					)
					(number "H40"
						(effects
							(font
								(size 1.27 1.27)
							)
						)
					)
				)
				(pin passive line
					(at 0 -15.24 0)
					(length 3.81)
					(hide yes)
					(name "GND"
						(effects
							(font
								(size 1.27 1.27)
							)
						)
					)
					(number "A01"
						(effects
							(font
								(size 1.27 1.27)
							)
						)
					)
				)
				(pin passive line
					(at 0 -15.24 0)
					(length 3.81)
					(hide yes)
					(name "GND"
						(effects
							(font
								(size 1.27 1.27)
							)
						)
					)
					(number "A04"
						(effects
							(font
								(size 1.27 1.27)
							)
						)
					)
				)
				(pin passive line
					(at 0 -15.24 0)
					(length 3.81)
					(hide yes)
					(name "GND"
						(effects
							(font
								(size 1.27 1.27)
							)
						)
					)
					(number "A05"
						(effects
							(font
								(size 1.27 1.27)
							)
						)
					)
				)
				(pin passive line
					(at 0 -15.24 0)
					(length 3.81)
					(hide yes)
					(name "GND"
						(effects
							(font
								(size 1.27 1.27)
							)
						)
					)
					(number "A08"
						(effects
							(font
								(size 1.27 1.27)
							)
						)
					)
				)
				(pin passive line
					(at 0 -15.24 0)
					(length 3.81)
					(hide yes)
					(name "GND"
						(effects
							(font
								(size 1.27 1.27)
							)
						)
					)
					(number "A09"
						(effects
							(font
								(size 1.27 1.27)
							)
						)
					)
				)
				(pin passive line
					(at 0 -15.24 0)
					(length 3.81)
					(hide yes)
					(name "GND"
						(effects
							(font
								(size 1.27 1.27)
							)
						)
					)
					(number "A12"
						(effects
							(font
								(size 1.27 1.27)
							)
						)
					)
				)
				(pin passive line
					(at 0 -15.24 0)
					(length 3.81)
					(hide yes)
					(name "GND"
						(effects
							(font
								(size 1.27 1.27)
							)
						)
					)
					(number "A13"
						(effects
							(font
								(size 1.27 1.27)
							)
						)
					)
				)
				(pin passive line
					(at 0 -15.24 0)
					(length 3.81)
					(hide yes)
					(name "GND"
						(effects
							(font
								(size 1.27 1.27)
							)
						)
					)
					(number "A16"
						(effects
							(font
								(size 1.27 1.27)
							)
						)
					)
				)
				(pin passive line
					(at 0 -15.24 0)
					(length 3.81)
					(hide yes)
					(name "GND"
						(effects
							(font
								(size 1.27 1.27)
							)
						)
					)
					(number "A17"
						(effects
							(font
								(size 1.27 1.27)
							)
						)
					)
				)
				(pin passive line
					(at 0 -15.24 0)
					(length 3.81)
					(hide yes)
					(name "GND"
						(effects
							(font
								(size 1.27 1.27)
							)
						)
					)
					(number "A20"
						(effects
							(font
								(size 1.27 1.27)
							)
						)
					)
				)
				(pin passive line
					(at 0 -15.24 0)
					(length 3.81)
					(hide yes)
					(name "GND"
						(effects
							(font
								(size 1.27 1.27)
							)
						)
					)
					(number "A21"
						(effects
							(font
								(size 1.27 1.27)
							)
						)
					)
				)
				(pin passive line
					(at 0 -15.24 0)
					(length 3.81)
					(hide yes)
					(name "GND"
						(effects
							(font
								(size 1.27 1.27)
							)
						)
					)
					(number "A24"
						(effects
							(font
								(size 1.27 1.27)
							)
						)
					)
				)
				(pin passive line
					(at 0 -15.24 0)
					(length 3.81)
					(hide yes)
					(name "GND"
						(effects
							(font
								(size 1.27 1.27)
							)
						)
					)
					(number "A25"
						(effects
							(font
								(size 1.27 1.27)
							)
						)
					)
				)
				(pin passive line
					(at 0 -15.24 0)
					(length 3.81)
					(hide yes)
					(name "GND"
						(effects
							(font
								(size 1.27 1.27)
							)
						)
					)
					(number "A28"
						(effects
							(font
								(size 1.27 1.27)
							)
						)
					)
				)
				(pin passive line
					(at 0 -15.24 0)
					(length 3.81)
					(hide yes)
					(name "GND"
						(effects
							(font
								(size 1.27 1.27)
							)
						)
					)
					(number "A29"
						(effects
							(font
								(size 1.27 1.27)
							)
						)
					)
				)
				(pin passive line
					(at 0 -15.24 0)
					(length 3.81)
					(hide yes)
					(name "GND"
						(effects
							(font
								(size 1.27 1.27)
							)
						)
					)
					(number "A32"
						(effects
							(font
								(size 1.27 1.27)
							)
						)
					)
				)
				(pin passive line
					(at 0 -15.24 0)
					(length 3.81)
					(hide yes)
					(name "GND"
						(effects
							(font
								(size 1.27 1.27)
							)
						)
					)
					(number "A33"
						(effects
							(font
								(size 1.27 1.27)
							)
						)
					)
				)
				(pin passive line
					(at 0 -15.24 0)
					(length 3.81)
					(hide yes)
					(name "GND"
						(effects
							(font
								(size 1.27 1.27)
							)
						)
					)
					(number "A36"
						(effects
							(font
								(size 1.27 1.27)
							)
						)
					)
				)
				(pin passive line
					(at 0 -15.24 0)
					(length 3.81)
					(hide yes)
					(name "GND"
						(effects
							(font
								(size 1.27 1.27)
							)
						)
					)
					(number "A37"
						(effects
							(font
								(size 1.27 1.27)
							)
						)
					)
				)
				(pin passive line
					(at 0 -15.24 0)
					(length 3.81)
					(hide yes)
					(name "GND"
						(effects
							(font
								(size 1.27 1.27)
							)
						)
					)
					(number "A40"
						(effects
							(font
								(size 1.27 1.27)
							)
						)
					)
				)
				(pin passive line
					(at 0 -15.24 0)
					(length 3.81)
					(hide yes)
					(name "GND"
						(effects
							(font
								(size 1.27 1.27)
							)
						)
					)
					(number "B02"
						(effects
							(font
								(size 1.27 1.27)
							)
						)
					)
				)
				(pin passive line
					(at 0 -15.24 0)
					(length 3.81)
					(hide yes)
					(name "GND"
						(effects
							(font
								(size 1.27 1.27)
							)
						)
					)
					(number "B03"
						(effects
							(font
								(size 1.27 1.27)
							)
						)
					)
				)
				(pin passive line
					(at 0 -15.24 0)
					(length 3.81)
					(hide yes)
					(name "GND"
						(effects
							(font
								(size 1.27 1.27)
							)
						)
					)
					(number "B06"
						(effects
							(font
								(size 1.27 1.27)
							)
						)
					)
				)
				(pin passive line
					(at 0 -15.24 0)
					(length 3.81)
					(hide yes)
					(name "GND"
						(effects
							(font
								(size 1.27 1.27)
							)
						)
					)
					(number "B07"
						(effects
							(font
								(size 1.27 1.27)
							)
						)
					)
				)
				(pin passive line
					(at 0 -15.24 0)
					(length 3.81)
					(hide yes)
					(name "GND"
						(effects
							(font
								(size 1.27 1.27)
							)
						)
					)
					(number "B10"
						(effects
							(font
								(size 1.27 1.27)
							)
						)
					)
				)
				(pin passive line
					(at 0 -15.24 0)
					(length 3.81)
					(hide yes)
					(name "GND"
						(effects
							(font
								(size 1.27 1.27)
							)
						)
					)
					(number "B11"
						(effects
							(font
								(size 1.27 1.27)
							)
						)
					)
				)
				(pin passive line
					(at 0 -15.24 0)
					(length 3.81)
					(hide yes)
					(name "GND"
						(effects
							(font
								(size 1.27 1.27)
							)
						)
					)
					(number "B14"
						(effects
							(font
								(size 1.27 1.27)
							)
						)
					)
				)
				(pin passive line
					(at 0 -15.24 0)
					(length 3.81)
					(hide yes)
					(name "GND"
						(effects
							(font
								(size 1.27 1.27)
							)
						)
					)
					(number "B15"
						(effects
							(font
								(size 1.27 1.27)
							)
						)
					)
				)
				(pin passive line
					(at 0 -15.24 0)
					(length 3.81)
					(hide yes)
					(name "GND"
						(effects
							(font
								(size 1.27 1.27)
							)
						)
					)
					(number "B18"
						(effects
							(font
								(size 1.27 1.27)
							)
						)
					)
				)
				(pin passive line
					(at 0 -15.24 0)
					(length 3.81)
					(hide yes)
					(name "GND"
						(effects
							(font
								(size 1.27 1.27)
							)
						)
					)
					(number "B19"
						(effects
							(font
								(size 1.27 1.27)
							)
						)
					)
				)
				(pin passive line
					(at 0 -15.24 0)
					(length 3.81)
					(hide yes)
					(name "GND"
						(effects
							(font
								(size 1.27 1.27)
							)
						)
					)
					(number "B22"
						(effects
							(font
								(size 1.27 1.27)
							)
						)
					)
				)
				(pin passive line
					(at 0 -15.24 0)
					(length 3.81)
					(hide yes)
					(name "GND"
						(effects
							(font
								(size 1.27 1.27)
							)
						)
					)
					(number "B23"
						(effects
							(font
								(size 1.27 1.27)
							)
						)
					)
				)
				(pin passive line
					(at 0 -15.24 0)
					(length 3.81)
					(hide yes)
					(name "GND"
						(effects
							(font
								(size 1.27 1.27)
							)
						)
					)
					(number "B26"
						(effects
							(font
								(size 1.27 1.27)
							)
						)
					)
				)
				(pin passive line
					(at 0 -15.24 0)
					(length 3.81)
					(hide yes)
					(name "GND"
						(effects
							(font
								(size 1.27 1.27)
							)
						)
					)
					(number "B27"
						(effects
							(font
								(size 1.27 1.27)
							)
						)
					)
				)
				(pin passive line
					(at 0 -15.24 0)
					(length 3.81)
					(hide yes)
					(name "GND"
						(effects
							(font
								(size 1.27 1.27)
							)
						)
					)
					(number "B30"
						(effects
							(font
								(size 1.27 1.27)
							)
						)
					)
				)
				(pin passive line
					(at 0 -15.24 0)
					(length 3.81)
					(hide yes)
					(name "GND"
						(effects
							(font
								(size 1.27 1.27)
							)
						)
					)
					(number "B31"
						(effects
							(font
								(size 1.27 1.27)
							)
						)
					)
				)
				(pin passive line
					(at 0 -15.24 0)
					(length 3.81)
					(hide yes)
					(name "GND"
						(effects
							(font
								(size 1.27 1.27)
							)
						)
					)
					(number "B34"
						(effects
							(font
								(size 1.27 1.27)
							)
						)
					)
				)
				(pin passive line
					(at 0 -15.24 0)
					(length 3.81)
					(hide yes)
					(name "GND"
						(effects
							(font
								(size 1.27 1.27)
							)
						)
					)
					(number "B35"
						(effects
							(font
								(size 1.27 1.27)
							)
						)
					)
				)
				(pin passive line
					(at 0 -15.24 0)
					(length 3.81)
					(hide yes)
					(name "GND"
						(effects
							(font
								(size 1.27 1.27)
							)
						)
					)
					(number "B38"
						(effects
							(font
								(size 1.27 1.27)
							)
						)
					)
				)
				(pin passive line
					(at 0 -15.24 0)
					(length 3.81)
					(hide yes)
					(name "GND"
						(effects
							(font
								(size 1.27 1.27)
							)
						)
					)
					(number "B39"
						(effects
							(font
								(size 1.27 1.27)
							)
						)
					)
				)
				(pin passive line
					(at 0 -15.24 0)
					(length 3.81)
					(hide yes)
					(name "GND"
						(effects
							(font
								(size 1.27 1.27)
							)
						)
					)
					(number "C01"
						(effects
							(font
								(size 1.27 1.27)
							)
						)
					)
				)
				(pin passive line
					(at 0 -15.24 0)
					(length 3.81)
					(hide yes)
					(name "GND"
						(effects
							(font
								(size 1.27 1.27)
							)
						)
					)
					(number "C04"
						(effects
							(font
								(size 1.27 1.27)
							)
						)
					)
				)
				(pin passive line
					(at 0 -15.24 0)
					(length 3.81)
					(hide yes)
					(name "GND"
						(effects
							(font
								(size 1.27 1.27)
							)
						)
					)
					(number "C05"
						(effects
							(font
								(size 1.27 1.27)
							)
						)
					)
				)
				(pin passive line
					(at 0 -15.24 0)
					(length 3.81)
					(hide yes)
					(name "GND"
						(effects
							(font
								(size 1.27 1.27)
							)
						)
					)
					(number "C08"
						(effects
							(font
								(size 1.27 1.27)
							)
						)
					)
				)
				(pin passive line
					(at 0 -15.24 0)
					(length 3.81)
					(hide yes)
					(name "GND"
						(effects
							(font
								(size 1.27 1.27)
							)
						)
					)
					(number "C09"
						(effects
							(font
								(size 1.27 1.27)
							)
						)
					)
				)
				(pin passive line
					(at 0 -15.24 0)
					(length 3.81)
					(hide yes)
					(name "GND"
						(effects
							(font
								(size 1.27 1.27)
							)
						)
					)
					(number "C12"
						(effects
							(font
								(size 1.27 1.27)
							)
						)
					)
				)
				(pin passive line
					(at 0 -15.24 0)
					(length 3.81)
					(hide yes)
					(name "GND"
						(effects
							(font
								(size 1.27 1.27)
							)
						)
					)
					(number "C13"
						(effects
							(font
								(size 1.27 1.27)
							)
						)
					)
				)
				(pin passive line
					(at 0 -15.24 0)
					(length 3.81)
					(hide yes)
					(name "GND"
						(effects
							(font
								(size 1.27 1.27)
							)
						)
					)
					(number "C16"
						(effects
							(font
								(size 1.27 1.27)
							)
						)
					)
				)
				(pin passive line
					(at 0 -15.24 0)
					(length 3.81)
					(hide yes)
					(name "GND"
						(effects
							(font
								(size 1.27 1.27)
							)
						)
					)
					(number "C17"
						(effects
							(font
								(size 1.27 1.27)
							)
						)
					)
				)
				(pin passive line
					(at 0 -15.24 0)
					(length 3.81)
					(hide yes)
					(name "GND"
						(effects
							(font
								(size 1.27 1.27)
							)
						)
					)
					(number "C20"
						(effects
							(font
								(size 1.27 1.27)
							)
						)
					)
				)
				(pin passive line
					(at 0 -15.24 0)
					(length 3.81)
					(hide yes)
					(name "GND"
						(effects
							(font
								(size 1.27 1.27)
							)
						)
					)
					(number "C21"
						(effects
							(font
								(size 1.27 1.27)
							)
						)
					)
				)
				(pin passive line
					(at 0 -15.24 0)
					(length 3.81)
					(hide yes)
					(name "GND"
						(effects
							(font
								(size 1.27 1.27)
							)
						)
					)
					(number "C24"
						(effects
							(font
								(size 1.27 1.27)
							)
						)
					)
				)
				(pin passive line
					(at 0 -15.24 0)
					(length 3.81)
					(hide yes)
					(name "GND"
						(effects
							(font
								(size 1.27 1.27)
							)
						)
					)
					(number "C25"
						(effects
							(font
								(size 1.27 1.27)
							)
						)
					)
				)
				(pin passive line
					(at 0 -15.24 0)
					(length 3.81)
					(hide yes)
					(name "GND"
						(effects
							(font
								(size 1.27 1.27)
							)
						)
					)
					(number "C28"
						(effects
							(font
								(size 1.27 1.27)
							)
						)
					)
				)
				(pin passive line
					(at 0 -15.24 0)
					(length 3.81)
					(hide yes)
					(name "GND"
						(effects
							(font
								(size 1.27 1.27)
							)
						)
					)
					(number "C29"
						(effects
							(font
								(size 1.27 1.27)
							)
						)
					)
				)
				(pin passive line
					(at 0 -15.24 0)
					(length 3.81)
					(hide yes)
					(name "GND"
						(effects
							(font
								(size 1.27 1.27)
							)
						)
					)
					(number "C32"
						(effects
							(font
								(size 1.27 1.27)
							)
						)
					)
				)
				(pin passive line
					(at 0 -15.24 0)
					(length 3.81)
					(hide yes)
					(name "GND"
						(effects
							(font
								(size 1.27 1.27)
							)
						)
					)
					(number "C33"
						(effects
							(font
								(size 1.27 1.27)
							)
						)
					)
				)
				(pin passive line
					(at 0 -15.24 0)
					(length 3.81)
					(hide yes)
					(name "GND"
						(effects
							(font
								(size 1.27 1.27)
							)
						)
					)
					(number "C36"
						(effects
							(font
								(size 1.27 1.27)
							)
						)
					)
				)
				(pin passive line
					(at 0 -15.24 0)
					(length 3.81)
					(hide yes)
					(name "GND"
						(effects
							(font
								(size 1.27 1.27)
							)
						)
					)
					(number "C38"
						(effects
							(font
								(size 1.27 1.27)
							)
						)
					)
				)
				(pin passive line
					(at 0 -15.24 0)
					(length 3.81)
					(hide yes)
					(name "GND"
						(effects
							(font
								(size 1.27 1.27)
							)
						)
					)
					(number "C40"
						(effects
							(font
								(size 1.27 1.27)
							)
						)
					)
				)
				(pin passive line
					(at 0 -15.24 0)
					(length 3.81)
					(hide yes)
					(name "GND"
						(effects
							(font
								(size 1.27 1.27)
							)
						)
					)
					(number "D02"
						(effects
							(font
								(size 1.27 1.27)
							)
						)
					)
				)
				(pin passive line
					(at 0 -15.24 0)
					(length 3.81)
					(hide yes)
					(name "GND"
						(effects
							(font
								(size 1.27 1.27)
							)
						)
					)
					(number "D03"
						(effects
							(font
								(size 1.27 1.27)
							)
						)
					)
				)
				(pin passive line
					(at 0 -15.24 0)
					(length 3.81)
					(hide yes)
					(name "GND"
						(effects
							(font
								(size 1.27 1.27)
							)
						)
					)
					(number "D06"
						(effects
							(font
								(size 1.27 1.27)
							)
						)
					)
				)
				(pin passive line
					(at 0 -15.24 0)
					(length 3.81)
					(hide yes)
					(name "GND"
						(effects
							(font
								(size 1.27 1.27)
							)
						)
					)
					(number "D07"
						(effects
							(font
								(size 1.27 1.27)
							)
						)
					)
				)
				(pin passive line
					(at 0 -15.24 0)
					(length 3.81)
					(hide yes)
					(name "GND"
						(effects
							(font
								(size 1.27 1.27)
							)
						)
					)
					(number "D10"
						(effects
							(font
								(size 1.27 1.27)
							)
						)
					)
				)
				(pin passive line
					(at 0 -15.24 0)
					(length 3.81)
					(hide yes)
					(name "GND"
						(effects
							(font
								(size 1.27 1.27)
							)
						)
					)
					(number "D13"
						(effects
							(font
								(size 1.27 1.27)
							)
						)
					)
				)
				(pin passive line
					(at 0 -15.24 0)
					(length 3.81)
					(hide yes)
					(name "GND"
						(effects
							(font
								(size 1.27 1.27)
							)
						)
					)
					(number "D16"
						(effects
							(font
								(size 1.27 1.27)
							)
						)
					)
				)
				(pin passive line
					(at 0 -15.24 0)
					(length 3.81)
					(hide yes)
					(name "GND"
						(effects
							(font
								(size 1.27 1.27)
							)
						)
					)
					(number "D19"
						(effects
							(font
								(size 1.27 1.27)
							)
						)
					)
				)
				(pin passive line
					(at 0 -15.24 0)
					(length 3.81)
					(hide yes)
					(name "GND"
						(effects
							(font
								(size 1.27 1.27)
							)
						)
					)
					(number "D22"
						(effects
							(font
								(size 1.27 1.27)
							)
						)
					)
				)
				(pin passive line
					(at 0 -15.24 0)
					(length 3.81)
					(hide yes)
					(name "GND"
						(effects
							(font
								(size 1.27 1.27)
							)
						)
					)
					(number "D25"
						(effects
							(font
								(size 1.27 1.27)
							)
						)
					)
				)
				(pin passive line
					(at 0 -15.24 0)
					(length 3.81)
					(hide yes)
					(name "GND"
						(effects
							(font
								(size 1.27 1.27)
							)
						)
					)
					(number "D28"
						(effects
							(font
								(size 1.27 1.27)
							)
						)
					)
				)
				(pin passive line
					(at 0 -15.24 0)
					(length 3.81)
					(hide yes)
					(name "GND"
						(effects
							(font
								(size 1.27 1.27)
							)
						)
					)
					(number "D37"
						(effects
							(font
								(size 1.27 1.27)
							)
						)
					)
				)
				(pin passive line
					(at 0 -15.24 0)
					(length 3.81)
					(hide yes)
					(name "GND"
						(effects
							(font
								(size 1.27 1.27)
							)
						)
					)
					(number "D39"
						(effects
							(font
								(size 1.27 1.27)
							)
						)
					)
				)
				(pin passive line
					(at 0 -15.24 0)
					(length 3.81)
					(hide yes)
					(name "GND"
						(effects
							(font
								(size 1.27 1.27)
							)
						)
					)
					(number "E01"
						(effects
							(font
								(size 1.27 1.27)
							)
						)
					)
				)
				(pin passive line
					(at 0 -15.24 0)
					(length 3.81)
					(hide yes)
					(name "GND"
						(effects
							(font
								(size 1.27 1.27)
							)
						)
					)
					(number "E04"
						(effects
							(font
								(size 1.27 1.27)
							)
						)
					)
				)
				(pin passive line
					(at 0 -15.24 0)
					(length 3.81)
					(hide yes)
					(name "GND"
						(effects
							(font
								(size 1.27 1.27)
							)
						)
					)
					(number "E05"
						(effects
							(font
								(size 1.27 1.27)
							)
						)
					)
				)
				(pin passive line
					(at 0 -15.24 0)
					(length 3.81)
					(hide yes)
					(name "GND"
						(effects
							(font
								(size 1.27 1.27)
							)
						)
					)
					(number "E08"
						(effects
							(font
								(size 1.27 1.27)
							)
						)
					)
				)
				(pin passive line
					(at 0 -15.24 0)
					(length 3.81)
					(hide yes)
					(name "GND"
						(effects
							(font
								(size 1.27 1.27)
							)
						)
					)
					(number "E11"
						(effects
							(font
								(size 1.27 1.27)
							)
						)
					)
				)
				(pin passive line
					(at 0 -15.24 0)
					(length 3.81)
					(hide yes)
					(name "GND"
						(effects
							(font
								(size 1.27 1.27)
							)
						)
					)
					(number "E14"
						(effects
							(font
								(size 1.27 1.27)
							)
						)
					)
				)
				(pin passive line
					(at 0 -15.24 0)
					(length 3.81)
					(hide yes)
					(name "GND"
						(effects
							(font
								(size 1.27 1.27)
							)
						)
					)
					(number "E17"
						(effects
							(font
								(size 1.27 1.27)
							)
						)
					)
				)
				(pin passive line
					(at 0 -15.24 0)
					(length 3.81)
					(hide yes)
					(name "GND"
						(effects
							(font
								(size 1.27 1.27)
							)
						)
					)
					(number "E20"
						(effects
							(font
								(size 1.27 1.27)
							)
						)
					)
				)
				(pin passive line
					(at 0 -15.24 0)
					(length 3.81)
					(hide yes)
					(name "GND"
						(effects
							(font
								(size 1.27 1.27)
							)
						)
					)
					(number "E23"
						(effects
							(font
								(size 1.27 1.27)
							)
						)
					)
				)
				(pin passive line
					(at 0 -15.24 0)
					(length 3.81)
					(hide yes)
					(name "GND"
						(effects
							(font
								(size 1.27 1.27)
							)
						)
					)
					(number "E26"
						(effects
							(font
								(size 1.27 1.27)
							)
						)
					)
				)
				(pin passive line
					(at 0 -15.24 0)
					(length 3.81)
					(hide yes)
					(name "GND"
						(effects
							(font
								(size 1.27 1.27)
							)
						)
					)
					(number "E29"
						(effects
							(font
								(size 1.27 1.27)
							)
						)
					)
				)
				(pin passive line
					(at 0 -15.24 0)
					(length 3.81)
					(hide yes)
					(name "GND"
						(effects
							(font
								(size 1.27 1.27)
							)
						)
					)
					(number "E32"
						(effects
							(font
								(size 1.27 1.27)
							)
						)
					)
				)
				(pin passive line
					(at 0 -15.24 0)
					(length 3.81)
					(hide yes)
					(name "GND"
						(effects
							(font
								(size 1.27 1.27)
							)
						)
					)
					(number "E35"
						(effects
							(font
								(size 1.27 1.27)
							)
						)
					)
				)
				(pin passive line
					(at 0 -15.24 0)
					(length 3.81)
					(hide yes)
					(name "GND"
						(effects
							(font
								(size 1.27 1.27)
							)
						)
					)
					(number "E38"
						(effects
							(font
								(size 1.27 1.27)
							)
						)
					)
				)
				(pin passive line
					(at 0 -15.24 0)
					(length 3.81)
					(hide yes)
					(name "GND"
						(effects
							(font
								(size 1.27 1.27)
							)
						)
					)
					(number "E40"
						(effects
							(font
								(size 1.27 1.27)
							)
						)
					)
				)
				(pin passive line
					(at 0 -15.24 0)
					(length 3.81)
					(hide yes)
					(name "GND"
						(effects
							(font
								(size 1.27 1.27)
							)
						)
					)
					(number "F02"
						(effects
							(font
								(size 1.27 1.27)
							)
						)
					)
				)
				(pin passive line
					(at 0 -15.24 0)
					(length 3.81)
					(hide yes)
					(name "GND"
						(effects
							(font
								(size 1.27 1.27)
							)
						)
					)
					(number "F03"
						(effects
							(font
								(size 1.27 1.27)
							)
						)
					)
				)
				(pin passive line
					(at 0 -15.24 0)
					(length 3.81)
					(hide yes)
					(name "GND"
						(effects
							(font
								(size 1.27 1.27)
							)
						)
					)
					(number "F06"
						(effects
							(font
								(size 1.27 1.27)
							)
						)
					)
				)
				(pin passive line
					(at 0 -15.24 0)
					(length 3.81)
					(hide yes)
					(name "GND"
						(effects
							(font
								(size 1.27 1.27)
							)
						)
					)
					(number "F09"
						(effects
							(font
								(size 1.27 1.27)
							)
						)
					)
				)
				(pin passive line
					(at 0 -15.24 0)
					(length 3.81)
					(hide yes)
					(name "GND"
						(effects
							(font
								(size 1.27 1.27)
							)
						)
					)
					(number "F12"
						(effects
							(font
								(size 1.27 1.27)
							)
						)
					)
				)
				(pin passive line
					(at 0 -15.24 0)
					(length 3.81)
					(hide yes)
					(name "GND"
						(effects
							(font
								(size 1.27 1.27)
							)
						)
					)
					(number "F15"
						(effects
							(font
								(size 1.27 1.27)
							)
						)
					)
				)
				(pin passive line
					(at 0 -15.24 0)
					(length 3.81)
					(hide yes)
					(name "GND"
						(effects
							(font
								(size 1.27 1.27)
							)
						)
					)
					(number "F18"
						(effects
							(font
								(size 1.27 1.27)
							)
						)
					)
				)
				(pin passive line
					(at 0 -15.24 0)
					(length 3.81)
					(hide yes)
					(name "GND"
						(effects
							(font
								(size 1.27 1.27)
							)
						)
					)
					(number "F21"
						(effects
							(font
								(size 1.27 1.27)
							)
						)
					)
				)
				(pin passive line
					(at 0 -15.24 0)
					(length 3.81)
					(hide yes)
					(name "GND"
						(effects
							(font
								(size 1.27 1.27)
							)
						)
					)
					(number "F24"
						(effects
							(font
								(size 1.27 1.27)
							)
						)
					)
				)
				(pin passive line
					(at 0 -15.24 0)
					(length 3.81)
					(hide yes)
					(name "GND"
						(effects
							(font
								(size 1.27 1.27)
							)
						)
					)
					(number "F27"
						(effects
							(font
								(size 1.27 1.27)
							)
						)
					)
				)
				(pin passive line
					(at 0 -15.24 0)
					(length 3.81)
					(hide yes)
					(name "GND"
						(effects
							(font
								(size 1.27 1.27)
							)
						)
					)
					(number "F30"
						(effects
							(font
								(size 1.27 1.27)
							)
						)
					)
				)
				(pin passive line
					(at 0 -15.24 0)
					(length 3.81)
					(hide yes)
					(name "GND"
						(effects
							(font
								(size 1.27 1.27)
							)
						)
					)
					(number "F33"
						(effects
							(font
								(size 1.27 1.27)
							)
						)
					)
				)
				(pin passive line
					(at 0 -15.24 0)
					(length 3.81)
					(hide yes)
					(name "GND"
						(effects
							(font
								(size 1.27 1.27)
							)
						)
					)
					(number "F36"
						(effects
							(font
								(size 1.27 1.27)
							)
						)
					)
				)
				(pin passive line
					(at 0 -15.24 0)
					(length 3.81)
					(hide yes)
					(name "GND"
						(effects
							(font
								(size 1.27 1.27)
							)
						)
					)
					(number "F39"
						(effects
							(font
								(size 1.27 1.27)
							)
						)
					)
				)
				(pin passive line
					(at 0 -15.24 0)
					(length 3.81)
					(hide yes)
					(name "GND"
						(effects
							(font
								(size 1.27 1.27)
							)
						)
					)
					(number "G01"
						(effects
							(font
								(size 1.27 1.27)
							)
						)
					)
				)
				(pin passive line
					(at 0 -15.24 0)
					(length 3.81)
					(hide yes)
					(name "GND"
						(effects
							(font
								(size 1.27 1.27)
							)
						)
					)
					(number "G04"
						(effects
							(font
								(size 1.27 1.27)
							)
						)
					)
				)
				(pin passive line
					(at 0 -15.24 0)
					(length 3.81)
					(hide yes)
					(name "GND"
						(effects
							(font
								(size 1.27 1.27)
							)
						)
					)
					(number "G05"
						(effects
							(font
								(size 1.27 1.27)
							)
						)
					)
				)
				(pin passive line
					(at 0 -15.24 0)
					(length 3.81)
					(hide yes)
					(name "GND"
						(effects
							(font
								(size 1.27 1.27)
							)
						)
					)
					(number "G08"
						(effects
							(font
								(size 1.27 1.27)
							)
						)
					)
				)
				(pin passive line
					(at 0 -15.24 0)
					(length 3.81)
					(hide yes)
					(name "GND"
						(effects
							(font
								(size 1.27 1.27)
							)
						)
					)
					(number "G11"
						(effects
							(font
								(size 1.27 1.27)
							)
						)
					)
				)
				(pin passive line
					(at 0 -15.24 0)
					(length 3.81)
					(hide yes)
					(name "GND"
						(effects
							(font
								(size 1.27 1.27)
							)
						)
					)
					(number "G14"
						(effects
							(font
								(size 1.27 1.27)
							)
						)
					)
				)
				(pin passive line
					(at 0 -15.24 0)
					(length 3.81)
					(hide yes)
					(name "GND"
						(effects
							(font
								(size 1.27 1.27)
							)
						)
					)
					(number "G17"
						(effects
							(font
								(size 1.27 1.27)
							)
						)
					)
				)
				(pin passive line
					(at 0 -15.24 0)
					(length 3.81)
					(hide yes)
					(name "GND"
						(effects
							(font
								(size 1.27 1.27)
							)
						)
					)
					(number "G20"
						(effects
							(font
								(size 1.27 1.27)
							)
						)
					)
				)
				(pin passive line
					(at 0 -15.24 0)
					(length 3.81)
					(hide yes)
					(name "GND"
						(effects
							(font
								(size 1.27 1.27)
							)
						)
					)
					(number "G23"
						(effects
							(font
								(size 1.27 1.27)
							)
						)
					)
				)
				(pin passive line
					(at 0 -15.24 0)
					(length 3.81)
					(hide yes)
					(name "GND"
						(effects
							(font
								(size 1.27 1.27)
							)
						)
					)
					(number "G26"
						(effects
							(font
								(size 1.27 1.27)
							)
						)
					)
				)
				(pin passive line
					(at 0 -15.24 0)
					(length 3.81)
					(hide yes)
					(name "GND"
						(effects
							(font
								(size 1.27 1.27)
							)
						)
					)
					(number "G29"
						(effects
							(font
								(size 1.27 1.27)
							)
						)
					)
				)
				(pin passive line
					(at 0 -15.24 0)
					(length 3.81)
					(hide yes)
					(name "GND"
						(effects
							(font
								(size 1.27 1.27)
							)
						)
					)
					(number "G32"
						(effects
							(font
								(size 1.27 1.27)
							)
						)
					)
				)
				(pin passive line
					(at 0 -15.24 0)
					(length 3.81)
					(hide yes)
					(name "GND"
						(effects
							(font
								(size 1.27 1.27)
							)
						)
					)
					(number "G35"
						(effects
							(font
								(size 1.27 1.27)
							)
						)
					)
				)
				(pin passive line
					(at 0 -15.24 0)
					(length 3.81)
					(hide yes)
					(name "GND"
						(effects
							(font
								(size 1.27 1.27)
							)
						)
					)
					(number "G38"
						(effects
							(font
								(size 1.27 1.27)
							)
						)
					)
				)
				(pin passive line
					(at 0 -15.24 0)
					(length 3.81)
					(hide yes)
					(name "GND"
						(effects
							(font
								(size 1.27 1.27)
							)
						)
					)
					(number "G40"
						(effects
							(font
								(size 1.27 1.27)
							)
						)
					)
				)
				(pin passive line
					(at 0 -15.24 0)
					(length 3.81)
					(hide yes)
					(name "GND"
						(effects
							(font
								(size 1.27 1.27)
							)
						)
					)
					(number "H03"
						(effects
							(font
								(size 1.27 1.27)
							)
						)
					)
				)
				(pin passive line
					(at 0 -15.24 0)
					(length 3.81)
					(hide yes)
					(name "GND"
						(effects
							(font
								(size 1.27 1.27)
							)
						)
					)
					(number "H06"
						(effects
							(font
								(size 1.27 1.27)
							)
						)
					)
				)
				(pin passive line
					(at 0 -15.24 0)
					(length 3.81)
					(hide yes)
					(name "GND"
						(effects
							(font
								(size 1.27 1.27)
							)
						)
					)
					(number "H09"
						(effects
							(font
								(size 1.27 1.27)
							)
						)
					)
				)
				(pin passive line
					(at 0 -15.24 0)
					(length 3.81)
					(hide yes)
					(name "GND"
						(effects
							(font
								(size 1.27 1.27)
							)
						)
					)
					(number "H12"
						(effects
							(font
								(size 1.27 1.27)
							)
						)
					)
				)
				(pin passive line
					(at 0 -15.24 0)
					(length 3.81)
					(hide yes)
					(name "GND"
						(effects
							(font
								(size 1.27 1.27)
							)
						)
					)
					(number "H15"
						(effects
							(font
								(size 1.27 1.27)
							)
						)
					)
				)
				(pin passive line
					(at 0 -15.24 0)
					(length 3.81)
					(hide yes)
					(name "GND"
						(effects
							(font
								(size 1.27 1.27)
							)
						)
					)
					(number "H18"
						(effects
							(font
								(size 1.27 1.27)
							)
						)
					)
				)
				(pin passive line
					(at 0 -15.24 0)
					(length 3.81)
					(hide yes)
					(name "GND"
						(effects
							(font
								(size 1.27 1.27)
							)
						)
					)
					(number "H21"
						(effects
							(font
								(size 1.27 1.27)
							)
						)
					)
				)
				(pin passive line
					(at 0 -15.24 0)
					(length 3.81)
					(hide yes)
					(name "GND"
						(effects
							(font
								(size 1.27 1.27)
							)
						)
					)
					(number "H24"
						(effects
							(font
								(size 1.27 1.27)
							)
						)
					)
				)
				(pin passive line
					(at 0 -15.24 0)
					(length 3.81)
					(hide yes)
					(name "GND"
						(effects
							(font
								(size 1.27 1.27)
							)
						)
					)
					(number "H27"
						(effects
							(font
								(size 1.27 1.27)
							)
						)
					)
				)
				(pin passive line
					(at 0 -15.24 0)
					(length 3.81)
					(hide yes)
					(name "GND"
						(effects
							(font
								(size 1.27 1.27)
							)
						)
					)
					(number "H30"
						(effects
							(font
								(size 1.27 1.27)
							)
						)
					)
				)
				(pin passive line
					(at 0 -15.24 0)
					(length 3.81)
					(hide yes)
					(name "GND"
						(effects
							(font
								(size 1.27 1.27)
							)
						)
					)
					(number "H33"
						(effects
							(font
								(size 1.27 1.27)
							)
						)
					)
				)
				(pin passive line
					(at 0 -15.24 0)
					(length 3.81)
					(hide yes)
					(name "GND"
						(effects
							(font
								(size 1.27 1.27)
							)
						)
					)
					(number "H36"
						(effects
							(font
								(size 1.27 1.27)
							)
						)
					)
				)
				(pin passive line
					(at 0 -15.24 0)
					(length 3.81)
					(hide yes)
					(name "GND"
						(effects
							(font
								(size 1.27 1.27)
							)
						)
					)
					(number "H39"
						(effects
							(font
								(size 1.27 1.27)
							)
						)
					)
				)
				(pin passive line
					(at 0 -15.24 0)
					(length 3.81)
					(hide yes)
					(name "GND"
						(effects
							(font
								(size 1.27 1.27)
							)
						)
					)
					(number "J01"
						(effects
							(font
								(size 1.27 1.27)
							)
						)
					)
				)
				(pin passive line
					(at 0 -15.24 0)
					(length 3.81)
					(hide yes)
					(name "GND"
						(effects
							(font
								(size 1.27 1.27)
							)
						)
					)
					(number "J04"
						(effects
							(font
								(size 1.27 1.27)
							)
						)
					)
				)
				(pin passive line
					(at 0 -15.24 0)
					(length 3.81)
					(hide yes)
					(name "GND"
						(effects
							(font
								(size 1.27 1.27)
							)
						)
					)
					(number "J05"
						(effects
							(font
								(size 1.27 1.27)
							)
						)
					)
				)
				(pin passive line
					(at 0 -15.24 0)
					(length 3.81)
					(hide yes)
					(name "GND"
						(effects
							(font
								(size 1.27 1.27)
							)
						)
					)
					(number "J08"
						(effects
							(font
								(size 1.27 1.27)
							)
						)
					)
				)
				(pin passive line
					(at 0 -15.24 0)
					(length 3.81)
					(hide yes)
					(name "GND"
						(effects
							(font
								(size 1.27 1.27)
							)
						)
					)
					(number "J11"
						(effects
							(font
								(size 1.27 1.27)
							)
						)
					)
				)
				(pin passive line
					(at 0 -15.24 0)
					(length 3.81)
					(hide yes)
					(name "GND"
						(effects
							(font
								(size 1.27 1.27)
							)
						)
					)
					(number "J14"
						(effects
							(font
								(size 1.27 1.27)
							)
						)
					)
				)
				(pin passive line
					(at 0 -15.24 0)
					(length 3.81)
					(hide yes)
					(name "GND"
						(effects
							(font
								(size 1.27 1.27)
							)
						)
					)
					(number "J17"
						(effects
							(font
								(size 1.27 1.27)
							)
						)
					)
				)
				(pin passive line
					(at 0 -15.24 0)
					(length 3.81)
					(hide yes)
					(name "GND"
						(effects
							(font
								(size 1.27 1.27)
							)
						)
					)
					(number "J20"
						(effects
							(font
								(size 1.27 1.27)
							)
						)
					)
				)
				(pin passive line
					(at 0 -15.24 0)
					(length 3.81)
					(hide yes)
					(name "GND"
						(effects
							(font
								(size 1.27 1.27)
							)
						)
					)
					(number "J23"
						(effects
							(font
								(size 1.27 1.27)
							)
						)
					)
				)
				(pin passive line
					(at 0 -15.24 0)
					(length 3.81)
					(hide yes)
					(name "GND"
						(effects
							(font
								(size 1.27 1.27)
							)
						)
					)
					(number "J26"
						(effects
							(font
								(size 1.27 1.27)
							)
						)
					)
				)
				(pin passive line
					(at 0 -15.24 0)
					(length 3.81)
					(hide yes)
					(name "GND"
						(effects
							(font
								(size 1.27 1.27)
							)
						)
					)
					(number "J29"
						(effects
							(font
								(size 1.27 1.27)
							)
						)
					)
				)
				(pin passive line
					(at 0 -15.24 0)
					(length 3.81)
					(hide yes)
					(name "GND"
						(effects
							(font
								(size 1.27 1.27)
							)
						)
					)
					(number "J32"
						(effects
							(font
								(size 1.27 1.27)
							)
						)
					)
				)
				(pin passive line
					(at 0 -15.24 0)
					(length 3.81)
					(hide yes)
					(name "GND"
						(effects
							(font
								(size 1.27 1.27)
							)
						)
					)
					(number "J35"
						(effects
							(font
								(size 1.27 1.27)
							)
						)
					)
				)
				(pin passive line
					(at 0 -15.24 0)
					(length 3.81)
					(hide yes)
					(name "GND"
						(effects
							(font
								(size 1.27 1.27)
							)
						)
					)
					(number "J38"
						(effects
							(font
								(size 1.27 1.27)
							)
						)
					)
				)
				(pin passive line
					(at 0 -15.24 0)
					(length 3.81)
					(hide yes)
					(name "GND"
						(effects
							(font
								(size 1.27 1.27)
							)
						)
					)
					(number "J40"
						(effects
							(font
								(size 1.27 1.27)
							)
						)
					)
				)
				(pin passive line
					(at 0 -15.24 0)
					(length 3.81)
					(hide yes)
					(name "GND"
						(effects
							(font
								(size 1.27 1.27)
							)
						)
					)
					(number "K02"
						(effects
							(font
								(size 1.27 1.27)
							)
						)
					)
				)
				(pin passive line
					(at 0 -15.24 0)
					(length 3.81)
					(hide yes)
					(name "GND"
						(effects
							(font
								(size 1.27 1.27)
							)
						)
					)
					(number "K03"
						(effects
							(font
								(size 1.27 1.27)
							)
						)
					)
				)
				(pin passive line
					(at 0 -15.24 0)
					(length 3.81)
					(hide yes)
					(name "GND"
						(effects
							(font
								(size 1.27 1.27)
							)
						)
					)
					(number "K06"
						(effects
							(font
								(size 1.27 1.27)
							)
						)
					)
				)
				(pin passive line
					(at 0 -15.24 0)
					(length 3.81)
					(hide yes)
					(name "GND"
						(effects
							(font
								(size 1.27 1.27)
							)
						)
					)
					(number "K09"
						(effects
							(font
								(size 1.27 1.27)
							)
						)
					)
				)
				(pin passive line
					(at 0 -15.24 0)
					(length 3.81)
					(hide yes)
					(name "GND"
						(effects
							(font
								(size 1.27 1.27)
							)
						)
					)
					(number "K12"
						(effects
							(font
								(size 1.27 1.27)
							)
						)
					)
				)
				(pin passive line
					(at 0 -15.24 0)
					(length 3.81)
					(hide yes)
					(name "GND"
						(effects
							(font
								(size 1.27 1.27)
							)
						)
					)
					(number "K15"
						(effects
							(font
								(size 1.27 1.27)
							)
						)
					)
				)
				(pin passive line
					(at 0 -15.24 0)
					(length 3.81)
					(hide yes)
					(name "GND"
						(effects
							(font
								(size 1.27 1.27)
							)
						)
					)
					(number "K18"
						(effects
							(font
								(size 1.27 1.27)
							)
						)
					)
				)
				(pin passive line
					(at 0 -15.24 0)
					(length 3.81)
					(hide yes)
					(name "GND"
						(effects
							(font
								(size 1.27 1.27)
							)
						)
					)
					(number "K21"
						(effects
							(font
								(size 1.27 1.27)
							)
						)
					)
				)
				(pin passive line
					(at 0 -15.24 0)
					(length 3.81)
					(hide yes)
					(name "GND"
						(effects
							(font
								(size 1.27 1.27)
							)
						)
					)
					(number "K24"
						(effects
							(font
								(size 1.27 1.27)
							)
						)
					)
				)
				(pin passive line
					(at 0 -15.24 0)
					(length 3.81)
					(hide yes)
					(name "GND"
						(effects
							(font
								(size 1.27 1.27)
							)
						)
					)
					(number "K27"
						(effects
							(font
								(size 1.27 1.27)
							)
						)
					)
				)
				(pin passive line
					(at 0 -15.24 0)
					(length 3.81)
					(hide yes)
					(name "GND"
						(effects
							(font
								(size 1.27 1.27)
							)
						)
					)
					(number "K30"
						(effects
							(font
								(size 1.27 1.27)
							)
						)
					)
				)
				(pin passive line
					(at 0 -15.24 0)
					(length 3.81)
					(hide yes)
					(name "GND"
						(effects
							(font
								(size 1.27 1.27)
							)
						)
					)
					(number "K33"
						(effects
							(font
								(size 1.27 1.27)
							)
						)
					)
				)
				(pin passive line
					(at 0 -15.24 0)
					(length 3.81)
					(hide yes)
					(name "GND"
						(effects
							(font
								(size 1.27 1.27)
							)
						)
					)
					(number "K36"
						(effects
							(font
								(size 1.27 1.27)
							)
						)
					)
				)
				(pin passive line
					(at 0 -15.24 0)
					(length 3.81)
					(hide yes)
					(name "GND"
						(effects
							(font
								(size 1.27 1.27)
							)
						)
					)
					(number "K39"
						(effects
							(font
								(size 1.27 1.27)
							)
						)
					)
				)
				(pin passive line
					(at 0 -15.24 0)
					(length 3.81)
					(name "GND"
						(effects
							(font
								(size 1.27 1.27)
							)
						)
					)
					(number "L02"
						(effects
							(font
								(size 1.27 1.27)
							)
						)
					)
				)
				(pin passive line
					(at 0 -15.24 0)
					(length 3.81)
					(hide yes)
					(name "GND"
						(effects
							(font
								(size 1.27 1.27)
							)
						)
					)
					(number "L03"
						(effects
							(font
								(size 1.27 1.27)
							)
						)
					)
				)
				(pin passive line
					(at 0 -15.24 0)
					(length 3.81)
					(hide yes)
					(name "GND"
						(effects
							(font
								(size 1.27 1.27)
							)
						)
					)
					(number "L06"
						(effects
							(font
								(size 1.27 1.27)
							)
						)
					)
				)
				(pin passive line
					(at 0 -15.24 0)
					(length 3.81)
					(hide yes)
					(name "GND"
						(effects
							(font
								(size 1.27 1.27)
							)
						)
					)
					(number "L07"
						(effects
							(font
								(size 1.27 1.27)
							)
						)
					)
				)
				(pin passive line
					(at 0 -15.24 0)
					(length 3.81)
					(hide yes)
					(name "GND"
						(effects
							(font
								(size 1.27 1.27)
							)
						)
					)
					(number "L10"
						(effects
							(font
								(size 1.27 1.27)
							)
						)
					)
				)
				(pin passive line
					(at 0 -15.24 0)
					(length 3.81)
					(hide yes)
					(name "GND"
						(effects
							(font
								(size 1.27 1.27)
							)
						)
					)
					(number "L11"
						(effects
							(font
								(size 1.27 1.27)
							)
						)
					)
				)
				(pin passive line
					(at 0 -15.24 0)
					(length 3.81)
					(hide yes)
					(name "GND"
						(effects
							(font
								(size 1.27 1.27)
							)
						)
					)
					(number "L14"
						(effects
							(font
								(size 1.27 1.27)
							)
						)
					)
				)
				(pin passive line
					(at 0 -15.24 0)
					(length 3.81)
					(hide yes)
					(name "GND"
						(effects
							(font
								(size 1.27 1.27)
							)
						)
					)
					(number "L15"
						(effects
							(font
								(size 1.27 1.27)
							)
						)
					)
				)
				(pin passive line
					(at 0 -15.24 0)
					(length 3.81)
					(hide yes)
					(name "GND"
						(effects
							(font
								(size 1.27 1.27)
							)
						)
					)
					(number "L18"
						(effects
							(font
								(size 1.27 1.27)
							)
						)
					)
				)
				(pin passive line
					(at 0 -15.24 0)
					(length 3.81)
					(hide yes)
					(name "GND"
						(effects
							(font
								(size 1.27 1.27)
							)
						)
					)
					(number "L19"
						(effects
							(font
								(size 1.27 1.27)
							)
						)
					)
				)
				(pin passive line
					(at 0 -15.24 0)
					(length 3.81)
					(hide yes)
					(name "GND"
						(effects
							(font
								(size 1.27 1.27)
							)
						)
					)
					(number "L22"
						(effects
							(font
								(size 1.27 1.27)
							)
						)
					)
				)
				(pin passive line
					(at 0 -15.24 0)
					(length 3.81)
					(hide yes)
					(name "GND"
						(effects
							(font
								(size 1.27 1.27)
							)
						)
					)
					(number "L23"
						(effects
							(font
								(size 1.27 1.27)
							)
						)
					)
				)
				(pin passive line
					(at 0 -15.24 0)
					(length 3.81)
					(hide yes)
					(name "GND"
						(effects
							(font
								(size 1.27 1.27)
							)
						)
					)
					(number "L26"
						(effects
							(font
								(size 1.27 1.27)
							)
						)
					)
				)
				(pin passive line
					(at 0 -15.24 0)
					(length 3.81)
					(hide yes)
					(name "GND"
						(effects
							(font
								(size 1.27 1.27)
							)
						)
					)
					(number "L27"
						(effects
							(font
								(size 1.27 1.27)
							)
						)
					)
				)
				(pin passive line
					(at 0 -15.24 0)
					(length 3.81)
					(hide yes)
					(name "GND"
						(effects
							(font
								(size 1.27 1.27)
							)
						)
					)
					(number "L30"
						(effects
							(font
								(size 1.27 1.27)
							)
						)
					)
				)
				(pin passive line
					(at 0 -15.24 0)
					(length 3.81)
					(hide yes)
					(name "GND"
						(effects
							(font
								(size 1.27 1.27)
							)
						)
					)
					(number "L31"
						(effects
							(font
								(size 1.27 1.27)
							)
						)
					)
				)
				(pin passive line
					(at 0 -15.24 0)
					(length 3.81)
					(hide yes)
					(name "GND"
						(effects
							(font
								(size 1.27 1.27)
							)
						)
					)
					(number "L34"
						(effects
							(font
								(size 1.27 1.27)
							)
						)
					)
				)
				(pin passive line
					(at 0 -15.24 0)
					(length 3.81)
					(hide yes)
					(name "GND"
						(effects
							(font
								(size 1.27 1.27)
							)
						)
					)
					(number "L35"
						(effects
							(font
								(size 1.27 1.27)
							)
						)
					)
				)
				(pin passive line
					(at 0 -15.24 0)
					(length 3.81)
					(hide yes)
					(name "GND"
						(effects
							(font
								(size 1.27 1.27)
							)
						)
					)
					(number "L38"
						(effects
							(font
								(size 1.27 1.27)
							)
						)
					)
				)
				(pin passive line
					(at 0 -15.24 0)
					(length 3.81)
					(hide yes)
					(name "GND"
						(effects
							(font
								(size 1.27 1.27)
							)
						)
					)
					(number "L39"
						(effects
							(font
								(size 1.27 1.27)
							)
						)
					)
				)
				(pin passive line
					(at 0 -15.24 0)
					(length 3.81)
					(hide yes)
					(name "GND"
						(effects
							(font
								(size 1.27 1.27)
							)
						)
					)
					(number "M01"
						(effects
							(font
								(size 1.27 1.27)
							)
						)
					)
				)
				(pin passive line
					(at 0 -15.24 0)
					(length 3.81)
					(hide yes)
					(name "GND"
						(effects
							(font
								(size 1.27 1.27)
							)
						)
					)
					(number "M04"
						(effects
							(font
								(size 1.27 1.27)
							)
						)
					)
				)
				(pin passive line
					(at 0 -15.24 0)
					(length 3.81)
					(hide yes)
					(name "GND"
						(effects
							(font
								(size 1.27 1.27)
							)
						)
					)
					(number "M05"
						(effects
							(font
								(size 1.27 1.27)
							)
						)
					)
				)
				(pin passive line
					(at 0 -15.24 0)
					(length 3.81)
					(hide yes)
					(name "GND"
						(effects
							(font
								(size 1.27 1.27)
							)
						)
					)
					(number "M08"
						(effects
							(font
								(size 1.27 1.27)
							)
						)
					)
				)
				(pin passive line
					(at 0 -15.24 0)
					(length 3.81)
					(hide yes)
					(name "GND"
						(effects
							(font
								(size 1.27 1.27)
							)
						)
					)
					(number "M09"
						(effects
							(font
								(size 1.27 1.27)
							)
						)
					)
				)
				(pin passive line
					(at 0 -15.24 0)
					(length 3.81)
					(hide yes)
					(name "GND"
						(effects
							(font
								(size 1.27 1.27)
							)
						)
					)
					(number "M12"
						(effects
							(font
								(size 1.27 1.27)
							)
						)
					)
				)
				(pin passive line
					(at 0 -15.24 0)
					(length 3.81)
					(hide yes)
					(name "GND"
						(effects
							(font
								(size 1.27 1.27)
							)
						)
					)
					(number "M13"
						(effects
							(font
								(size 1.27 1.27)
							)
						)
					)
				)
				(pin passive line
					(at 0 -15.24 0)
					(length 3.81)
					(hide yes)
					(name "GND"
						(effects
							(font
								(size 1.27 1.27)
							)
						)
					)
					(number "M16"
						(effects
							(font
								(size 1.27 1.27)
							)
						)
					)
				)
				(pin passive line
					(at 0 -15.24 0)
					(length 3.81)
					(hide yes)
					(name "GND"
						(effects
							(font
								(size 1.27 1.27)
							)
						)
					)
					(number "M17"
						(effects
							(font
								(size 1.27 1.27)
							)
						)
					)
				)
				(pin passive line
					(at 0 -15.24 0)
					(length 3.81)
					(hide yes)
					(name "GND"
						(effects
							(font
								(size 1.27 1.27)
							)
						)
					)
					(number "M20"
						(effects
							(font
								(size 1.27 1.27)
							)
						)
					)
				)
				(pin passive line
					(at 0 -15.24 0)
					(length 3.81)
					(hide yes)
					(name "GND"
						(effects
							(font
								(size 1.27 1.27)
							)
						)
					)
					(number "M21"
						(effects
							(font
								(size 1.27 1.27)
							)
						)
					)
				)
				(pin passive line
					(at 0 -15.24 0)
					(length 3.81)
					(hide yes)
					(name "GND"
						(effects
							(font
								(size 1.27 1.27)
							)
						)
					)
					(number "M24"
						(effects
							(font
								(size 1.27 1.27)
							)
						)
					)
				)
				(pin passive line
					(at 0 -15.24 0)
					(length 3.81)
					(hide yes)
					(name "GND"
						(effects
							(font
								(size 1.27 1.27)
							)
						)
					)
					(number "M25"
						(effects
							(font
								(size 1.27 1.27)
							)
						)
					)
				)
				(pin passive line
					(at 0 -15.24 0)
					(length 3.81)
					(hide yes)
					(name "GND"
						(effects
							(font
								(size 1.27 1.27)
							)
						)
					)
					(number "M28"
						(effects
							(font
								(size 1.27 1.27)
							)
						)
					)
				)
				(pin passive line
					(at 0 -15.24 0)
					(length 3.81)
					(hide yes)
					(name "GND"
						(effects
							(font
								(size 1.27 1.27)
							)
						)
					)
					(number "M29"
						(effects
							(font
								(size 1.27 1.27)
							)
						)
					)
				)
				(pin passive line
					(at 0 -15.24 0)
					(length 3.81)
					(hide yes)
					(name "GND"
						(effects
							(font
								(size 1.27 1.27)
							)
						)
					)
					(number "M32"
						(effects
							(font
								(size 1.27 1.27)
							)
						)
					)
				)
				(pin passive line
					(at 0 -15.24 0)
					(length 3.81)
					(hide yes)
					(name "GND"
						(effects
							(font
								(size 1.27 1.27)
							)
						)
					)
					(number "M33"
						(effects
							(font
								(size 1.27 1.27)
							)
						)
					)
				)
				(pin passive line
					(at 0 -15.24 0)
					(length 3.81)
					(hide yes)
					(name "GND"
						(effects
							(font
								(size 1.27 1.27)
							)
						)
					)
					(number "M36"
						(effects
							(font
								(size 1.27 1.27)
							)
						)
					)
				)
				(pin passive line
					(at 0 -15.24 0)
					(length 3.81)
					(hide yes)
					(name "GND"
						(effects
							(font
								(size 1.27 1.27)
							)
						)
					)
					(number "M37"
						(effects
							(font
								(size 1.27 1.27)
							)
						)
					)
				)
				(pin passive line
					(at 0 -15.24 0)
					(length 3.81)
					(hide yes)
					(name "GND"
						(effects
							(font
								(size 1.27 1.27)
							)
						)
					)
					(number "M40"
						(effects
							(font
								(size 1.27 1.27)
							)
						)
					)
				)
				(pin passive line
					(at 0 -15.24 0)
					(length 3.81)
					(hide yes)
					(name "GND"
						(effects
							(font
								(size 1.27 1.27)
							)
						)
					)
					(number "Y01"
						(effects
							(font
								(size 1.27 1.27)
							)
						)
					)
				)
				(pin passive line
					(at 0 -15.24 0)
					(length 3.81)
					(hide yes)
					(name "GND"
						(effects
							(font
								(size 1.27 1.27)
							)
						)
					)
					(number "Y04"
						(effects
							(font
								(size 1.27 1.27)
							)
						)
					)
				)
				(pin passive line
					(at 0 -15.24 0)
					(length 3.81)
					(hide yes)
					(name "GND"
						(effects
							(font
								(size 1.27 1.27)
							)
						)
					)
					(number "Y05"
						(effects
							(font
								(size 1.27 1.27)
							)
						)
					)
				)
				(pin passive line
					(at 0 -15.24 0)
					(length 3.81)
					(hide yes)
					(name "GND"
						(effects
							(font
								(size 1.27 1.27)
							)
						)
					)
					(number "Y08"
						(effects
							(font
								(size 1.27 1.27)
							)
						)
					)
				)
				(pin passive line
					(at 0 -15.24 0)
					(length 3.81)
					(hide yes)
					(name "GND"
						(effects
							(font
								(size 1.27 1.27)
							)
						)
					)
					(number "Y09"
						(effects
							(font
								(size 1.27 1.27)
							)
						)
					)
				)
				(pin passive line
					(at 0 -15.24 0)
					(length 3.81)
					(hide yes)
					(name "GND"
						(effects
							(font
								(size 1.27 1.27)
							)
						)
					)
					(number "Y12"
						(effects
							(font
								(size 1.27 1.27)
							)
						)
					)
				)
				(pin passive line
					(at 0 -15.24 0)
					(length 3.81)
					(hide yes)
					(name "GND"
						(effects
							(font
								(size 1.27 1.27)
							)
						)
					)
					(number "Y13"
						(effects
							(font
								(size 1.27 1.27)
							)
						)
					)
				)
				(pin passive line
					(at 0 -15.24 0)
					(length 3.81)
					(hide yes)
					(name "GND"
						(effects
							(font
								(size 1.27 1.27)
							)
						)
					)
					(number "Y16"
						(effects
							(font
								(size 1.27 1.27)
							)
						)
					)
				)
				(pin passive line
					(at 0 -15.24 0)
					(length 3.81)
					(hide yes)
					(name "GND"
						(effects
							(font
								(size 1.27 1.27)
							)
						)
					)
					(number "Y17"
						(effects
							(font
								(size 1.27 1.27)
							)
						)
					)
				)
				(pin passive line
					(at 0 -15.24 0)
					(length 3.81)
					(hide yes)
					(name "GND"
						(effects
							(font
								(size 1.27 1.27)
							)
						)
					)
					(number "Y20"
						(effects
							(font
								(size 1.27 1.27)
							)
						)
					)
				)
				(pin passive line
					(at 0 -15.24 0)
					(length 3.81)
					(hide yes)
					(name "GND"
						(effects
							(font
								(size 1.27 1.27)
							)
						)
					)
					(number "Y21"
						(effects
							(font
								(size 1.27 1.27)
							)
						)
					)
				)
				(pin passive line
					(at 0 -15.24 0)
					(length 3.81)
					(hide yes)
					(name "GND"
						(effects
							(font
								(size 1.27 1.27)
							)
						)
					)
					(number "Y24"
						(effects
							(font
								(size 1.27 1.27)
							)
						)
					)
				)
				(pin passive line
					(at 0 -15.24 0)
					(length 3.81)
					(hide yes)
					(name "GND"
						(effects
							(font
								(size 1.27 1.27)
							)
						)
					)
					(number "Y25"
						(effects
							(font
								(size 1.27 1.27)
							)
						)
					)
				)
				(pin passive line
					(at 0 -15.24 0)
					(length 3.81)
					(hide yes)
					(name "GND"
						(effects
							(font
								(size 1.27 1.27)
							)
						)
					)
					(number "Y28"
						(effects
							(font
								(size 1.27 1.27)
							)
						)
					)
				)
				(pin passive line
					(at 0 -15.24 0)
					(length 3.81)
					(hide yes)
					(name "GND"
						(effects
							(font
								(size 1.27 1.27)
							)
						)
					)
					(number "Y29"
						(effects
							(font
								(size 1.27 1.27)
							)
						)
					)
				)
				(pin passive line
					(at 0 -15.24 0)
					(length 3.81)
					(hide yes)
					(name "GND"
						(effects
							(font
								(size 1.27 1.27)
							)
						)
					)
					(number "Y32"
						(effects
							(font
								(size 1.27 1.27)
							)
						)
					)
				)
				(pin passive line
					(at 0 -15.24 0)
					(length 3.81)
					(hide yes)
					(name "GND"
						(effects
							(font
								(size 1.27 1.27)
							)
						)
					)
					(number "Y33"
						(effects
							(font
								(size 1.27 1.27)
							)
						)
					)
				)
				(pin passive line
					(at 0 -15.24 0)
					(length 3.81)
					(hide yes)
					(name "GND"
						(effects
							(font
								(size 1.27 1.27)
							)
						)
					)
					(number "Y36"
						(effects
							(font
								(size 1.27 1.27)
							)
						)
					)
				)
				(pin passive line
					(at 0 -15.24 0)
					(length 3.81)
					(hide yes)
					(name "GND"
						(effects
							(font
								(size 1.27 1.27)
							)
						)
					)
					(number "Y37"
						(effects
							(font
								(size 1.27 1.27)
							)
						)
					)
				)
				(pin passive line
					(at 0 -15.24 0)
					(length 3.81)
					(hide yes)
					(name "GND"
						(effects
							(font
								(size 1.27 1.27)
							)
						)
					)
					(number "Y40"
						(effects
							(font
								(size 1.27 1.27)
							)
						)
					)
				)
				(pin passive line
					(at 0 -15.24 0)
					(length 3.81)
					(hide yes)
					(name "GND"
						(effects
							(font
								(size 1.27 1.27)
							)
						)
					)
					(number "Z02"
						(effects
							(font
								(size 1.27 1.27)
							)
						)
					)
				)
				(pin passive line
					(at 0 -15.24 0)
					(length 3.81)
					(hide yes)
					(name "GND"
						(effects
							(font
								(size 1.27 1.27)
							)
						)
					)
					(number "Z03"
						(effects
							(font
								(size 1.27 1.27)
							)
						)
					)
				)
				(pin passive line
					(at 0 -15.24 0)
					(length 3.81)
					(hide yes)
					(name "GND"
						(effects
							(font
								(size 1.27 1.27)
							)
						)
					)
					(number "Z06"
						(effects
							(font
								(size 1.27 1.27)
							)
						)
					)
				)
				(pin passive line
					(at 0 -15.24 0)
					(length 3.81)
					(hide yes)
					(name "GND"
						(effects
							(font
								(size 1.27 1.27)
							)
						)
					)
					(number "Z07"
						(effects
							(font
								(size 1.27 1.27)
							)
						)
					)
				)
				(pin passive line
					(at 0 -15.24 0)
					(length 3.81)
					(hide yes)
					(name "GND"
						(effects
							(font
								(size 1.27 1.27)
							)
						)
					)
					(number "Z10"
						(effects
							(font
								(size 1.27 1.27)
							)
						)
					)
				)
				(pin passive line
					(at 0 -15.24 0)
					(length 3.81)
					(hide yes)
					(name "GND"
						(effects
							(font
								(size 1.27 1.27)
							)
						)
					)
					(number "Z11"
						(effects
							(font
								(size 1.27 1.27)
							)
						)
					)
				)
				(pin passive line
					(at 0 -15.24 0)
					(length 3.81)
					(hide yes)
					(name "GND"
						(effects
							(font
								(size 1.27 1.27)
							)
						)
					)
					(number "Z14"
						(effects
							(font
								(size 1.27 1.27)
							)
						)
					)
				)
				(pin passive line
					(at 0 -15.24 0)
					(length 3.81)
					(hide yes)
					(name "GND"
						(effects
							(font
								(size 1.27 1.27)
							)
						)
					)
					(number "Z15"
						(effects
							(font
								(size 1.27 1.27)
							)
						)
					)
				)
				(pin passive line
					(at 0 -15.24 0)
					(length 3.81)
					(hide yes)
					(name "GND"
						(effects
							(font
								(size 1.27 1.27)
							)
						)
					)
					(number "Z18"
						(effects
							(font
								(size 1.27 1.27)
							)
						)
					)
				)
				(pin passive line
					(at 0 -15.24 0)
					(length 3.81)
					(hide yes)
					(name "GND"
						(effects
							(font
								(size 1.27 1.27)
							)
						)
					)
					(number "Z19"
						(effects
							(font
								(size 1.27 1.27)
							)
						)
					)
				)
				(pin passive line
					(at 0 -15.24 0)
					(length 3.81)
					(hide yes)
					(name "GND"
						(effects
							(font
								(size 1.27 1.27)
							)
						)
					)
					(number "Z22"
						(effects
							(font
								(size 1.27 1.27)
							)
						)
					)
				)
				(pin passive line
					(at 0 -15.24 0)
					(length 3.81)
					(hide yes)
					(name "GND"
						(effects
							(font
								(size 1.27 1.27)
							)
						)
					)
					(number "Z23"
						(effects
							(font
								(size 1.27 1.27)
							)
						)
					)
				)
				(pin passive line
					(at 0 -15.24 0)
					(length 3.81)
					(hide yes)
					(name "GND"
						(effects
							(font
								(size 1.27 1.27)
							)
						)
					)
					(number "Z26"
						(effects
							(font
								(size 1.27 1.27)
							)
						)
					)
				)
				(pin passive line
					(at 0 -15.24 0)
					(length 3.81)
					(hide yes)
					(name "GND"
						(effects
							(font
								(size 1.27 1.27)
							)
						)
					)
					(number "Z27"
						(effects
							(font
								(size 1.27 1.27)
							)
						)
					)
				)
				(pin passive line
					(at 0 -15.24 0)
					(length 3.81)
					(hide yes)
					(name "GND"
						(effects
							(font
								(size 1.27 1.27)
							)
						)
					)
					(number "Z30"
						(effects
							(font
								(size 1.27 1.27)
							)
						)
					)
				)
				(pin passive line
					(at 0 -15.24 0)
					(length 3.81)
					(hide yes)
					(name "GND"
						(effects
							(font
								(size 1.27 1.27)
							)
						)
					)
					(number "Z31"
						(effects
							(font
								(size 1.27 1.27)
							)
						)
					)
				)
				(pin passive line
					(at 0 -15.24 0)
					(length 3.81)
					(hide yes)
					(name "GND"
						(effects
							(font
								(size 1.27 1.27)
							)
						)
					)
					(number "Z34"
						(effects
							(font
								(size 1.27 1.27)
							)
						)
					)
				)
				(pin passive line
					(at 0 -15.24 0)
					(length 3.81)
					(hide yes)
					(name "GND"
						(effects
							(font
								(size 1.27 1.27)
							)
						)
					)
					(number "Z35"
						(effects
							(font
								(size 1.27 1.27)
							)
						)
					)
				)
				(pin passive line
					(at 0 -15.24 0)
					(length 3.81)
					(hide yes)
					(name "GND"
						(effects
							(font
								(size 1.27 1.27)
							)
						)
					)
					(number "Z38"
						(effects
							(font
								(size 1.27 1.27)
							)
						)
					)
				)
				(pin passive line
					(at 0 -15.24 0)
					(length 3.81)
					(hide yes)
					(name "GND"
						(effects
							(font
								(size 1.27 1.27)
							)
						)
					)
					(number "Z39"
						(effects
							(font
								(size 1.27 1.27)
							)
						)
					)
				)
				(pin no_connect line
					(at 17.78 -17.78 90)
					(length 3.81)
					(hide yes)
					(name "RES0"
						(effects
							(font
								(size 1.27 1.27)
							)
						)
					)
					(number "B40"
						(effects
							(font
								(size 1.27 1.27)
							)
						)
					)
				)
				(pin no_connect line
					(at 20.32 -17.78 90)
					(length 3.81)
					(hide yes)
					(name "RES1"
						(effects
							(font
								(size 1.27 1.27)
							)
						)
					)
					(number "L01"
						(effects
							(font
								(size 1.27 1.27)
							)
						)
					)
				)
				(pin no_connect line
					(at 22.86 -17.78 90)
					(length 3.81)
					(hide yes)
					(name "RES2"
						(effects
							(font
								(size 1.27 1.27)
							)
						)
					)
					(number "L32"
						(effects
							(font
								(size 1.27 1.27)
							)
						)
					)
				)
				(pin no_connect line
					(at 25.4 -17.78 90)
					(length 3.81)
					(hide yes)
					(name "RES3"
						(effects
							(font
								(size 1.27 1.27)
							)
						)
					)
					(number "L33"
						(effects
							(font
								(size 1.27 1.27)
							)
						)
					)
				)
				(pin passive line
					(at 30.48 0 180)
					(length 3.81)
					(name "VREF_A_M2C"
						(effects
							(font
								(size 1.27 1.27)
							)
						)
					)
					(number "H01"
						(effects
							(font
								(size 1.27 1.27)
							)
						)
					)
				)
				(pin passive line
					(at 30.48 -2.54 180)
					(length 3.81)
					(name "VREF_B_M2C"
						(effects
							(font
								(size 1.27 1.27)
							)
						)
					)
					(number "K01"
						(effects
							(font
								(size 1.27 1.27)
							)
						)
					)
				)
				(pin passive line
					(at 30.48 -5.08 180)
					(length 3.81)
					(name "VIO_B_M2C"
						(effects
							(font
								(size 1.27 1.27)
							)
						)
					)
					(number "J39"
						(effects
							(font
								(size 1.27 1.27)
							)
						)
					)
				)
				(pin passive line
					(at 30.48 -5.08 180)
					(length 3.81)
					(hide yes)
					(name "VIO_B_M2C"
						(effects
							(font
								(size 1.27 1.27)
							)
						)
					)
					(number "K40"
						(effects
							(font
								(size 1.27 1.27)
							)
						)
					)
				)
				(pin passive line
					(at 30.48 -7.62 180)
					(length 3.81)
					(name "3P3VAUX"
						(effects
							(font
								(size 1.27 1.27)
							)
						)
					)
					(number "D32"
						(effects
							(font
								(size 1.27 1.27)
							)
						)
					)
				)
			)
			(symbol "ASP-184329-01_CUSTOM_mounting_holes_2_0"
				(rectangle
					(start 19.05 -3.81)
					(end 26.67 -16.51)
					(stroke
						(width 0.254)
						(type default)
					)
					(fill
						(type none)
					)
				)
				(rectangle
					(start 19.05 -19.05)
					(end 26.67 -24.13)
					(stroke
						(width 0.254)
						(type default)
					)
					(fill
						(type none)
					)
				)
				(text "CONTROL"
					(at 15.24 3.81 0)
					(effects
						(font
							(size 1.27 1.27)
						)
					)
				)
				(text "JTAG"
					(at 20.32 -10.16 900)
					(effects
						(font
							(size 1.27 1.27)
						)
					)
				)
				(text "I2C"
					(at 20.32 -21.59 900)
					(effects
						(font
							(size 1.27 1.27)
						)
					)
				)
			)
			(symbol "ASP-184329-01_CUSTOM_mounting_holes_2_1"
				(rectangle
					(start 3.81 6.35)
					(end 26.67 -25.4)
					(stroke
						(width 0.254)
						(type default)
					)
					(fill
						(type background)
					)
				)
				(pin passive line
					(at 0 0 0)
					(length 3.81)
					(name "HSPC_PRSNT_M2C_L"
						(effects
							(font
								(size 1.27 1.27)
							)
						)
					)
					(number "Z01"
						(effects
							(font
								(size 1.27 1.27)
							)
						)
					)
				)
				(pin passive line
					(at 0 -2.54 0)
					(length 3.81)
					(name "PRSNT_M2C_L"
						(effects
							(font
								(size 1.27 1.27)
							)
						)
					)
					(number "H02"
						(effects
							(font
								(size 1.27 1.27)
							)
						)
					)
				)
				(pin passive line
					(at 0 -5.08 0)
					(length 3.81)
					(name "PG_M2C"
						(effects
							(font
								(size 1.27 1.27)
							)
						)
					)
					(number "F01"
						(effects
							(font
								(size 1.27 1.27)
							)
						)
					)
				)
				(pin passive line
					(at 0 -7.62 0)
					(length 3.81)
					(name "PG_C2M"
						(effects
							(font
								(size 1.27 1.27)
							)
						)
					)
					(number "D01"
						(effects
							(font
								(size 1.27 1.27)
							)
						)
					)
				)
				(pin passive line
					(at 0 -20.32 0)
					(length 3.81)
					(name "GA0"
						(effects
							(font
								(size 1.27 1.27)
							)
						)
					)
					(number "C34"
						(effects
							(font
								(size 1.27 1.27)
							)
						)
					)
				)
				(pin passive line
					(at 0 -22.86 0)
					(length 3.81)
					(name "GA1"
						(effects
							(font
								(size 1.27 1.27)
							)
						)
					)
					(number "D35"
						(effects
							(font
								(size 1.27 1.27)
							)
						)
					)
				)
				(pin passive line
					(at 30.48 -5.08 180)
					(length 3.81)
					(name "TCK"
						(effects
							(font
								(size 1.27 1.27)
							)
						)
					)
					(number "D29"
						(effects
							(font
								(size 1.27 1.27)
							)
						)
					)
				)
				(pin passive line
					(at 30.48 -7.62 180)
					(length 3.81)
					(name "TDI"
						(effects
							(font
								(size 1.27 1.27)
							)
						)
					)
					(number "D30"
						(effects
							(font
								(size 1.27 1.27)
							)
						)
					)
				)
				(pin passive line
					(at 30.48 -10.16 180)
					(length 3.81)
					(name "TDO"
						(effects
							(font
								(size 1.27 1.27)
							)
						)
					)
					(number "D31"
						(effects
							(font
								(size 1.27 1.27)
							)
						)
					)
				)
				(pin passive line
					(at 30.48 -12.7 180)
					(length 3.81)
					(name "TMS"
						(effects
							(font
								(size 1.27 1.27)
							)
						)
					)
					(number "D33"
						(effects
							(font
								(size 1.27 1.27)
							)
						)
					)
				)
				(pin passive line
					(at 30.48 -15.24 180)
					(length 3.81)
					(name "TRST_L"
						(effects
							(font
								(size 1.27 1.27)
							)
						)
					)
					(number "D34"
						(effects
							(font
								(size 1.27 1.27)
							)
						)
					)
				)
				(pin passive line
					(at 30.48 -20.32 180)
					(length 3.81)
					(name "SDA"
						(effects
							(font
								(size 1.27 1.27)
							)
						)
					)
					(number "C31"
						(effects
							(font
								(size 1.27 1.27)
							)
						)
					)
				)
				(pin passive line
					(at 30.48 -22.86 180)
					(length 3.81)
					(name "SCL"
						(effects
							(font
								(size 1.27 1.27)
							)
						)
					)
					(number "C30"
						(effects
							(font
								(size 1.27 1.27)
							)
						)
					)
				)
			)
			(symbol "ASP-184329-01_CUSTOM_mounting_holes_3_0"
				(text "USER DEFINED"
					(at 16.51 6.35 0)
					(effects
						(font
							(size 1.27 1.27)
						)
					)
				)
				(text "BANK A (LPC)"
					(at 16.51 3.81 0)
					(effects
						(font
							(size 1.27 1.27)
						)
					)
				)
			)
			(symbol "ASP-184329-01_CUSTOM_mounting_holes_3_1"
				(rectangle
					(start 3.81 8.89)
					(end 29.21 -86.36)
					(stroke
						(width 0.254)
						(type default)
					)
					(fill
						(type background)
					)
				)
				(pin passive line
					(at 0 0 0)
					(length 3.81)
					(name "LA00_P_CC"
						(effects
							(font
								(size 1.27 1.27)
							)
						)
					)
					(number "G06"
						(effects
							(font
								(size 1.27 1.27)
							)
						)
					)
				)
				(pin passive line
					(at 0 -2.54 0)
					(length 3.81)
					(name "LA00_N_CC"
						(effects
							(font
								(size 1.27 1.27)
							)
						)
					)
					(number "G07"
						(effects
							(font
								(size 1.27 1.27)
							)
						)
					)
				)
				(pin passive line
					(at 0 -5.08 0)
					(length 3.81)
					(name "LA01_P_CC"
						(effects
							(font
								(size 1.27 1.27)
							)
						)
					)
					(number "D08"
						(effects
							(font
								(size 1.27 1.27)
							)
						)
					)
				)
				(pin passive line
					(at 0 -7.62 0)
					(length 3.81)
					(name "LA01_N_CC"
						(effects
							(font
								(size 1.27 1.27)
							)
						)
					)
					(number "D09"
						(effects
							(font
								(size 1.27 1.27)
							)
						)
					)
				)
				(pin passive line
					(at 0 -10.16 0)
					(length 3.81)
					(name "LA02_P"
						(effects
							(font
								(size 1.27 1.27)
							)
						)
					)
					(number "H07"
						(effects
							(font
								(size 1.27 1.27)
							)
						)
					)
				)
				(pin passive line
					(at 0 -12.7 0)
					(length 3.81)
					(name "LA02_N"
						(effects
							(font
								(size 1.27 1.27)
							)
						)
					)
					(number "H08"
						(effects
							(font
								(size 1.27 1.27)
							)
						)
					)
				)
				(pin passive line
					(at 0 -15.24 0)
					(length 3.81)
					(name "LA03_P"
						(effects
							(font
								(size 1.27 1.27)
							)
						)
					)
					(number "G09"
						(effects
							(font
								(size 1.27 1.27)
							)
						)
					)
				)
				(pin passive line
					(at 0 -17.78 0)
					(length 3.81)
					(name "LA03_N"
						(effects
							(font
								(size 1.27 1.27)
							)
						)
					)
					(number "G10"
						(effects
							(font
								(size 1.27 1.27)
							)
						)
					)
				)
				(pin passive line
					(at 0 -20.32 0)
					(length 3.81)
					(name "LA04_P"
						(effects
							(font
								(size 1.27 1.27)
							)
						)
					)
					(number "H10"
						(effects
							(font
								(size 1.27 1.27)
							)
						)
					)
				)
				(pin passive line
					(at 0 -22.86 0)
					(length 3.81)
					(name "LA04_N"
						(effects
							(font
								(size 1.27 1.27)
							)
						)
					)
					(number "H11"
						(effects
							(font
								(size 1.27 1.27)
							)
						)
					)
				)
				(pin passive line
					(at 0 -25.4 0)
					(length 3.81)
					(name "LA05_P"
						(effects
							(font
								(size 1.27 1.27)
							)
						)
					)
					(number "D11"
						(effects
							(font
								(size 1.27 1.27)
							)
						)
					)
				)
				(pin passive line
					(at 0 -27.94 0)
					(length 3.81)
					(name "LA05_N"
						(effects
							(font
								(size 1.27 1.27)
							)
						)
					)
					(number "D12"
						(effects
							(font
								(size 1.27 1.27)
							)
						)
					)
				)
				(pin passive line
					(at 0 -30.48 0)
					(length 3.81)
					(name "LA06_P"
						(effects
							(font
								(size 1.27 1.27)
							)
						)
					)
					(number "C10"
						(effects
							(font
								(size 1.27 1.27)
							)
						)
					)
				)
				(pin passive line
					(at 0 -33.02 0)
					(length 3.81)
					(name "LA06_N"
						(effects
							(font
								(size 1.27 1.27)
							)
						)
					)
					(number "C11"
						(effects
							(font
								(size 1.27 1.27)
							)
						)
					)
				)
				(pin passive line
					(at 0 -35.56 0)
					(length 3.81)
					(name "LA07_P"
						(effects
							(font
								(size 1.27 1.27)
							)
						)
					)
					(number "H13"
						(effects
							(font
								(size 1.27 1.27)
							)
						)
					)
				)
				(pin passive line
					(at 0 -38.1 0)
					(length 3.81)
					(name "LA07_N"
						(effects
							(font
								(size 1.27 1.27)
							)
						)
					)
					(number "H14"
						(effects
							(font
								(size 1.27 1.27)
							)
						)
					)
				)
				(pin passive line
					(at 0 -40.64 0)
					(length 3.81)
					(name "LA08_P"
						(effects
							(font
								(size 1.27 1.27)
							)
						)
					)
					(number "G12"
						(effects
							(font
								(size 1.27 1.27)
							)
						)
					)
				)
				(pin passive line
					(at 0 -43.18 0)
					(length 3.81)
					(name "LA08_N"
						(effects
							(font
								(size 1.27 1.27)
							)
						)
					)
					(number "G13"
						(effects
							(font
								(size 1.27 1.27)
							)
						)
					)
				)
				(pin passive line
					(at 0 -45.72 0)
					(length 3.81)
					(name "LA09_P"
						(effects
							(font
								(size 1.27 1.27)
							)
						)
					)
					(number "D14"
						(effects
							(font
								(size 1.27 1.27)
							)
						)
					)
				)
				(pin passive line
					(at 0 -48.26 0)
					(length 3.81)
					(name "LA09_N"
						(effects
							(font
								(size 1.27 1.27)
							)
						)
					)
					(number "D15"
						(effects
							(font
								(size 1.27 1.27)
							)
						)
					)
				)
				(pin passive line
					(at 0 -50.8 0)
					(length 3.81)
					(name "LA10_P"
						(effects
							(font
								(size 1.27 1.27)
							)
						)
					)
					(number "C14"
						(effects
							(font
								(size 1.27 1.27)
							)
						)
					)
				)
				(pin passive line
					(at 0 -53.34 0)
					(length 3.81)
					(name "LA10_N"
						(effects
							(font
								(size 1.27 1.27)
							)
						)
					)
					(number "C15"
						(effects
							(font
								(size 1.27 1.27)
							)
						)
					)
				)
				(pin passive line
					(at 0 -55.88 0)
					(length 3.81)
					(name "LA11_P"
						(effects
							(font
								(size 1.27 1.27)
							)
						)
					)
					(number "H16"
						(effects
							(font
								(size 1.27 1.27)
							)
						)
					)
				)
				(pin passive line
					(at 0 -58.42 0)
					(length 3.81)
					(name "LA11_N"
						(effects
							(font
								(size 1.27 1.27)
							)
						)
					)
					(number "H17"
						(effects
							(font
								(size 1.27 1.27)
							)
						)
					)
				)
				(pin passive line
					(at 0 -60.96 0)
					(length 3.81)
					(name "LA12_P"
						(effects
							(font
								(size 1.27 1.27)
							)
						)
					)
					(number "G15"
						(effects
							(font
								(size 1.27 1.27)
							)
						)
					)
				)
				(pin passive line
					(at 0 -63.5 0)
					(length 3.81)
					(name "LA12_N"
						(effects
							(font
								(size 1.27 1.27)
							)
						)
					)
					(number "G16"
						(effects
							(font
								(size 1.27 1.27)
							)
						)
					)
				)
				(pin passive line
					(at 0 -66.04 0)
					(length 3.81)
					(name "LA13_P"
						(effects
							(font
								(size 1.27 1.27)
							)
						)
					)
					(number "D17"
						(effects
							(font
								(size 1.27 1.27)
							)
						)
					)
				)
				(pin passive line
					(at 0 -68.58 0)
					(length 3.81)
					(name "LA13_N"
						(effects
							(font
								(size 1.27 1.27)
							)
						)
					)
					(number "D18"
						(effects
							(font
								(size 1.27 1.27)
							)
						)
					)
				)
				(pin passive line
					(at 0 -71.12 0)
					(length 3.81)
					(name "LA14_P"
						(effects
							(font
								(size 1.27 1.27)
							)
						)
					)
					(number "C18"
						(effects
							(font
								(size 1.27 1.27)
							)
						)
					)
				)
				(pin passive line
					(at 0 -73.66 0)
					(length 3.81)
					(name "LA14_N"
						(effects
							(font
								(size 1.27 1.27)
							)
						)
					)
					(number "C19"
						(effects
							(font
								(size 1.27 1.27)
							)
						)
					)
				)
				(pin passive line
					(at 0 -76.2 0)
					(length 3.81)
					(name "LA15_P"
						(effects
							(font
								(size 1.27 1.27)
							)
						)
					)
					(number "H19"
						(effects
							(font
								(size 1.27 1.27)
							)
						)
					)
				)
				(pin passive line
					(at 0 -78.74 0)
					(length 3.81)
					(name "LA15_N"
						(effects
							(font
								(size 1.27 1.27)
							)
						)
					)
					(number "H20"
						(effects
							(font
								(size 1.27 1.27)
							)
						)
					)
				)
				(pin passive line
					(at 0 -81.28 0)
					(length 3.81)
					(name "LA16_P"
						(effects
							(font
								(size 1.27 1.27)
							)
						)
					)
					(number "G18"
						(effects
							(font
								(size 1.27 1.27)
							)
						)
					)
				)
				(pin passive line
					(at 0 -83.82 0)
					(length 3.81)
					(name "LA16_N"
						(effects
							(font
								(size 1.27 1.27)
							)
						)
					)
					(number "G19"
						(effects
							(font
								(size 1.27 1.27)
							)
						)
					)
				)
				(pin passive line
					(at 33.02 0 180)
					(length 3.81)
					(name "LA17_P_CC"
						(effects
							(font
								(size 1.27 1.27)
							)
						)
					)
					(number "D20"
						(effects
							(font
								(size 1.27 1.27)
							)
						)
					)
				)
				(pin passive line
					(at 33.02 -2.54 180)
					(length 3.81)
					(name "LA17_N_CC"
						(effects
							(font
								(size 1.27 1.27)
							)
						)
					)
					(number "D21"
						(effects
							(font
								(size 1.27 1.27)
							)
						)
					)
				)
				(pin passive line
					(at 33.02 -5.08 180)
					(length 3.81)
					(name "LA18_P_CC"
						(effects
							(font
								(size 1.27 1.27)
							)
						)
					)
					(number "C22"
						(effects
							(font
								(size 1.27 1.27)
							)
						)
					)
				)
				(pin passive line
					(at 33.02 -7.62 180)
					(length 3.81)
					(name "LA18_N_CC"
						(effects
							(font
								(size 1.27 1.27)
							)
						)
					)
					(number "C23"
						(effects
							(font
								(size 1.27 1.27)
							)
						)
					)
				)
				(pin passive line
					(at 33.02 -10.16 180)
					(length 3.81)
					(name "LA19_P"
						(effects
							(font
								(size 1.27 1.27)
							)
						)
					)
					(number "H22"
						(effects
							(font
								(size 1.27 1.27)
							)
						)
					)
				)
				(pin passive line
					(at 33.02 -12.7 180)
					(length 3.81)
					(name "LA19_N"
						(effects
							(font
								(size 1.27 1.27)
							)
						)
					)
					(number "H23"
						(effects
							(font
								(size 1.27 1.27)
							)
						)
					)
				)
				(pin passive line
					(at 33.02 -15.24 180)
					(length 3.81)
					(name "LA20_P"
						(effects
							(font
								(size 1.27 1.27)
							)
						)
					)
					(number "G21"
						(effects
							(font
								(size 1.27 1.27)
							)
						)
					)
				)
				(pin passive line
					(at 33.02 -17.78 180)
					(length 3.81)
					(name "LA20_N"
						(effects
							(font
								(size 1.27 1.27)
							)
						)
					)
					(number "G22"
						(effects
							(font
								(size 1.27 1.27)
							)
						)
					)
				)
				(pin passive line
					(at 33.02 -20.32 180)
					(length 3.81)
					(name "LA21_P"
						(effects
							(font
								(size 1.27 1.27)
							)
						)
					)
					(number "H25"
						(effects
							(font
								(size 1.27 1.27)
							)
						)
					)
				)
				(pin passive line
					(at 33.02 -22.86 180)
					(length 3.81)
					(name "LA21_N"
						(effects
							(font
								(size 1.27 1.27)
							)
						)
					)
					(number "H26"
						(effects
							(font
								(size 1.27 1.27)
							)
						)
					)
				)
				(pin passive line
					(at 33.02 -25.4 180)
					(length 3.81)
					(name "LA22_P"
						(effects
							(font
								(size 1.27 1.27)
							)
						)
					)
					(number "G24"
						(effects
							(font
								(size 1.27 1.27)
							)
						)
					)
				)
				(pin passive line
					(at 33.02 -27.94 180)
					(length 3.81)
					(name "LA22_N"
						(effects
							(font
								(size 1.27 1.27)
							)
						)
					)
					(number "G25"
						(effects
							(font
								(size 1.27 1.27)
							)
						)
					)
				)
				(pin passive line
					(at 33.02 -30.48 180)
					(length 3.81)
					(name "LA23_P"
						(effects
							(font
								(size 1.27 1.27)
							)
						)
					)
					(number "D23"
						(effects
							(font
								(size 1.27 1.27)
							)
						)
					)
				)
				(pin passive line
					(at 33.02 -33.02 180)
					(length 3.81)
					(name "LA23_N"
						(effects
							(font
								(size 1.27 1.27)
							)
						)
					)
					(number "D24"
						(effects
							(font
								(size 1.27 1.27)
							)
						)
					)
				)
				(pin passive line
					(at 33.02 -35.56 180)
					(length 3.81)
					(name "LA24_P"
						(effects
							(font
								(size 1.27 1.27)
							)
						)
					)
					(number "H28"
						(effects
							(font
								(size 1.27 1.27)
							)
						)
					)
				)
				(pin passive line
					(at 33.02 -38.1 180)
					(length 3.81)
					(name "LA24_N"
						(effects
							(font
								(size 1.27 1.27)
							)
						)
					)
					(number "H29"
						(effects
							(font
								(size 1.27 1.27)
							)
						)
					)
				)
				(pin passive line
					(at 33.02 -40.64 180)
					(length 3.81)
					(name "LA25_P"
						(effects
							(font
								(size 1.27 1.27)
							)
						)
					)
					(number "G27"
						(effects
							(font
								(size 1.27 1.27)
							)
						)
					)
				)
				(pin passive line
					(at 33.02 -43.18 180)
					(length 3.81)
					(name "LA25_N"
						(effects
							(font
								(size 1.27 1.27)
							)
						)
					)
					(number "G28"
						(effects
							(font
								(size 1.27 1.27)
							)
						)
					)
				)
				(pin passive line
					(at 33.02 -45.72 180)
					(length 3.81)
					(name "LA26_P"
						(effects
							(font
								(size 1.27 1.27)
							)
						)
					)
					(number "D26"
						(effects
							(font
								(size 1.27 1.27)
							)
						)
					)
				)
				(pin passive line
					(at 33.02 -48.26 180)
					(length 3.81)
					(name "LA26_N"
						(effects
							(font
								(size 1.27 1.27)
							)
						)
					)
					(number "D27"
						(effects
							(font
								(size 1.27 1.27)
							)
						)
					)
				)
				(pin passive line
					(at 33.02 -50.8 180)
					(length 3.81)
					(name "LA27_P"
						(effects
							(font
								(size 1.27 1.27)
							)
						)
					)
					(number "C26"
						(effects
							(font
								(size 1.27 1.27)
							)
						)
					)
				)
				(pin passive line
					(at 33.02 -53.34 180)
					(length 3.81)
					(name "LA27_N"
						(effects
							(font
								(size 1.27 1.27)
							)
						)
					)
					(number "C27"
						(effects
							(font
								(size 1.27 1.27)
							)
						)
					)
				)
				(pin passive line
					(at 33.02 -55.88 180)
					(length 3.81)
					(name "LA28_P"
						(effects
							(font
								(size 1.27 1.27)
							)
						)
					)
					(number "H31"
						(effects
							(font
								(size 1.27 1.27)
							)
						)
					)
				)
				(pin passive line
					(at 33.02 -58.42 180)
					(length 3.81)
					(name "LA28_N"
						(effects
							(font
								(size 1.27 1.27)
							)
						)
					)
					(number "H32"
						(effects
							(font
								(size 1.27 1.27)
							)
						)
					)
				)
				(pin passive line
					(at 33.02 -60.96 180)
					(length 3.81)
					(name "LA29_P"
						(effects
							(font
								(size 1.27 1.27)
							)
						)
					)
					(number "G30"
						(effects
							(font
								(size 1.27 1.27)
							)
						)
					)
				)
				(pin passive line
					(at 33.02 -63.5 180)
					(length 3.81)
					(name "LA29_N"
						(effects
							(font
								(size 1.27 1.27)
							)
						)
					)
					(number "G31"
						(effects
							(font
								(size 1.27 1.27)
							)
						)
					)
				)
				(pin passive line
					(at 33.02 -66.04 180)
					(length 3.81)
					(name "LA30_P"
						(effects
							(font
								(size 1.27 1.27)
							)
						)
					)
					(number "H34"
						(effects
							(font
								(size 1.27 1.27)
							)
						)
					)
				)
				(pin passive line
					(at 33.02 -68.58 180)
					(length 3.81)
					(name "LA30_N"
						(effects
							(font
								(size 1.27 1.27)
							)
						)
					)
					(number "H35"
						(effects
							(font
								(size 1.27 1.27)
							)
						)
					)
				)
				(pin passive line
					(at 33.02 -71.12 180)
					(length 3.81)
					(name "LA31_P"
						(effects
							(font
								(size 1.27 1.27)
							)
						)
					)
					(number "G33"
						(effects
							(font
								(size 1.27 1.27)
							)
						)
					)
				)
				(pin passive line
					(at 33.02 -73.66 180)
					(length 3.81)
					(name "LA31_N"
						(effects
							(font
								(size 1.27 1.27)
							)
						)
					)
					(number "G34"
						(effects
							(font
								(size 1.27 1.27)
							)
						)
					)
				)
				(pin passive line
					(at 33.02 -76.2 180)
					(length 3.81)
					(name "LA32_P"
						(effects
							(font
								(size 1.27 1.27)
							)
						)
					)
					(number "H37"
						(effects
							(font
								(size 1.27 1.27)
							)
						)
					)
				)
				(pin passive line
					(at 33.02 -78.74 180)
					(length 3.81)
					(name "LA32_N"
						(effects
							(font
								(size 1.27 1.27)
							)
						)
					)
					(number "H38"
						(effects
							(font
								(size 1.27 1.27)
							)
						)
					)
				)
				(pin passive line
					(at 33.02 -81.28 180)
					(length 3.81)
					(name "LA33_P"
						(effects
							(font
								(size 1.27 1.27)
							)
						)
					)
					(number "G36"
						(effects
							(font
								(size 1.27 1.27)
							)
						)
					)
				)
				(pin passive line
					(at 33.02 -83.82 180)
					(length 3.81)
					(name "LA33_N"
						(effects
							(font
								(size 1.27 1.27)
							)
						)
					)
					(number "G37"
						(effects
							(font
								(size 1.27 1.27)
							)
						)
					)
				)
			)
			(symbol "ASP-184329-01_CUSTOM_mounting_holes_4_0"
				(text "USER DEFINED"
					(at 16.51 6.35 0)
					(effects
						(font
							(size 1.27 1.27)
						)
					)
				)
				(text "BANK A (HPC)"
					(at 16.51 3.81 0)
					(effects
						(font
							(size 1.27 1.27)
						)
					)
				)
			)
			(symbol "ASP-184329-01_CUSTOM_mounting_holes_4_1"
				(rectangle
					(start 3.81 8.89)
					(end 29.21 -60.96)
					(stroke
						(width 0.254)
						(type default)
					)
					(fill
						(type background)
					)
				)
				(pin passive line
					(at 0 0 0)
					(length 3.81)
					(name "HA00_P_CC"
						(effects
							(font
								(size 1.27 1.27)
							)
						)
					)
					(number "F04"
						(effects
							(font
								(size 1.27 1.27)
							)
						)
					)
				)
				(pin passive line
					(at 0 -2.54 0)
					(length 3.81)
					(name "HA00_N_CC"
						(effects
							(font
								(size 1.27 1.27)
							)
						)
					)
					(number "F05"
						(effects
							(font
								(size 1.27 1.27)
							)
						)
					)
				)
				(pin passive line
					(at 0 -5.08 0)
					(length 3.81)
					(name "HA01_P_CC"
						(effects
							(font
								(size 1.27 1.27)
							)
						)
					)
					(number "E02"
						(effects
							(font
								(size 1.27 1.27)
							)
						)
					)
				)
				(pin passive line
					(at 0 -7.62 0)
					(length 3.81)
					(name "HA01_N_CC"
						(effects
							(font
								(size 1.27 1.27)
							)
						)
					)
					(number "E03"
						(effects
							(font
								(size 1.27 1.27)
							)
						)
					)
				)
				(pin passive line
					(at 0 -10.16 0)
					(length 3.81)
					(name "HA02_P"
						(effects
							(font
								(size 1.27 1.27)
							)
						)
					)
					(number "K07"
						(effects
							(font
								(size 1.27 1.27)
							)
						)
					)
				)
				(pin passive line
					(at 0 -12.7 0)
					(length 3.81)
					(name "HA02_N"
						(effects
							(font
								(size 1.27 1.27)
							)
						)
					)
					(number "K08"
						(effects
							(font
								(size 1.27 1.27)
							)
						)
					)
				)
				(pin passive line
					(at 0 -15.24 0)
					(length 3.81)
					(name "HA03_P"
						(effects
							(font
								(size 1.27 1.27)
							)
						)
					)
					(number "J06"
						(effects
							(font
								(size 1.27 1.27)
							)
						)
					)
				)
				(pin passive line
					(at 0 -17.78 0)
					(length 3.81)
					(name "HA03_N"
						(effects
							(font
								(size 1.27 1.27)
							)
						)
					)
					(number "J07"
						(effects
							(font
								(size 1.27 1.27)
							)
						)
					)
				)
				(pin passive line
					(at 0 -20.32 0)
					(length 3.81)
					(name "HA04_P"
						(effects
							(font
								(size 1.27 1.27)
							)
						)
					)
					(number "F07"
						(effects
							(font
								(size 1.27 1.27)
							)
						)
					)
				)
				(pin passive line
					(at 0 -22.86 0)
					(length 3.81)
					(name "HA04_N"
						(effects
							(font
								(size 1.27 1.27)
							)
						)
					)
					(number "F08"
						(effects
							(font
								(size 1.27 1.27)
							)
						)
					)
				)
				(pin passive line
					(at 0 -25.4 0)
					(length 3.81)
					(name "HA05_P"
						(effects
							(font
								(size 1.27 1.27)
							)
						)
					)
					(number "E06"
						(effects
							(font
								(size 1.27 1.27)
							)
						)
					)
				)
				(pin passive line
					(at 0 -27.94 0)
					(length 3.81)
					(name "HA05_N"
						(effects
							(font
								(size 1.27 1.27)
							)
						)
					)
					(number "E07"
						(effects
							(font
								(size 1.27 1.27)
							)
						)
					)
				)
				(pin passive line
					(at 0 -30.48 0)
					(length 3.81)
					(name "HA06_P"
						(effects
							(font
								(size 1.27 1.27)
							)
						)
					)
					(number "K10"
						(effects
							(font
								(size 1.27 1.27)
							)
						)
					)
				)
				(pin passive line
					(at 0 -33.02 0)
					(length 3.81)
					(name "HA06_N"
						(effects
							(font
								(size 1.27 1.27)
							)
						)
					)
					(number "K11"
						(effects
							(font
								(size 1.27 1.27)
							)
						)
					)
				)
				(pin passive line
					(at 0 -35.56 0)
					(length 3.81)
					(name "HA07_P"
						(effects
							(font
								(size 1.27 1.27)
							)
						)
					)
					(number "J09"
						(effects
							(font
								(size 1.27 1.27)
							)
						)
					)
				)
				(pin passive line
					(at 0 -38.1 0)
					(length 3.81)
					(name "HA07_N"
						(effects
							(font
								(size 1.27 1.27)
							)
						)
					)
					(number "J10"
						(effects
							(font
								(size 1.27 1.27)
							)
						)
					)
				)
				(pin passive line
					(at 0 -40.64 0)
					(length 3.81)
					(name "HA08_P"
						(effects
							(font
								(size 1.27 1.27)
							)
						)
					)
					(number "F10"
						(effects
							(font
								(size 1.27 1.27)
							)
						)
					)
				)
				(pin passive line
					(at 0 -43.18 0)
					(length 3.81)
					(name "HA08_N"
						(effects
							(font
								(size 1.27 1.27)
							)
						)
					)
					(number "F11"
						(effects
							(font
								(size 1.27 1.27)
							)
						)
					)
				)
				(pin passive line
					(at 0 -45.72 0)
					(length 3.81)
					(name "HA09_P"
						(effects
							(font
								(size 1.27 1.27)
							)
						)
					)
					(number "E09"
						(effects
							(font
								(size 1.27 1.27)
							)
						)
					)
				)
				(pin passive line
					(at 0 -48.26 0)
					(length 3.81)
					(name "HA09_N"
						(effects
							(font
								(size 1.27 1.27)
							)
						)
					)
					(number "E10"
						(effects
							(font
								(size 1.27 1.27)
							)
						)
					)
				)
				(pin passive line
					(at 0 -50.8 0)
					(length 3.81)
					(name "HA10_P"
						(effects
							(font
								(size 1.27 1.27)
							)
						)
					)
					(number "K13"
						(effects
							(font
								(size 1.27 1.27)
							)
						)
					)
				)
				(pin passive line
					(at 0 -53.34 0)
					(length 3.81)
					(name "HA10_N"
						(effects
							(font
								(size 1.27 1.27)
							)
						)
					)
					(number "K14"
						(effects
							(font
								(size 1.27 1.27)
							)
						)
					)
				)
				(pin passive line
					(at 0 -55.88 0)
					(length 3.81)
					(name "HA11_P"
						(effects
							(font
								(size 1.27 1.27)
							)
						)
					)
					(number "J12"
						(effects
							(font
								(size 1.27 1.27)
							)
						)
					)
				)
				(pin passive line
					(at 0 -58.42 0)
					(length 3.81)
					(name "HA11_N"
						(effects
							(font
								(size 1.27 1.27)
							)
						)
					)
					(number "J13"
						(effects
							(font
								(size 1.27 1.27)
							)
						)
					)
				)
				(pin passive line
					(at 33.02 0 180)
					(length 3.81)
					(name "HA12_P"
						(effects
							(font
								(size 1.27 1.27)
							)
						)
					)
					(number "F13"
						(effects
							(font
								(size 1.27 1.27)
							)
						)
					)
				)
				(pin passive line
					(at 33.02 -2.54 180)
					(length 3.81)
					(name "HA12_N"
						(effects
							(font
								(size 1.27 1.27)
							)
						)
					)
					(number "F14"
						(effects
							(font
								(size 1.27 1.27)
							)
						)
					)
				)
				(pin passive line
					(at 33.02 -5.08 180)
					(length 3.81)
					(name "HA13_P"
						(effects
							(font
								(size 1.27 1.27)
							)
						)
					)
					(number "E12"
						(effects
							(font
								(size 1.27 1.27)
							)
						)
					)
				)
				(pin passive line
					(at 33.02 -7.62 180)
					(length 3.81)
					(name "HA13_N"
						(effects
							(font
								(size 1.27 1.27)
							)
						)
					)
					(number "E13"
						(effects
							(font
								(size 1.27 1.27)
							)
						)
					)
				)
				(pin passive line
					(at 33.02 -10.16 180)
					(length 3.81)
					(name "HA14_P"
						(effects
							(font
								(size 1.27 1.27)
							)
						)
					)
					(number "J15"
						(effects
							(font
								(size 1.27 1.27)
							)
						)
					)
				)
				(pin passive line
					(at 33.02 -12.7 180)
					(length 3.81)
					(name "HA14_N"
						(effects
							(font
								(size 1.27 1.27)
							)
						)
					)
					(number "J16"
						(effects
							(font
								(size 1.27 1.27)
							)
						)
					)
				)
				(pin passive line
					(at 33.02 -15.24 180)
					(length 3.81)
					(name "HA15_P"
						(effects
							(font
								(size 1.27 1.27)
							)
						)
					)
					(number "F16"
						(effects
							(font
								(size 1.27 1.27)
							)
						)
					)
				)
				(pin passive line
					(at 33.02 -17.78 180)
					(length 3.81)
					(name "HA15_N"
						(effects
							(font
								(size 1.27 1.27)
							)
						)
					)
					(number "F17"
						(effects
							(font
								(size 1.27 1.27)
							)
						)
					)
				)
				(pin passive line
					(at 33.02 -20.32 180)
					(length 3.81)
					(name "HA16_P"
						(effects
							(font
								(size 1.27 1.27)
							)
						)
					)
					(number "E15"
						(effects
							(font
								(size 1.27 1.27)
							)
						)
					)
				)
				(pin passive line
					(at 33.02 -22.86 180)
					(length 3.81)
					(name "HA16_N"
						(effects
							(font
								(size 1.27 1.27)
							)
						)
					)
					(number "E16"
						(effects
							(font
								(size 1.27 1.27)
							)
						)
					)
				)
				(pin passive line
					(at 33.02 -25.4 180)
					(length 3.81)
					(name "HA17_P_CC"
						(effects
							(font
								(size 1.27 1.27)
							)
						)
					)
					(number "K16"
						(effects
							(font
								(size 1.27 1.27)
							)
						)
					)
				)
				(pin passive line
					(at 33.02 -27.94 180)
					(length 3.81)
					(name "HA17_N_CC"
						(effects
							(font
								(size 1.27 1.27)
							)
						)
					)
					(number "K17"
						(effects
							(font
								(size 1.27 1.27)
							)
						)
					)
				)
				(pin passive line
					(at 33.02 -30.48 180)
					(length 3.81)
					(name "HA18_P"
						(effects
							(font
								(size 1.27 1.27)
							)
						)
					)
					(number "J18"
						(effects
							(font
								(size 1.27 1.27)
							)
						)
					)
				)
				(pin passive line
					(at 33.02 -33.02 180)
					(length 3.81)
					(name "HA18_N"
						(effects
							(font
								(size 1.27 1.27)
							)
						)
					)
					(number "J19"
						(effects
							(font
								(size 1.27 1.27)
							)
						)
					)
				)
				(pin passive line
					(at 33.02 -35.56 180)
					(length 3.81)
					(name "HA19_P"
						(effects
							(font
								(size 1.27 1.27)
							)
						)
					)
					(number "F19"
						(effects
							(font
								(size 1.27 1.27)
							)
						)
					)
				)
				(pin passive line
					(at 33.02 -38.1 180)
					(length 3.81)
					(name "HA19_N"
						(effects
							(font
								(size 1.27 1.27)
							)
						)
					)
					(number "F20"
						(effects
							(font
								(size 1.27 1.27)
							)
						)
					)
				)
				(pin passive line
					(at 33.02 -40.64 180)
					(length 3.81)
					(name "HA20_P"
						(effects
							(font
								(size 1.27 1.27)
							)
						)
					)
					(number "E18"
						(effects
							(font
								(size 1.27 1.27)
							)
						)
					)
				)
				(pin passive line
					(at 33.02 -43.18 180)
					(length 3.81)
					(name "HA20_N"
						(effects
							(font
								(size 1.27 1.27)
							)
						)
					)
					(number "E19"
						(effects
							(font
								(size 1.27 1.27)
							)
						)
					)
				)
				(pin passive line
					(at 33.02 -45.72 180)
					(length 3.81)
					(name "HA21_P"
						(effects
							(font
								(size 1.27 1.27)
							)
						)
					)
					(number "K19"
						(effects
							(font
								(size 1.27 1.27)
							)
						)
					)
				)
				(pin passive line
					(at 33.02 -48.26 180)
					(length 3.81)
					(name "HA21_N"
						(effects
							(font
								(size 1.27 1.27)
							)
						)
					)
					(number "K20"
						(effects
							(font
								(size 1.27 1.27)
							)
						)
					)
				)
				(pin passive line
					(at 33.02 -50.8 180)
					(length 3.81)
					(name "HA22_P"
						(effects
							(font
								(size 1.27 1.27)
							)
						)
					)
					(number "J21"
						(effects
							(font
								(size 1.27 1.27)
							)
						)
					)
				)
				(pin passive line
					(at 33.02 -53.34 180)
					(length 3.81)
					(name "HA22_N"
						(effects
							(font
								(size 1.27 1.27)
							)
						)
					)
					(number "J22"
						(effects
							(font
								(size 1.27 1.27)
							)
						)
					)
				)
				(pin passive line
					(at 33.02 -55.88 180)
					(length 3.81)
					(name "HA23_P"
						(effects
							(font
								(size 1.27 1.27)
							)
						)
					)
					(number "K22"
						(effects
							(font
								(size 1.27 1.27)
							)
						)
					)
				)
				(pin passive line
					(at 33.02 -58.42 180)
					(length 3.81)
					(name "HA23_N"
						(effects
							(font
								(size 1.27 1.27)
							)
						)
					)
					(number "K23"
						(effects
							(font
								(size 1.27 1.27)
							)
						)
					)
				)
			)
			(symbol "ASP-184329-01_CUSTOM_mounting_holes_5_0"
				(text "USER DEFINED"
					(at 16.51 6.35 0)
					(effects
						(font
							(size 1.27 1.27)
						)
					)
				)
				(text "BANK B (HPC)"
					(at 16.51 3.81 0)
					(effects
						(font
							(size 1.27 1.27)
						)
					)
				)
			)
			(symbol "ASP-184329-01_CUSTOM_mounting_holes_5_1"
				(rectangle
					(start 3.81 8.89)
					(end 29.21 -55.88)
					(stroke
						(width 0.254)
						(type default)
					)
					(fill
						(type background)
					)
				)
				(pin passive line
					(at 0 0 0)
					(length 3.81)
					(name "HB00_P_CC"
						(effects
							(font
								(size 1.27 1.27)
							)
						)
					)
					(number "K25"
						(effects
							(font
								(size 1.27 1.27)
							)
						)
					)
				)
				(pin passive line
					(at 0 -2.54 0)
					(length 3.81)
					(name "HB00_N_CC"
						(effects
							(font
								(size 1.27 1.27)
							)
						)
					)
					(number "K26"
						(effects
							(font
								(size 1.27 1.27)
							)
						)
					)
				)
				(pin passive line
					(at 0 -5.08 0)
					(length 3.81)
					(name "HB01_P"
						(effects
							(font
								(size 1.27 1.27)
							)
						)
					)
					(number "J24"
						(effects
							(font
								(size 1.27 1.27)
							)
						)
					)
				)
				(pin passive line
					(at 0 -7.62 0)
					(length 3.81)
					(name "HB01_N"
						(effects
							(font
								(size 1.27 1.27)
							)
						)
					)
					(number "J25"
						(effects
							(font
								(size 1.27 1.27)
							)
						)
					)
				)
				(pin passive line
					(at 0 -10.16 0)
					(length 3.81)
					(name "HB02_P"
						(effects
							(font
								(size 1.27 1.27)
							)
						)
					)
					(number "F22"
						(effects
							(font
								(size 1.27 1.27)
							)
						)
					)
				)
				(pin passive line
					(at 0 -12.7 0)
					(length 3.81)
					(name "HB02_N"
						(effects
							(font
								(size 1.27 1.27)
							)
						)
					)
					(number "F23"
						(effects
							(font
								(size 1.27 1.27)
							)
						)
					)
				)
				(pin passive line
					(at 0 -15.24 0)
					(length 3.81)
					(name "HB03_P"
						(effects
							(font
								(size 1.27 1.27)
							)
						)
					)
					(number "E21"
						(effects
							(font
								(size 1.27 1.27)
							)
						)
					)
				)
				(pin passive line
					(at 0 -17.78 0)
					(length 3.81)
					(name "HB03_N"
						(effects
							(font
								(size 1.27 1.27)
							)
						)
					)
					(number "E22"
						(effects
							(font
								(size 1.27 1.27)
							)
						)
					)
				)
				(pin passive line
					(at 0 -20.32 0)
					(length 3.81)
					(name "HB04_P"
						(effects
							(font
								(size 1.27 1.27)
							)
						)
					)
					(number "F25"
						(effects
							(font
								(size 1.27 1.27)
							)
						)
					)
				)
				(pin passive line
					(at 0 -22.86 0)
					(length 3.81)
					(name "HB04_N"
						(effects
							(font
								(size 1.27 1.27)
							)
						)
					)
					(number "F26"
						(effects
							(font
								(size 1.27 1.27)
							)
						)
					)
				)
				(pin passive line
					(at 0 -25.4 0)
					(length 3.81)
					(name "HB05_P"
						(effects
							(font
								(size 1.27 1.27)
							)
						)
					)
					(number "E24"
						(effects
							(font
								(size 1.27 1.27)
							)
						)
					)
				)
				(pin passive line
					(at 0 -27.94 0)
					(length 3.81)
					(name "HB05_N"
						(effects
							(font
								(size 1.27 1.27)
							)
						)
					)
					(number "E25"
						(effects
							(font
								(size 1.27 1.27)
							)
						)
					)
				)
				(pin passive line
					(at 0 -30.48 0)
					(length 3.81)
					(name "HB06_P_CC"
						(effects
							(font
								(size 1.27 1.27)
							)
						)
					)
					(number "K28"
						(effects
							(font
								(size 1.27 1.27)
							)
						)
					)
				)
				(pin passive line
					(at 0 -33.02 0)
					(length 3.81)
					(name "HB06_N_CC"
						(effects
							(font
								(size 1.27 1.27)
							)
						)
					)
					(number "K29"
						(effects
							(font
								(size 1.27 1.27)
							)
						)
					)
				)
				(pin passive line
					(at 0 -35.56 0)
					(length 3.81)
					(name "HB07_P"
						(effects
							(font
								(size 1.27 1.27)
							)
						)
					)
					(number "J27"
						(effects
							(font
								(size 1.27 1.27)
							)
						)
					)
				)
				(pin passive line
					(at 0 -38.1 0)
					(length 3.81)
					(name "HB07_N"
						(effects
							(font
								(size 1.27 1.27)
							)
						)
					)
					(number "J28"
						(effects
							(font
								(size 1.27 1.27)
							)
						)
					)
				)
				(pin passive line
					(at 0 -40.64 0)
					(length 3.81)
					(name "HB08_P"
						(effects
							(font
								(size 1.27 1.27)
							)
						)
					)
					(number "F28"
						(effects
							(font
								(size 1.27 1.27)
							)
						)
					)
				)
				(pin passive line
					(at 0 -43.18 0)
					(length 3.81)
					(name "HB08_N"
						(effects
							(font
								(size 1.27 1.27)
							)
						)
					)
					(number "F29"
						(effects
							(font
								(size 1.27 1.27)
							)
						)
					)
				)
				(pin passive line
					(at 0 -45.72 0)
					(length 3.81)
					(name "HB09_P"
						(effects
							(font
								(size 1.27 1.27)
							)
						)
					)
					(number "E27"
						(effects
							(font
								(size 1.27 1.27)
							)
						)
					)
				)
				(pin passive line
					(at 0 -48.26 0)
					(length 3.81)
					(name "HB09_N"
						(effects
							(font
								(size 1.27 1.27)
							)
						)
					)
					(number "E28"
						(effects
							(font
								(size 1.27 1.27)
							)
						)
					)
				)
				(pin passive line
					(at 0 -50.8 0)
					(length 3.81)
					(name "HB10_P"
						(effects
							(font
								(size 1.27 1.27)
							)
						)
					)
					(number "K31"
						(effects
							(font
								(size 1.27 1.27)
							)
						)
					)
				)
				(pin passive line
					(at 0 -53.34 0)
					(length 3.81)
					(name "HB10_N"
						(effects
							(font
								(size 1.27 1.27)
							)
						)
					)
					(number "K32"
						(effects
							(font
								(size 1.27 1.27)
							)
						)
					)
				)
				(pin passive line
					(at 33.02 0 180)
					(length 3.81)
					(name "HB11_P"
						(effects
							(font
								(size 1.27 1.27)
							)
						)
					)
					(number "J30"
						(effects
							(font
								(size 1.27 1.27)
							)
						)
					)
				)
				(pin passive line
					(at 33.02 -2.54 180)
					(length 3.81)
					(name "HB11_N"
						(effects
							(font
								(size 1.27 1.27)
							)
						)
					)
					(number "J31"
						(effects
							(font
								(size 1.27 1.27)
							)
						)
					)
				)
				(pin passive line
					(at 33.02 -5.08 180)
					(length 3.81)
					(name "HB12_P"
						(effects
							(font
								(size 1.27 1.27)
							)
						)
					)
					(number "F31"
						(effects
							(font
								(size 1.27 1.27)
							)
						)
					)
				)
				(pin passive line
					(at 33.02 -7.62 180)
					(length 3.81)
					(name "HB12_N"
						(effects
							(font
								(size 1.27 1.27)
							)
						)
					)
					(number "F32"
						(effects
							(font
								(size 1.27 1.27)
							)
						)
					)
				)
				(pin passive line
					(at 33.02 -10.16 180)
					(length 3.81)
					(name "HB13_P"
						(effects
							(font
								(size 1.27 1.27)
							)
						)
					)
					(number "E30"
						(effects
							(font
								(size 1.27 1.27)
							)
						)
					)
				)
				(pin passive line
					(at 33.02 -12.7 180)
					(length 3.81)
					(name "HB13_N"
						(effects
							(font
								(size 1.27 1.27)
							)
						)
					)
					(number "E31"
						(effects
							(font
								(size 1.27 1.27)
							)
						)
					)
				)
				(pin passive line
					(at 33.02 -15.24 180)
					(length 3.81)
					(name "HB14_P"
						(effects
							(font
								(size 1.27 1.27)
							)
						)
					)
					(number "K34"
						(effects
							(font
								(size 1.27 1.27)
							)
						)
					)
				)
				(pin passive line
					(at 33.02 -17.78 180)
					(length 3.81)
					(name "HB14_N"
						(effects
							(font
								(size 1.27 1.27)
							)
						)
					)
					(number "K35"
						(effects
							(font
								(size 1.27 1.27)
							)
						)
					)
				)
				(pin passive line
					(at 33.02 -20.32 180)
					(length 3.81)
					(name "HB15_P"
						(effects
							(font
								(size 1.27 1.27)
							)
						)
					)
					(number "J33"
						(effects
							(font
								(size 1.27 1.27)
							)
						)
					)
				)
				(pin passive line
					(at 33.02 -22.86 180)
					(length 3.81)
					(name "HB15_N"
						(effects
							(font
								(size 1.27 1.27)
							)
						)
					)
					(number "J34"
						(effects
							(font
								(size 1.27 1.27)
							)
						)
					)
				)
				(pin passive line
					(at 33.02 -25.4 180)
					(length 3.81)
					(name "HB16_P"
						(effects
							(font
								(size 1.27 1.27)
							)
						)
					)
					(number "F34"
						(effects
							(font
								(size 1.27 1.27)
							)
						)
					)
				)
				(pin passive line
					(at 33.02 -27.94 180)
					(length 3.81)
					(name "HB16_N"
						(effects
							(font
								(size 1.27 1.27)
							)
						)
					)
					(number "F35"
						(effects
							(font
								(size 1.27 1.27)
							)
						)
					)
				)
				(pin passive line
					(at 33.02 -30.48 180)
					(length 3.81)
					(name "HB17_P_CC"
						(effects
							(font
								(size 1.27 1.27)
							)
						)
					)
					(number "K37"
						(effects
							(font
								(size 1.27 1.27)
							)
						)
					)
				)
				(pin passive line
					(at 33.02 -33.02 180)
					(length 3.81)
					(name "HB17_N_CC"
						(effects
							(font
								(size 1.27 1.27)
							)
						)
					)
					(number "K38"
						(effects
							(font
								(size 1.27 1.27)
							)
						)
					)
				)
				(pin passive line
					(at 33.02 -35.56 180)
					(length 3.81)
					(name "HB18_P"
						(effects
							(font
								(size 1.27 1.27)
							)
						)
					)
					(number "J36"
						(effects
							(font
								(size 1.27 1.27)
							)
						)
					)
				)
				(pin passive line
					(at 33.02 -38.1 180)
					(length 3.81)
					(name "HB18_N"
						(effects
							(font
								(size 1.27 1.27)
							)
						)
					)
					(number "J37"
						(effects
							(font
								(size 1.27 1.27)
							)
						)
					)
				)
				(pin passive line
					(at 33.02 -40.64 180)
					(length 3.81)
					(name "HB19_P"
						(effects
							(font
								(size 1.27 1.27)
							)
						)
					)
					(number "E33"
						(effects
							(font
								(size 1.27 1.27)
							)
						)
					)
				)
				(pin passive line
					(at 33.02 -43.18 180)
					(length 3.81)
					(name "HB19_N"
						(effects
							(font
								(size 1.27 1.27)
							)
						)
					)
					(number "E34"
						(effects
							(font
								(size 1.27 1.27)
							)
						)
					)
				)
				(pin passive line
					(at 33.02 -45.72 180)
					(length 3.81)
					(name "HB20_P"
						(effects
							(font
								(size 1.27 1.27)
							)
						)
					)
					(number "F37"
						(effects
							(font
								(size 1.27 1.27)
							)
						)
					)
				)
				(pin passive line
					(at 33.02 -48.26 180)
					(length 3.81)
					(name "HB20_N"
						(effects
							(font
								(size 1.27 1.27)
							)
						)
					)
					(number "F38"
						(effects
							(font
								(size 1.27 1.27)
							)
						)
					)
				)
				(pin passive line
					(at 33.02 -50.8 180)
					(length 3.81)
					(name "HB21_P"
						(effects
							(font
								(size 1.27 1.27)
							)
						)
					)
					(number "E36"
						(effects
							(font
								(size 1.27 1.27)
							)
						)
					)
				)
				(pin passive line
					(at 33.02 -53.34 180)
					(length 3.81)
					(name "HB21_N"
						(effects
							(font
								(size 1.27 1.27)
							)
						)
					)
					(number "E37"
						(effects
							(font
								(size 1.27 1.27)
							)
						)
					)
				)
			)
			(symbol "ASP-184329-01_CUSTOM_mounting_holes_6_0"
				(text "USER DEFINED"
					(at -12.7 6.35 0)
					(effects
						(font
							(size 1.27 1.27)
						)
					)
				)
				(text "CLOCKS"
					(at -12.7 3.81 0)
					(effects
						(font
							(size 1.27 1.27)
						)
					)
				)
			)
			(symbol "ASP-184329-01_CUSTOM_mounting_holes_6_1"
				(rectangle
					(start -21.59 8.89)
					(end -3.81 -25.4)
					(stroke
						(width 0.254)
						(type default)
					)
					(fill
						(type background)
					)
				)
				(pin passive line
					(at 0 0 180)
					(length 3.81)
					(name "CLK0_M2C_P"
						(effects
							(font
								(size 1.27 1.27)
							)
						)
					)
					(number "H04"
						(effects
							(font
								(size 1.27 1.27)
							)
						)
					)
				)
				(pin passive line
					(at 0 -2.54 180)
					(length 3.81)
					(name "CLK0_M2C_N"
						(effects
							(font
								(size 1.27 1.27)
							)
						)
					)
					(number "H05"
						(effects
							(font
								(size 1.27 1.27)
							)
						)
					)
				)
				(pin passive line
					(at 0 -5.08 180)
					(length 3.81)
					(name "CLK1_M2C_P"
						(effects
							(font
								(size 1.27 1.27)
							)
						)
					)
					(number "G02"
						(effects
							(font
								(size 1.27 1.27)
							)
						)
					)
				)
				(pin passive line
					(at 0 -7.62 180)
					(length 3.81)
					(name "CLK1_M2C_N"
						(effects
							(font
								(size 1.27 1.27)
							)
						)
					)
					(number "G03"
						(effects
							(font
								(size 1.27 1.27)
							)
						)
					)
				)
				(pin passive line
					(at 0 -12.7 180)
					(length 3.81)
					(name "CLK2_BIDIR_P"
						(effects
							(font
								(size 1.27 1.27)
							)
						)
					)
					(number "K04"
						(effects
							(font
								(size 1.27 1.27)
							)
						)
					)
				)
				(pin passive line
					(at 0 -15.24 180)
					(length 3.81)
					(name "CLK2_BIDIR_N"
						(effects
							(font
								(size 1.27 1.27)
							)
						)
					)
					(number "K05"
						(effects
							(font
								(size 1.27 1.27)
							)
						)
					)
				)
				(pin passive line
					(at 0 -17.78 180)
					(length 3.81)
					(name "CLK3_BIDIR_P"
						(effects
							(font
								(size 1.27 1.27)
							)
						)
					)
					(number "J02"
						(effects
							(font
								(size 1.27 1.27)
							)
						)
					)
				)
				(pin passive line
					(at 0 -20.32 180)
					(length 3.81)
					(name "CLK3_BIDIR_N"
						(effects
							(font
								(size 1.27 1.27)
							)
						)
					)
					(number "J03"
						(effects
							(font
								(size 1.27 1.27)
							)
						)
					)
				)
				(pin passive line
					(at 0 -22.86 180)
					(length 3.81)
					(name "CLK_DIR"
						(effects
							(font
								(size 1.27 1.27)
							)
						)
					)
					(number "B01"
						(effects
							(font
								(size 1.27 1.27)
							)
						)
					)
				)
			)
			(symbol "ASP-184329-01_CUSTOM_mounting_holes_7_0"
				(text "MULTI-GIGABIT"
					(at -15.24 6.35 0)
					(effects
						(font
							(size 1.27 1.27)
						)
					)
				)
				(text "CLOCKS"
					(at -15.24 3.81 0)
					(effects
						(font
							(size 1.27 1.27)
						)
					)
				)
			)
			(symbol "ASP-184329-01_CUSTOM_mounting_holes_7_1"
				(rectangle
					(start -25.4 -55.88)
					(end -3.81 8.89)
					(stroke
						(width 0.254)
						(type default)
					)
					(fill
						(type background)
					)
				)
				(pin passive line
					(at 0 0 180)
					(length 3.81)
					(name "GBTCLK0_M2C_P"
						(effects
							(font
								(size 1.27 1.27)
							)
						)
					)
					(number "D04"
						(effects
							(font
								(size 1.27 1.27)
							)
						)
					)
				)
				(pin passive line
					(at 0 -2.54 180)
					(length 3.81)
					(name "GBTCLK0_M2C_N"
						(effects
							(font
								(size 1.27 1.27)
							)
						)
					)
					(number "D05"
						(effects
							(font
								(size 1.27 1.27)
							)
						)
					)
				)
				(pin passive line
					(at 0 -5.08 180)
					(length 3.81)
					(name "GBTCLK1_M2C_P"
						(effects
							(font
								(size 1.27 1.27)
							)
						)
					)
					(number "B20"
						(effects
							(font
								(size 1.27 1.27)
							)
						)
					)
				)
				(pin passive line
					(at 0 -7.62 180)
					(length 3.81)
					(name "GBTCLK1_M2C_N"
						(effects
							(font
								(size 1.27 1.27)
							)
						)
					)
					(number "B21"
						(effects
							(font
								(size 1.27 1.27)
							)
						)
					)
				)
				(pin passive line
					(at 0 -10.16 180)
					(length 3.81)
					(name "GBTCLK2_M2C_P"
						(effects
							(font
								(size 1.27 1.27)
							)
						)
					)
					(number "L12"
						(effects
							(font
								(size 1.27 1.27)
							)
						)
					)
				)
				(pin passive line
					(at 0 -12.7 180)
					(length 3.81)
					(name "GBTCLK2_M2C_N"
						(effects
							(font
								(size 1.27 1.27)
							)
						)
					)
					(number "L13"
						(effects
							(font
								(size 1.27 1.27)
							)
						)
					)
				)
				(pin passive line
					(at 0 -15.24 180)
					(length 3.81)
					(name "GBTCLK3_M2C_P"
						(effects
							(font
								(size 1.27 1.27)
							)
						)
					)
					(number "L08"
						(effects
							(font
								(size 1.27 1.27)
							)
						)
					)
				)
				(pin passive line
					(at 0 -17.78 180)
					(length 3.81)
					(name "GBTCLK3_M2C_N"
						(effects
							(font
								(size 1.27 1.27)
							)
						)
					)
					(number "L09"
						(effects
							(font
								(size 1.27 1.27)
							)
						)
					)
				)
				(pin passive line
					(at 0 -20.32 180)
					(length 3.81)
					(name "GBTCLK4_M2C_P"
						(effects
							(font
								(size 1.27 1.27)
							)
						)
					)
					(number "L04"
						(effects
							(font
								(size 1.27 1.27)
							)
						)
					)
				)
				(pin passive line
					(at 0 -22.86 180)
					(length 3.81)
					(name "GBTCLK4_M2C_N"
						(effects
							(font
								(size 1.27 1.27)
							)
						)
					)
					(number "L05"
						(effects
							(font
								(size 1.27 1.27)
							)
						)
					)
				)
				(pin passive line
					(at 0 -25.4 180)
					(length 3.81)
					(name "GBTCLK5_M2C_P"
						(effects
							(font
								(size 1.27 1.27)
							)
						)
					)
					(number "Z20"
						(effects
							(font
								(size 1.27 1.27)
							)
						)
					)
				)
				(pin passive line
					(at 0 -27.94 180)
					(length 3.81)
					(name "GBTCLK5_M2C_N"
						(effects
							(font
								(size 1.27 1.27)
							)
						)
					)
					(number "Z21"
						(effects
							(font
								(size 1.27 1.27)
							)
						)
					)
				)
				(pin passive line
					(at 0 -33.02 180)
					(length 3.81)
					(name "REFCLK_C2M_P"
						(effects
							(font
								(size 1.27 1.27)
							)
						)
					)
					(number "L20"
						(effects
							(font
								(size 1.27 1.27)
							)
						)
					)
				)
				(pin passive line
					(at 0 -35.56 180)
					(length 3.81)
					(name "REFCLK_C2M_N"
						(effects
							(font
								(size 1.27 1.27)
							)
						)
					)
					(number "L21"
						(effects
							(font
								(size 1.27 1.27)
							)
						)
					)
				)
				(pin passive line
					(at 0 -38.1 180)
					(length 3.81)
					(name "REFCLK_M2C_P"
						(effects
							(font
								(size 1.27 1.27)
							)
						)
					)
					(number "L24"
						(effects
							(font
								(size 1.27 1.27)
							)
						)
					)
				)
				(pin passive line
					(at 0 -40.64 180)
					(length 3.81)
					(name "REFCLK_M2C_N"
						(effects
							(font
								(size 1.27 1.27)
							)
						)
					)
					(number "L25"
						(effects
							(font
								(size 1.27 1.27)
							)
						)
					)
				)
				(pin passive line
					(at 0 -45.72 180)
					(length 3.81)
					(name "SYNC_C2M_P"
						(effects
							(font
								(size 1.27 1.27)
							)
						)
					)
					(number "L16"
						(effects
							(font
								(size 1.27 1.27)
							)
						)
					)
				)
				(pin passive line
					(at 0 -48.26 180)
					(length 3.81)
					(name "SYNC_C2M_N"
						(effects
							(font
								(size 1.27 1.27)
							)
						)
					)
					(number "L17"
						(effects
							(font
								(size 1.27 1.27)
							)
						)
					)
				)
				(pin passive line
					(at 0 -50.8 180)
					(length 3.81)
					(name "SYNC_M2C_P"
						(effects
							(font
								(size 1.27 1.27)
							)
						)
					)
					(number "L28"
						(effects
							(font
								(size 1.27 1.27)
							)
						)
					)
				)
				(pin passive line
					(at 0 -53.34 180)
					(length 3.81)
					(name "SYNC_M2C_N"
						(effects
							(font
								(size 1.27 1.27)
							)
						)
					)
					(number "L29"
						(effects
							(font
								(size 1.27 1.27)
							)
						)
					)
				)
			)
			(symbol "ASP-184329-01_CUSTOM_mounting_holes_8_0"
				(text "MULTI-GIGABIT"
					(at 17.78 6.35 0)
					(effects
						(font
							(size 1.27 1.27)
						)
					)
				)
				(text "DATA"
					(at 17.78 3.81 0)
					(effects
						(font
							(size 1.27 1.27)
						)
					)
				)
			)
			(symbol "ASP-184329-01_CUSTOM_mounting_holes_8_1"
				(rectangle
					(start 3.81 8.89)
					(end 31.75 -121.92)
					(stroke
						(width 0.254)
						(type default)
					)
					(fill
						(type background)
					)
				)
				(pin passive line
					(at 0 0 0)
					(length 3.81)
					(name "DP0_C2M_P"
						(effects
							(font
								(size 1.27 1.27)
							)
						)
					)
					(number "C02"
						(effects
							(font
								(size 1.27 1.27)
							)
						)
					)
				)
				(pin passive line
					(at 0 -2.54 0)
					(length 3.81)
					(name "DP0_C2M_N"
						(effects
							(font
								(size 1.27 1.27)
							)
						)
					)
					(number "C03"
						(effects
							(font
								(size 1.27 1.27)
							)
						)
					)
				)
				(pin passive line
					(at 0 -5.08 0)
					(length 3.81)
					(name "DP1_C2M_P"
						(effects
							(font
								(size 1.27 1.27)
							)
						)
					)
					(number "A22"
						(effects
							(font
								(size 1.27 1.27)
							)
						)
					)
				)
				(pin passive line
					(at 0 -7.62 0)
					(length 3.81)
					(name "DP1_C2M_N"
						(effects
							(font
								(size 1.27 1.27)
							)
						)
					)
					(number "A23"
						(effects
							(font
								(size 1.27 1.27)
							)
						)
					)
				)
				(pin passive line
					(at 0 -10.16 0)
					(length 3.81)
					(name "DP2_C2M_P"
						(effects
							(font
								(size 1.27 1.27)
							)
						)
					)
					(number "A26"
						(effects
							(font
								(size 1.27 1.27)
							)
						)
					)
				)
				(pin passive line
					(at 0 -12.7 0)
					(length 3.81)
					(name "DP2_C2M_N"
						(effects
							(font
								(size 1.27 1.27)
							)
						)
					)
					(number "A27"
						(effects
							(font
								(size 1.27 1.27)
							)
						)
					)
				)
				(pin passive line
					(at 0 -15.24 0)
					(length 3.81)
					(name "DP3_C2M_P"
						(effects
							(font
								(size 1.27 1.27)
							)
						)
					)
					(number "A30"
						(effects
							(font
								(size 1.27 1.27)
							)
						)
					)
				)
				(pin passive line
					(at 0 -17.78 0)
					(length 3.81)
					(name "DP3_C2M_N"
						(effects
							(font
								(size 1.27 1.27)
							)
						)
					)
					(number "A31"
						(effects
							(font
								(size 1.27 1.27)
							)
						)
					)
				)
				(pin passive line
					(at 0 -20.32 0)
					(length 3.81)
					(name "DP4_C2M_P"
						(effects
							(font
								(size 1.27 1.27)
							)
						)
					)
					(number "A34"
						(effects
							(font
								(size 1.27 1.27)
							)
						)
					)
				)
				(pin passive line
					(at 0 -22.86 0)
					(length 3.81)
					(name "DP4_C2M_N"
						(effects
							(font
								(size 1.27 1.27)
							)
						)
					)
					(number "A35"
						(effects
							(font
								(size 1.27 1.27)
							)
						)
					)
				)
				(pin passive line
					(at 0 -25.4 0)
					(length 3.81)
					(name "DP5_C2M_P"
						(effects
							(font
								(size 1.27 1.27)
							)
						)
					)
					(number "A38"
						(effects
							(font
								(size 1.27 1.27)
							)
						)
					)
				)
				(pin passive line
					(at 0 -27.94 0)
					(length 3.81)
					(name "DP5_C2M_N"
						(effects
							(font
								(size 1.27 1.27)
							)
						)
					)
					(number "A39"
						(effects
							(font
								(size 1.27 1.27)
							)
						)
					)
				)
				(pin passive line
					(at 0 -30.48 0)
					(length 3.81)
					(name "DP6_C2M_P"
						(effects
							(font
								(size 1.27 1.27)
							)
						)
					)
					(number "B36"
						(effects
							(font
								(size 1.27 1.27)
							)
						)
					)
				)
				(pin passive line
					(at 0 -33.02 0)
					(length 3.81)
					(name "DP6_C2M_N"
						(effects
							(font
								(size 1.27 1.27)
							)
						)
					)
					(number "B37"
						(effects
							(font
								(size 1.27 1.27)
							)
						)
					)
				)
				(pin passive line
					(at 0 -35.56 0)
					(length 3.81)
					(name "DP7_C2M_P"
						(effects
							(font
								(size 1.27 1.27)
							)
						)
					)
					(number "B32"
						(effects
							(font
								(size 1.27 1.27)
							)
						)
					)
				)
				(pin passive line
					(at 0 -38.1 0)
					(length 3.81)
					(name "DP7_C2M_N"
						(effects
							(font
								(size 1.27 1.27)
							)
						)
					)
					(number "B33"
						(effects
							(font
								(size 1.27 1.27)
							)
						)
					)
				)
				(pin passive line
					(at 0 -40.64 0)
					(length 3.81)
					(name "DP8_C2M_P"
						(effects
							(font
								(size 1.27 1.27)
							)
						)
					)
					(number "B28"
						(effects
							(font
								(size 1.27 1.27)
							)
						)
					)
				)
				(pin passive line
					(at 0 -43.18 0)
					(length 3.81)
					(name "DP8_C2M_N"
						(effects
							(font
								(size 1.27 1.27)
							)
						)
					)
					(number "B29"
						(effects
							(font
								(size 1.27 1.27)
							)
						)
					)
				)
				(pin passive line
					(at 0 -45.72 0)
					(length 3.81)
					(name "DP9_C2M_P"
						(effects
							(font
								(size 1.27 1.27)
							)
						)
					)
					(number "B24"
						(effects
							(font
								(size 1.27 1.27)
							)
						)
					)
				)
				(pin passive line
					(at 0 -48.26 0)
					(length 3.81)
					(name "DP9_C2M_N"
						(effects
							(font
								(size 1.27 1.27)
							)
						)
					)
					(number "B25"
						(effects
							(font
								(size 1.27 1.27)
							)
						)
					)
				)
				(pin passive line
					(at 0 -50.8 0)
					(length 3.81)
					(name "DP10_C2M_P"
						(effects
							(font
								(size 1.27 1.27)
							)
						)
					)
					(number "Z24"
						(effects
							(font
								(size 1.27 1.27)
							)
						)
					)
				)
				(pin passive line
					(at 0 -53.34 0)
					(length 3.81)
					(name "DP10_C2M_N"
						(effects
							(font
								(size 1.27 1.27)
							)
						)
					)
					(number "Z25"
						(effects
							(font
								(size 1.27 1.27)
							)
						)
					)
				)
				(pin passive line
					(at 0 -55.88 0)
					(length 3.81)
					(name "DP11_C2M_P"
						(effects
							(font
								(size 1.27 1.27)
							)
						)
					)
					(number "Y26"
						(effects
							(font
								(size 1.27 1.27)
							)
						)
					)
				)
				(pin passive line
					(at 0 -58.42 0)
					(length 3.81)
					(name "DP11_C2M_N"
						(effects
							(font
								(size 1.27 1.27)
							)
						)
					)
					(number "Y27"
						(effects
							(font
								(size 1.27 1.27)
							)
						)
					)
				)
				(pin passive line
					(at 0 -60.96 0)
					(length 3.81)
					(name "DP12_C2M_P"
						(effects
							(font
								(size 1.27 1.27)
							)
						)
					)
					(number "Z28"
						(effects
							(font
								(size 1.27 1.27)
							)
						)
					)
				)
				(pin passive line
					(at 0 -63.5 0)
					(length 3.81)
					(name "DP12_C2M_N"
						(effects
							(font
								(size 1.27 1.27)
							)
						)
					)
					(number "Z29"
						(effects
							(font
								(size 1.27 1.27)
							)
						)
					)
				)
				(pin passive line
					(at 0 -66.04 0)
					(length 3.81)
					(name "DP13_C2M_P"
						(effects
							(font
								(size 1.27 1.27)
							)
						)
					)
					(number "Y30"
						(effects
							(font
								(size 1.27 1.27)
							)
						)
					)
				)
				(pin passive line
					(at 0 -68.58 0)
					(length 3.81)
					(name "DP13_C2M_N"
						(effects
							(font
								(size 1.27 1.27)
							)
						)
					)
					(number "Y31"
						(effects
							(font
								(size 1.27 1.27)
							)
						)
					)
				)
				(pin passive line
					(at 0 -71.12 0)
					(length 3.81)
					(name "DP14_C2M_P"
						(effects
							(font
								(size 1.27 1.27)
							)
						)
					)
					(number "M18"
						(effects
							(font
								(size 1.27 1.27)
							)
						)
					)
				)
				(pin passive line
					(at 0 -73.66 0)
					(length 3.81)
					(name "DP14_C2M_N"
						(effects
							(font
								(size 1.27 1.27)
							)
						)
					)
					(number "M19"
						(effects
							(font
								(size 1.27 1.27)
							)
						)
					)
				)
				(pin passive line
					(at 0 -76.2 0)
					(length 3.81)
					(name "DP15_C2M_P"
						(effects
							(font
								(size 1.27 1.27)
							)
						)
					)
					(number "M22"
						(effects
							(font
								(size 1.27 1.27)
							)
						)
					)
				)
				(pin passive line
					(at 0 -78.74 0)
					(length 3.81)
					(name "DP15_C2M_N"
						(effects
							(font
								(size 1.27 1.27)
							)
						)
					)
					(number "M23"
						(effects
							(font
								(size 1.27 1.27)
							)
						)
					)
				)
				(pin passive line
					(at 0 -81.28 0)
					(length 3.81)
					(name "DP16_C2M_P"
						(effects
							(font
								(size 1.27 1.27)
							)
						)
					)
					(number "M26"
						(effects
							(font
								(size 1.27 1.27)
							)
						)
					)
				)
				(pin passive line
					(at 0 -83.82 0)
					(length 3.81)
					(name "DP16_C2M_N"
						(effects
							(font
								(size 1.27 1.27)
							)
						)
					)
					(number "M27"
						(effects
							(font
								(size 1.27 1.27)
							)
						)
					)
				)
				(pin passive line
					(at 0 -86.36 0)
					(length 3.81)
					(name "DP17_C2M_P"
						(effects
							(font
								(size 1.27 1.27)
							)
						)
					)
					(number "M30"
						(effects
							(font
								(size 1.27 1.27)
							)
						)
					)
				)
				(pin passive line
					(at 0 -88.9 0)
					(length 3.81)
					(name "DP17_C2M_N"
						(effects
							(font
								(size 1.27 1.27)
							)
						)
					)
					(number "M31"
						(effects
							(font
								(size 1.27 1.27)
							)
						)
					)
				)
				(pin passive line
					(at 0 -91.44 0)
					(length 3.81)
					(name "DP18_C2M_P"
						(effects
							(font
								(size 1.27 1.27)
							)
						)
					)
					(number "M34"
						(effects
							(font
								(size 1.27 1.27)
							)
						)
					)
				)
				(pin passive line
					(at 0 -93.98 0)
					(length 3.81)
					(name "DP18_C2M_N"
						(effects
							(font
								(size 1.27 1.27)
							)
						)
					)
					(number "M35"
						(effects
							(font
								(size 1.27 1.27)
							)
						)
					)
				)
				(pin passive line
					(at 0 -96.52 0)
					(length 3.81)
					(name "DP19_C2M_P"
						(effects
							(font
								(size 1.27 1.27)
							)
						)
					)
					(number "M38"
						(effects
							(font
								(size 1.27 1.27)
							)
						)
					)
				)
				(pin passive line
					(at 0 -99.06 0)
					(length 3.81)
					(name "DP19_C2M_N"
						(effects
							(font
								(size 1.27 1.27)
							)
						)
					)
					(number "M39"
						(effects
							(font
								(size 1.27 1.27)
							)
						)
					)
				)
				(pin passive line
					(at 0 -101.6 0)
					(length 3.81)
					(name "DP20_C2M_P"
						(effects
							(font
								(size 1.27 1.27)
							)
						)
					)
					(number "Z08"
						(effects
							(font
								(size 1.27 1.27)
							)
						)
					)
				)
				(pin passive line
					(at 0 -104.14 0)
					(length 3.81)
					(name "DP20_C2M_N"
						(effects
							(font
								(size 1.27 1.27)
							)
						)
					)
					(number "Z09"
						(effects
							(font
								(size 1.27 1.27)
							)
						)
					)
				)
				(pin passive line
					(at 0 -106.68 0)
					(length 3.81)
					(name "DP21_C2M_P"
						(effects
							(font
								(size 1.27 1.27)
							)
						)
					)
					(number "Y06"
						(effects
							(font
								(size 1.27 1.27)
							)
						)
					)
				)
				(pin passive line
					(at 0 -109.22 0)
					(length 3.81)
					(name "DP21_C2M_N"
						(effects
							(font
								(size 1.27 1.27)
							)
						)
					)
					(number "Y07"
						(effects
							(font
								(size 1.27 1.27)
							)
						)
					)
				)
				(pin passive line
					(at 0 -111.76 0)
					(length 3.81)
					(name "DP22_C2M_P"
						(effects
							(font
								(size 1.27 1.27)
							)
						)
					)
					(number "Z04"
						(effects
							(font
								(size 1.27 1.27)
							)
						)
					)
				)
				(pin passive line
					(at 0 -114.3 0)
					(length 3.81)
					(name "DP22_C2M_N"
						(effects
							(font
								(size 1.27 1.27)
							)
						)
					)
					(number "Z05"
						(effects
							(font
								(size 1.27 1.27)
							)
						)
					)
				)
				(pin passive line
					(at 0 -116.84 0)
					(length 3.81)
					(name "DP23_C2M_P"
						(effects
							(font
								(size 1.27 1.27)
							)
						)
					)
					(number "Y02"
						(effects
							(font
								(size 1.27 1.27)
							)
						)
					)
				)
				(pin passive line
					(at 0 -119.38 0)
					(length 3.81)
					(name "DP23_C2M_N"
						(effects
							(font
								(size 1.27 1.27)
							)
						)
					)
					(number "Y03"
						(effects
							(font
								(size 1.27 1.27)
							)
						)
					)
				)
				(pin passive line
					(at 35.56 0 180)
					(length 3.81)
					(name "DP0_M2C_P"
						(effects
							(font
								(size 1.27 1.27)
							)
						)
					)
					(number "C06"
						(effects
							(font
								(size 1.27 1.27)
							)
						)
					)
				)
				(pin passive line
					(at 35.56 -2.54 180)
					(length 3.81)
					(name "DP0_M2C_N"
						(effects
							(font
								(size 1.27 1.27)
							)
						)
					)
					(number "C07"
						(effects
							(font
								(size 1.27 1.27)
							)
						)
					)
				)
				(pin passive line
					(at 35.56 -5.08 180)
					(length 3.81)
					(name "DP1_M2C_P"
						(effects
							(font
								(size 1.27 1.27)
							)
						)
					)
					(number "A02"
						(effects
							(font
								(size 1.27 1.27)
							)
						)
					)
				)
				(pin passive line
					(at 35.56 -7.62 180)
					(length 3.81)
					(name "DP1_M2C_N"
						(effects
							(font
								(size 1.27 1.27)
							)
						)
					)
					(number "A03"
						(effects
							(font
								(size 1.27 1.27)
							)
						)
					)
				)
				(pin passive line
					(at 35.56 -10.16 180)
					(length 3.81)
					(name "DP2_M2C_P"
						(effects
							(font
								(size 1.27 1.27)
							)
						)
					)
					(number "A06"
						(effects
							(font
								(size 1.27 1.27)
							)
						)
					)
				)
				(pin passive line
					(at 35.56 -12.7 180)
					(length 3.81)
					(name "DP2_M2C_N"
						(effects
							(font
								(size 1.27 1.27)
							)
						)
					)
					(number "A07"
						(effects
							(font
								(size 1.27 1.27)
							)
						)
					)
				)
				(pin passive line
					(at 35.56 -15.24 180)
					(length 3.81)
					(name "DP3_M2C_P"
						(effects
							(font
								(size 1.27 1.27)
							)
						)
					)
					(number "A10"
						(effects
							(font
								(size 1.27 1.27)
							)
						)
					)
				)
				(pin passive line
					(at 35.56 -17.78 180)
					(length 3.81)
					(name "DP3_M2C_N"
						(effects
							(font
								(size 1.27 1.27)
							)
						)
					)
					(number "A11"
						(effects
							(font
								(size 1.27 1.27)
							)
						)
					)
				)
				(pin passive line
					(at 35.56 -20.32 180)
					(length 3.81)
					(name "DP4_M2C_P"
						(effects
							(font
								(size 1.27 1.27)
							)
						)
					)
					(number "A14"
						(effects
							(font
								(size 1.27 1.27)
							)
						)
					)
				)
				(pin passive line
					(at 35.56 -22.86 180)
					(length 3.81)
					(name "DP4_M2C_N"
						(effects
							(font
								(size 1.27 1.27)
							)
						)
					)
					(number "A15"
						(effects
							(font
								(size 1.27 1.27)
							)
						)
					)
				)
				(pin passive line
					(at 35.56 -25.4 180)
					(length 3.81)
					(name "DP5_M2C_P"
						(effects
							(font
								(size 1.27 1.27)
							)
						)
					)
					(number "A18"
						(effects
							(font
								(size 1.27 1.27)
							)
						)
					)
				)
				(pin passive line
					(at 35.56 -27.94 180)
					(length 3.81)
					(name "DP5_M2C_N"
						(effects
							(font
								(size 1.27 1.27)
							)
						)
					)
					(number "A19"
						(effects
							(font
								(size 1.27 1.27)
							)
						)
					)
				)
				(pin passive line
					(at 35.56 -30.48 180)
					(length 3.81)
					(name "DP6_M2C_P"
						(effects
							(font
								(size 1.27 1.27)
							)
						)
					)
					(number "B16"
						(effects
							(font
								(size 1.27 1.27)
							)
						)
					)
				)
				(pin passive line
					(at 35.56 -33.02 180)
					(length 3.81)
					(name "DP6_M2C_N"
						(effects
							(font
								(size 1.27 1.27)
							)
						)
					)
					(number "B17"
						(effects
							(font
								(size 1.27 1.27)
							)
						)
					)
				)
				(pin passive line
					(at 35.56 -35.56 180)
					(length 3.81)
					(name "DP7_M2C_P"
						(effects
							(font
								(size 1.27 1.27)
							)
						)
					)
					(number "B12"
						(effects
							(font
								(size 1.27 1.27)
							)
						)
					)
				)
				(pin passive line
					(at 35.56 -38.1 180)
					(length 3.81)
					(name "DP7_M2C_N"
						(effects
							(font
								(size 1.27 1.27)
							)
						)
					)
					(number "B13"
						(effects
							(font
								(size 1.27 1.27)
							)
						)
					)
				)
				(pin passive line
					(at 35.56 -40.64 180)
					(length 3.81)
					(name "DP8_M2C_P"
						(effects
							(font
								(size 1.27 1.27)
							)
						)
					)
					(number "B08"
						(effects
							(font
								(size 1.27 1.27)
							)
						)
					)
				)
				(pin passive line
					(at 35.56 -43.18 180)
					(length 3.81)
					(name "DP8_M2C_N"
						(effects
							(font
								(size 1.27 1.27)
							)
						)
					)
					(number "B09"
						(effects
							(font
								(size 1.27 1.27)
							)
						)
					)
				)
				(pin passive line
					(at 35.56 -45.72 180)
					(length 3.81)
					(name "DP9_M2C_P"
						(effects
							(font
								(size 1.27 1.27)
							)
						)
					)
					(number "B04"
						(effects
							(font
								(size 1.27 1.27)
							)
						)
					)
				)
				(pin passive line
					(at 35.56 -48.26 180)
					(length 3.81)
					(name "DP9_M2C_N"
						(effects
							(font
								(size 1.27 1.27)
							)
						)
					)
					(number "B05"
						(effects
							(font
								(size 1.27 1.27)
							)
						)
					)
				)
				(pin passive line
					(at 35.56 -50.8 180)
					(length 3.81)
					(name "DP10_M2C_P"
						(effects
							(font
								(size 1.27 1.27)
							)
						)
					)
					(number "Y10"
						(effects
							(font
								(size 1.27 1.27)
							)
						)
					)
				)
				(pin passive line
					(at 35.56 -53.34 180)
					(length 3.81)
					(name "DP10_M2C_N"
						(effects
							(font
								(size 1.27 1.27)
							)
						)
					)
					(number "Y11"
						(effects
							(font
								(size 1.27 1.27)
							)
						)
					)
				)
				(pin passive line
					(at 35.56 -55.88 180)
					(length 3.81)
					(name "DP11_M2C_P"
						(effects
							(font
								(size 1.27 1.27)
							)
						)
					)
					(number "Z12"
						(effects
							(font
								(size 1.27 1.27)
							)
						)
					)
				)
				(pin passive line
					(at 35.56 -58.42 180)
					(length 3.81)
					(name "DP11_M2C_N"
						(effects
							(font
								(size 1.27 1.27)
							)
						)
					)
					(number "Z13"
						(effects
							(font
								(size 1.27 1.27)
							)
						)
					)
				)
				(pin passive line
					(at 35.56 -60.96 180)
					(length 3.81)
					(name "DP12_M2C_P"
						(effects
							(font
								(size 1.27 1.27)
							)
						)
					)
					(number "Y14"
						(effects
							(font
								(size 1.27 1.27)
							)
						)
					)
				)
				(pin passive line
					(at 35.56 -63.5 180)
					(length 3.81)
					(name "DP12_M2C_N"
						(effects
							(font
								(size 1.27 1.27)
							)
						)
					)
					(number "Y15"
						(effects
							(font
								(size 1.27 1.27)
							)
						)
					)
				)
				(pin passive line
					(at 35.56 -66.04 180)
					(length 3.81)
					(name "DP13_M2C_P"
						(effects
							(font
								(size 1.27 1.27)
							)
						)
					)
					(number "Z16"
						(effects
							(font
								(size 1.27 1.27)
							)
						)
					)
				)
				(pin passive line
					(at 35.56 -68.58 180)
					(length 3.81)
					(name "DP13_M2C_N"
						(effects
							(font
								(size 1.27 1.27)
							)
						)
					)
					(number "Z17"
						(effects
							(font
								(size 1.27 1.27)
							)
						)
					)
				)
				(pin passive line
					(at 35.56 -71.12 180)
					(length 3.81)
					(name "DP14_M2C_P"
						(effects
							(font
								(size 1.27 1.27)
							)
						)
					)
					(number "Y18"
						(effects
							(font
								(size 1.27 1.27)
							)
						)
					)
				)
				(pin passive line
					(at 35.56 -73.66 180)
					(length 3.81)
					(name "DP14_M2C_N"
						(effects
							(font
								(size 1.27 1.27)
							)
						)
					)
					(number "Y19"
						(effects
							(font
								(size 1.27 1.27)
							)
						)
					)
				)
				(pin passive line
					(at 35.56 -76.2 180)
					(length 3.81)
					(name "DP15_M2C_P"
						(effects
							(font
								(size 1.27 1.27)
							)
						)
					)
					(number "Y22"
						(effects
							(font
								(size 1.27 1.27)
							)
						)
					)
				)
				(pin passive line
					(at 35.56 -78.74 180)
					(length 3.81)
					(name "DP15_M2C_N"
						(effects
							(font
								(size 1.27 1.27)
							)
						)
					)
					(number "Y23"
						(effects
							(font
								(size 1.27 1.27)
							)
						)
					)
				)
				(pin passive line
					(at 35.56 -81.28 180)
					(length 3.81)
					(name "DP16_M2C_P"
						(effects
							(font
								(size 1.27 1.27)
							)
						)
					)
					(number "Z32"
						(effects
							(font
								(size 1.27 1.27)
							)
						)
					)
				)
				(pin passive line
					(at 35.56 -83.82 180)
					(length 3.81)
					(name "DP16_M2C_N"
						(effects
							(font
								(size 1.27 1.27)
							)
						)
					)
					(number "Z33"
						(effects
							(font
								(size 1.27 1.27)
							)
						)
					)
				)
				(pin passive line
					(at 35.56 -86.36 180)
					(length 3.81)
					(name "DP17_M2C_P"
						(effects
							(font
								(size 1.27 1.27)
							)
						)
					)
					(number "Y34"
						(effects
							(font
								(size 1.27 1.27)
							)
						)
					)
				)
				(pin passive line
					(at 35.56 -88.9 180)
					(length 3.81)
					(name "DP17_M2C_N"
						(effects
							(font
								(size 1.27 1.27)
							)
						)
					)
					(number "Y35"
						(effects
							(font
								(size 1.27 1.27)
							)
						)
					)
				)
				(pin passive line
					(at 35.56 -91.44 180)
					(length 3.81)
					(name "DP18_M2C_P"
						(effects
							(font
								(size 1.27 1.27)
							)
						)
					)
					(number "Z36"
						(effects
							(font
								(size 1.27 1.27)
							)
						)
					)
				)
				(pin passive line
					(at 35.56 -93.98 180)
					(length 3.81)
					(name "DP18_M2C_N"
						(effects
							(font
								(size 1.27 1.27)
							)
						)
					)
					(number "Z37"
						(effects
							(font
								(size 1.27 1.27)
							)
						)
					)
				)
				(pin passive line
					(at 35.56 -96.52 180)
					(length 3.81)
					(name "DP19_M2C_P"
						(effects
							(font
								(size 1.27 1.27)
							)
						)
					)
					(number "Y38"
						(effects
							(font
								(size 1.27 1.27)
							)
						)
					)
				)
				(pin passive line
					(at 35.56 -99.06 180)
					(length 3.81)
					(name "DP19_M2C_N"
						(effects
							(font
								(size 1.27 1.27)
							)
						)
					)
					(number "Y39"
						(effects
							(font
								(size 1.27 1.27)
							)
						)
					)
				)
				(pin passive line
					(at 35.56 -101.6 180)
					(length 3.81)
					(name "DP20_M2C_P"
						(effects
							(font
								(size 1.27 1.27)
							)
						)
					)
					(number "M14"
						(effects
							(font
								(size 1.27 1.27)
							)
						)
					)
				)
				(pin passive line
					(at 35.56 -104.14 180)
					(length 3.81)
					(name "DP20_M2C_N"
						(effects
							(font
								(size 1.27 1.27)
							)
						)
					)
					(number "M15"
						(effects
							(font
								(size 1.27 1.27)
							)
						)
					)
				)
				(pin passive line
					(at 35.56 -106.68 180)
					(length 3.81)
					(name "DP21_M2C_P"
						(effects
							(font
								(size 1.27 1.27)
							)
						)
					)
					(number "M10"
						(effects
							(font
								(size 1.27 1.27)
							)
						)
					)
				)
				(pin passive line
					(at 35.56 -109.22 180)
					(length 3.81)
					(name "DP21_M2C_N"
						(effects
							(font
								(size 1.27 1.27)
							)
						)
					)
					(number "M11"
						(effects
							(font
								(size 1.27 1.27)
							)
						)
					)
				)
				(pin passive line
					(at 35.56 -111.76 180)
					(length 3.81)
					(name "DP22_M2C_P"
						(effects
							(font
								(size 1.27 1.27)
							)
						)
					)
					(number "M06"
						(effects
							(font
								(size 1.27 1.27)
							)
						)
					)
				)
				(pin passive line
					(at 35.56 -114.3 180)
					(length 3.81)
					(name "DP22_M2C_N"
						(effects
							(font
								(size 1.27 1.27)
							)
						)
					)
					(number "M07"
						(effects
							(font
								(size 1.27 1.27)
							)
						)
					)
				)
				(pin passive line
					(at 35.56 -116.84 180)
					(length 3.81)
					(name "DP23_M2C_P"
						(effects
							(font
								(size 1.27 1.27)
							)
						)
					)
					(number "M02"
						(effects
							(font
								(size 1.27 1.27)
							)
						)
					)
				)
				(pin passive line
					(at 35.56 -119.38 180)
					(length 3.81)
					(name "DP23_M2C_N"
						(effects
							(font
								(size 1.27 1.27)
							)
						)
					)
					(number "M03"
						(effects
							(font
								(size 1.27 1.27)
							)
						)
					)
				)
			)
		)
	(symbol "antmicroB2BConnectors:Socket_Samtec_ERF5_2x20_ERF5-020-05.0-L-DV-K-TR"
			(exclude_from_sim no)
			(in_bom yes)
			(on_board yes)
			(property "Reference" "J"
				(at 26.67 0 0)
				(effects
					(font
						(size 1.27 1.27)
						(thickness 0.15)
					)
					(justify left bottom)
				)
			)
			(property "Value" "Socket_Samtec_ERF5_2x20_ERF5-020-05.0-L-DV-K-TR"
				(at 26.67 -5.08 0)
				(effects
					(font
						(size 1.27 1.27)
						(thickness 0.15)
					)
					(justify left bottom)
					(hide yes)
				)
			)
			(property "Footprint" "antmicro-footprints:Conn_Socket_Samtec_ERF5_2x20_ERF5-020-05.0-L-DV-K-TR"
				(at 26.67 -7.62 0)
				(effects
					(font
						(size 1.27 1.27)
						(thickness 0.15)
					)
					(justify left bottom)
					(hide yes)
				)
			)
			(property "Datasheet" "https://suddendocs.samtec.com/productspecs/erm5-erf5.pdf?_gl=1*1g914su*_ga*MTE0MzExNjY4MC4xNjcyMTQ5NTUz*_ga_3KFNZC07WW*MTY3Mjg0NzY5Ny42LjEuMTY3Mjg0ODE3MS42MC4wLjA."
				(at 26.67 -10.16 0)
				(effects
					(font
						(size 1.27 1.27)
						(thickness 0.15)
					)
					(justify left bottom)
					(hide yes)
				)
			)
			(property "Description" "Board to Board & Mezzanine Connectors 0.50 mm Edge Rate Rugged High Speed Socket"
				(at 0 0 0)
				(effects
					(font
						(size 1.27 1.27)
					)
					(hide yes)
				)
			)
			(property "MPN" "ERF5-020-05.0-L-DV-K-TR"
				(at 26.67 -2.54 0)
				(effects
					(font
						(size 1.27 1.27)
						(thickness 0.15)
					)
					(justify left bottom)
				)
			)
			(property "Manufacturer" "Samtec"
				(at 26.67 -12.7 0)
				(effects
					(font
						(size 1.27 1.27)
						(thickness 0.15)
					)
					(justify left bottom)
					(hide yes)
				)
			)
			(property "Author" "Antmicro"
				(at 26.67 -17.78 0)
				(effects
					(font
						(size 1.27 1.27)
						(thickness 0.15)
					)
					(justify left bottom)
					(hide yes)
				)
			)
			(property "License" "Apache-2.0"
				(at 26.67 -20.32 0)
				(effects
					(font
						(size 1.27 1.27)
						(thickness 0.15)
					)
					(justify left bottom)
					(hide yes)
				)
			)
			(property "Pitch" "0.5 mm"
				(at 26.67 -15.24 0)
				(effects
					(font
						(size 1.27 1.27)
					)
					(justify left bottom)
					(hide yes)
				)
			)
			(property "ki_keywords" "CONNECTOR, B2B, SOCKET"
				(at 0 0 0)
				(effects
					(font
						(size 1.27 1.27)
					)
					(hide yes)
				)
			)
			(symbol "Socket_Samtec_ERF5_2x20_ERF5-020-05.0-L-DV-K-TR_1_1"
				(rectangle
					(start 2.54 2.54)
					(end 8.89 -50.8)
					(stroke
						(width 0.254)
						(type default)
					)
					(fill
						(type background)
					)
				)
				(rectangle
					(start 3.81 1.27)
					(end 7.62 -49.53)
					(stroke
						(width 0.254)
						(type default)
					)
					(fill
						(type background)
					)
				)
				(pin passive line
					(at 0 0 0)
					(length 2.54)
					(name "~"
						(effects
							(font
								(size 1.27 1.27)
							)
						)
					)
					(number "1"
						(effects
							(font
								(size 1.27 1.27)
							)
						)
					)
				)
				(pin passive line
					(at 0 -2.54 0)
					(length 2.54)
					(name "~"
						(effects
							(font
								(size 1.27 1.27)
							)
						)
					)
					(number "3"
						(effects
							(font
								(size 1.27 1.27)
							)
						)
					)
				)
				(pin passive line
					(at 0 -5.08 0)
					(length 2.54)
					(name "~"
						(effects
							(font
								(size 1.27 1.27)
							)
						)
					)
					(number "5"
						(effects
							(font
								(size 1.27 1.27)
							)
						)
					)
				)
				(pin passive line
					(at 0 -7.62 0)
					(length 2.54)
					(name "~"
						(effects
							(font
								(size 1.27 1.27)
							)
						)
					)
					(number "7"
						(effects
							(font
								(size 1.27 1.27)
							)
						)
					)
				)
				(pin passive line
					(at 0 -10.16 0)
					(length 2.54)
					(name "~"
						(effects
							(font
								(size 1.27 1.27)
							)
						)
					)
					(number "9"
						(effects
							(font
								(size 1.27 1.27)
							)
						)
					)
				)
				(pin passive line
					(at 0 -12.7 0)
					(length 2.54)
					(name "~"
						(effects
							(font
								(size 1.27 1.27)
							)
						)
					)
					(number "11"
						(effects
							(font
								(size 1.27 1.27)
							)
						)
					)
				)
				(pin passive line
					(at 0 -15.24 0)
					(length 2.54)
					(name "~"
						(effects
							(font
								(size 1.27 1.27)
							)
						)
					)
					(number "13"
						(effects
							(font
								(size 1.27 1.27)
							)
						)
					)
				)
				(pin passive line
					(at 0 -17.78 0)
					(length 2.54)
					(name "~"
						(effects
							(font
								(size 1.27 1.27)
							)
						)
					)
					(number "15"
						(effects
							(font
								(size 1.27 1.27)
							)
						)
					)
				)
				(pin passive line
					(at 0 -20.32 0)
					(length 2.54)
					(name "~"
						(effects
							(font
								(size 1.27 1.27)
							)
						)
					)
					(number "17"
						(effects
							(font
								(size 1.27 1.27)
							)
						)
					)
				)
				(pin passive line
					(at 0 -22.86 0)
					(length 2.54)
					(name "~"
						(effects
							(font
								(size 1.27 1.27)
							)
						)
					)
					(number "19"
						(effects
							(font
								(size 1.27 1.27)
							)
						)
					)
				)
				(pin passive line
					(at 0 -25.4 0)
					(length 2.54)
					(name "~"
						(effects
							(font
								(size 1.27 1.27)
							)
						)
					)
					(number "21"
						(effects
							(font
								(size 1.27 1.27)
							)
						)
					)
				)
				(pin passive line
					(at 0 -27.94 0)
					(length 2.54)
					(name "~"
						(effects
							(font
								(size 1.27 1.27)
							)
						)
					)
					(number "23"
						(effects
							(font
								(size 1.27 1.27)
							)
						)
					)
				)
				(pin passive line
					(at 0 -30.48 0)
					(length 2.54)
					(name "~"
						(effects
							(font
								(size 1.27 1.27)
							)
						)
					)
					(number "25"
						(effects
							(font
								(size 1.27 1.27)
							)
						)
					)
				)
				(pin passive line
					(at 0 -33.02 0)
					(length 2.54)
					(name "~"
						(effects
							(font
								(size 1.27 1.27)
							)
						)
					)
					(number "27"
						(effects
							(font
								(size 1.27 1.27)
							)
						)
					)
				)
				(pin passive line
					(at 0 -35.56 0)
					(length 2.54)
					(name "~"
						(effects
							(font
								(size 1.27 1.27)
							)
						)
					)
					(number "29"
						(effects
							(font
								(size 1.27 1.27)
							)
						)
					)
				)
				(pin passive line
					(at 0 -38.1 0)
					(length 2.54)
					(name "~"
						(effects
							(font
								(size 1.27 1.27)
							)
						)
					)
					(number "31"
						(effects
							(font
								(size 1.27 1.27)
							)
						)
					)
				)
				(pin passive line
					(at 0 -40.64 0)
					(length 2.54)
					(name "~"
						(effects
							(font
								(size 1.27 1.27)
							)
						)
					)
					(number "33"
						(effects
							(font
								(size 1.27 1.27)
							)
						)
					)
				)
				(pin passive line
					(at 0 -43.18 0)
					(length 2.54)
					(name "~"
						(effects
							(font
								(size 1.27 1.27)
							)
						)
					)
					(number "35"
						(effects
							(font
								(size 1.27 1.27)
							)
						)
					)
				)
				(pin passive line
					(at 0 -45.72 0)
					(length 2.54)
					(name "~"
						(effects
							(font
								(size 1.27 1.27)
							)
						)
					)
					(number "37"
						(effects
							(font
								(size 1.27 1.27)
							)
						)
					)
				)
				(pin passive line
					(at 0 -48.26 0)
					(length 2.54)
					(name "~"
						(effects
							(font
								(size 1.27 1.27)
							)
						)
					)
					(number "39"
						(effects
							(font
								(size 1.27 1.27)
							)
						)
					)
				)
				(pin passive line
					(at 11.43 0 180)
					(length 2.54)
					(name "~"
						(effects
							(font
								(size 1.27 1.27)
							)
						)
					)
					(number "2"
						(effects
							(font
								(size 1.27 1.27)
							)
						)
					)
				)
				(pin passive line
					(at 11.43 -2.54 180)
					(length 2.54)
					(name "~"
						(effects
							(font
								(size 1.27 1.27)
							)
						)
					)
					(number "4"
						(effects
							(font
								(size 1.27 1.27)
							)
						)
					)
				)
				(pin passive line
					(at 11.43 -5.08 180)
					(length 2.54)
					(name "~"
						(effects
							(font
								(size 1.27 1.27)
							)
						)
					)
					(number "6"
						(effects
							(font
								(size 1.27 1.27)
							)
						)
					)
				)
				(pin passive line
					(at 11.43 -7.62 180)
					(length 2.54)
					(name "~"
						(effects
							(font
								(size 1.27 1.27)
							)
						)
					)
					(number "8"
						(effects
							(font
								(size 1.27 1.27)
							)
						)
					)
				)
				(pin passive line
					(at 11.43 -10.16 180)
					(length 2.54)
					(name "~"
						(effects
							(font
								(size 1.27 1.27)
							)
						)
					)
					(number "10"
						(effects
							(font
								(size 1.27 1.27)
							)
						)
					)
				)
				(pin passive line
					(at 11.43 -12.7 180)
					(length 2.54)
					(name "~"
						(effects
							(font
								(size 1.27 1.27)
							)
						)
					)
					(number "12"
						(effects
							(font
								(size 1.27 1.27)
							)
						)
					)
				)
				(pin passive line
					(at 11.43 -15.24 180)
					(length 2.54)
					(name "~"
						(effects
							(font
								(size 1.27 1.27)
							)
						)
					)
					(number "14"
						(effects
							(font
								(size 1.27 1.27)
							)
						)
					)
				)
				(pin passive line
					(at 11.43 -17.78 180)
					(length 2.54)
					(name "~"
						(effects
							(font
								(size 1.27 1.27)
							)
						)
					)
					(number "16"
						(effects
							(font
								(size 1.27 1.27)
							)
						)
					)
				)
				(pin passive line
					(at 11.43 -20.32 180)
					(length 2.54)
					(name "~"
						(effects
							(font
								(size 1.27 1.27)
							)
						)
					)
					(number "18"
						(effects
							(font
								(size 1.27 1.27)
							)
						)
					)
				)
				(pin passive line
					(at 11.43 -22.86 180)
					(length 2.54)
					(name "~"
						(effects
							(font
								(size 1.27 1.27)
							)
						)
					)
					(number "20"
						(effects
							(font
								(size 1.27 1.27)
							)
						)
					)
				)
				(pin passive line
					(at 11.43 -25.4 180)
					(length 2.54)
					(name "~"
						(effects
							(font
								(size 1.27 1.27)
							)
						)
					)
					(number "22"
						(effects
							(font
								(size 1.27 1.27)
							)
						)
					)
				)
				(pin passive line
					(at 11.43 -27.94 180)
					(length 2.54)
					(name "~"
						(effects
							(font
								(size 1.27 1.27)
							)
						)
					)
					(number "24"
						(effects
							(font
								(size 1.27 1.27)
							)
						)
					)
				)
				(pin passive line
					(at 11.43 -30.48 180)
					(length 2.54)
					(name "~"
						(effects
							(font
								(size 1.27 1.27)
							)
						)
					)
					(number "26"
						(effects
							(font
								(size 1.27 1.27)
							)
						)
					)
				)
				(pin passive line
					(at 11.43 -33.02 180)
					(length 2.54)
					(name "~"
						(effects
							(font
								(size 1.27 1.27)
							)
						)
					)
					(number "28"
						(effects
							(font
								(size 1.27 1.27)
							)
						)
					)
				)
				(pin passive line
					(at 11.43 -35.56 180)
					(length 2.54)
					(name "~"
						(effects
							(font
								(size 1.27 1.27)
							)
						)
					)
					(number "30"
						(effects
							(font
								(size 1.27 1.27)
							)
						)
					)
				)
				(pin passive line
					(at 11.43 -38.1 180)
					(length 2.54)
					(name "~"
						(effects
							(font
								(size 1.27 1.27)
							)
						)
					)
					(number "32"
						(effects
							(font
								(size 1.27 1.27)
							)
						)
					)
				)
				(pin passive line
					(at 11.43 -40.64 180)
					(length 2.54)
					(name "~"
						(effects
							(font
								(size 1.27 1.27)
							)
						)
					)
					(number "34"
						(effects
							(font
								(size 1.27 1.27)
							)
						)
					)
				)
				(pin passive line
					(at 11.43 -43.18 180)
					(length 2.54)
					(name "~"
						(effects
							(font
								(size 1.27 1.27)
							)
						)
					)
					(number "36"
						(effects
							(font
								(size 1.27 1.27)
							)
						)
					)
				)
				(pin passive line
					(at 11.43 -45.72 180)
					(length 2.54)
					(name "~"
						(effects
							(font
								(size 1.27 1.27)
							)
						)
					)
					(number "38"
						(effects
							(font
								(size 1.27 1.27)
							)
						)
					)
				)
				(pin passive line
					(at 11.43 -48.26 180)
					(length 2.54)
					(name "~"
						(effects
							(font
								(size 1.27 1.27)
							)
						)
					)
					(number "40"
						(effects
							(font
								(size 1.27 1.27)
							)
						)
					)
				)
			)
		)
	(symbol "antmicroBarrelPowerConnectors:BarrelJack_Pin2mm_MJ-179PH"
			(pin_names
				(hide yes)
			)
			(exclude_from_sim no)
			(in_bom yes)
			(on_board yes)
			(property "Reference" "J"
				(at 17.78 -5.08 0)
				(effects
					(font
						(size 1.27 1.27)
						(thickness 0.15)
					)
					(justify left bottom)
				)
			)
			(property "Value" "BarrelJack_Pin2mm_MJ-179PH"
				(at 17.78 -10.16 0)
				(effects
					(font
						(size 1.27 1.27)
						(thickness 0.15)
					)
					(justify left bottom)
					(hide yes)
				)
			)
			(property "Footprint" "antmicro-footprints:BarrelJack_Pin2mm_MJ-179PH"
				(at 17.78 -12.7 0)
				(effects
					(font
						(size 1.27 1.27)
						(thickness 0.15)
					)
					(justify left bottom)
					(hide yes)
				)
			)
			(property "Datasheet" "https://www.farnell.com/datasheets/3167288.pdf"
				(at 17.78 -15.24 0)
				(effects
					(font
						(size 1.27 1.27)
						(thickness 0.15)
					)
					(justify left bottom)
					(hide yes)
				)
			)
			(property "Description" "DC Power Connector, Jack, 4 A, 1.95 mm, PCB Mount, Through Hole"
				(at 0 0 0)
				(effects
					(font
						(size 1.27 1.27)
					)
					(hide yes)
				)
			)
			(property "MPN" "MJ-179PH"
				(at 17.78 -7.62 0)
				(effects
					(font
						(size 1.27 1.27)
						(thickness 0.15)
					)
					(justify left bottom)
				)
			)
			(property "Manufacturer" "Multicomp Pro"
				(at 17.78 -17.78 0)
				(effects
					(font
						(size 1.27 1.27)
						(thickness 0.15)
					)
					(justify left bottom)
					(hide yes)
				)
			)
			(property "Author" "Antmicro"
				(at 17.78 -20.32 0)
				(effects
					(font
						(size 1.27 1.27)
						(thickness 0.15)
					)
					(justify left bottom)
					(hide yes)
				)
			)
			(property "License" "Apache-2.0"
				(at 17.78 -22.86 0)
				(effects
					(font
						(size 1.27 1.27)
						(thickness 0.15)
					)
					(justify left bottom)
					(hide yes)
				)
			)
			(property "ki_keywords" "HORIZONTAL, THT, JACK, CONNECTOR, POWER"
				(at 0 0 0)
				(effects
					(font
						(size 1.27 1.27)
					)
					(hide yes)
				)
			)
			(symbol "BarrelJack_Pin2mm_MJ-179PH_0_1"
				(polyline
					(pts
						(xy -5.08 -5.08) (xy -5.334 -4.064) (xy -4.826 -4.064) (xy -5.08 -5.08)
					)
					(stroke
						(width 0)
						(type default)
					)
					(fill
						(type outline)
					)
				)
			)
			(symbol "BarrelJack_Pin2mm_MJ-179PH_1_1"
				(rectangle
					(start -12.7 1.27)
					(end -2.54 -6.35)
					(stroke
						(width 0.254)
						(type default)
					)
					(fill
						(type background)
					)
				)
				(arc
					(start -10.795 0)
					(mid -10.609 0.449)
					(end -10.16 0.635)
					(stroke
						(width 0.254)
						(type default)
					)
					(fill
						(type outline)
					)
				)
				(arc
					(start -10.16 -0.635)
					(mid -10.609 -0.449)
					(end -10.795 0)
					(stroke
						(width 0.254)
						(type default)
					)
					(fill
						(type outline)
					)
				)
				(rectangle
					(start -10.16 -0.635)
					(end -6.985 0.635)
					(stroke
						(width 0.254)
						(type default)
					)
					(fill
						(type outline)
					)
				)
				(arc
					(start -8.89 -3.175)
					(mid -7.543 -3.733)
					(end -6.985 -5.08)
					(stroke
						(width 0.254)
						(type default)
					)
					(fill
						(type none)
					)
				)
				(arc
					(start -10.795 -5.08)
					(mid -10.237 -3.733)
					(end -8.89 -3.175)
					(stroke
						(width 0.254)
						(type default)
					)
					(fill
						(type none)
					)
				)
				(polyline
					(pts
						(xy -5.08 -2.54) (xy -5.08 -5.08)
					)
					(stroke
						(width 0.254)
						(type default)
					)
					(fill
						(type background)
					)
				)
				(polyline
					(pts
						(xy -2.54 0) (xy -6.985 0)
					)
					(stroke
						(width 0.254)
						(type default)
					)
					(fill
						(type background)
					)
				)
				(polyline
					(pts
						(xy -2.54 -2.54) (xy -5.08 -2.54)
					)
					(stroke
						(width 0.254)
						(type default)
					)
					(fill
						(type background)
					)
				)
				(polyline
					(pts
						(xy -2.54 -5.08) (xy -6.985 -5.08)
					)
					(stroke
						(width 0.254)
						(type default)
					)
					(fill
						(type background)
					)
				)
				(pin passive line
					(at 0 0 180)
					(length 2.54)
					(name "1"
						(effects
							(font
								(size 1.27 1.27)
							)
						)
					)
					(number "1"
						(effects
							(font
								(size 1.27 1.27)
							)
						)
					)
				)
				(pin passive line
					(at 0 -2.54 180)
					(length 2.54)
					(name "2"
						(effects
							(font
								(size 1.27 1.27)
							)
						)
					)
					(number "2"
						(effects
							(font
								(size 1.27 1.27)
							)
						)
					)
				)
				(pin passive line
					(at 0 -5.08 180)
					(length 2.54)
					(name "3"
						(effects
							(font
								(size 1.27 1.27)
							)
						)
					)
					(number "3"
						(effects
							(font
								(size 1.27 1.27)
							)
						)
					)
				)
			)
		)
	(symbol "antmicroCapacitors0402:C_100n_0402"
			(pin_numbers
				(hide yes)
			)
			(pin_names
				(hide yes)
			)
			(exclude_from_sim no)
			(in_bom yes)
			(on_board yes)
			(property "Reference" "C"
				(at 20.32 -5.08 0)
				(effects
					(font
						(size 1.27 1.27)
						(thickness 0.15)
					)
					(justify left bottom)
				)
			)
			(property "Value" "C_100n_0402"
				(at 20.32 -10.16 0)
				(effects
					(font
						(size 1.27 1.27)
						(thickness 0.15)
					)
					(justify left bottom)
					(hide yes)
				)
			)
			(property "Footprint" "antmicro-footprints:C_0402_1005Metric"
				(at 20.32 -12.7 0)
				(effects
					(font
						(size 1.27 1.27)
						(thickness 0.15)
					)
					(justify left bottom)
					(hide yes)
				)
			)
			(property "Datasheet" "https://www.murata.com/products/productdetail?partno=GRM155R61H104KE14%23"
				(at 20.32 -15.24 0)
				(effects
					(font
						(size 1.27 1.27)
						(thickness 0.15)
					)
					(justify left bottom)
					(hide yes)
				)
			)
			(property "Description" "SMD Multilayer Ceramic Capacitor, 0.1 µF, 50 V, 0402 [1005 Metric], ± 10%, X5R, GRM Series"
				(at 0 0 0)
				(effects
					(font
						(size 1.27 1.27)
					)
					(hide yes)
				)
			)
			(property "MPN" "GRM155R61H104KE14D"
				(at 20.32 -17.78 0)
				(effects
					(font
						(size 1.27 1.27)
						(thickness 0.15)
					)
					(justify left bottom)
					(hide yes)
				)
			)
			(property "Manufacturer" "Murata"
				(at 20.32 -20.32 0)
				(effects
					(font
						(size 1.27 1.27)
						(thickness 0.15)
					)
					(justify left bottom)
					(hide yes)
				)
			)
			(property "License" "Apache-2.0"
				(at 20.32 -22.86 0)
				(effects
					(font
						(size 1.27 1.27)
						(thickness 0.15)
					)
					(justify left bottom)
					(hide yes)
				)
			)
			(property "Author" "Antmicro"
				(at 20.32 -25.4 0)
				(effects
					(font
						(size 1.27 1.27)
						(thickness 0.15)
					)
					(justify left bottom)
					(hide yes)
				)
			)
			(property "Val" "100n"
				(at 20.32 -7.62 0)
				(effects
					(font
						(size 1.27 1.27)
						(thickness 0.15)
					)
					(justify left bottom)
				)
			)
			(property "Voltage" "50V"
				(at 20.32 -27.94 0)
				(effects
					(font
						(size 1.27 1.27)
					)
					(justify left bottom)
					(hide yes)
				)
			)
			(property "Dielectric" "X5R"
				(at 20.32 -30.48 0)
				(effects
					(font
						(size 1.27 1.27)
					)
					(justify left bottom)
					(hide yes)
				)
			)
			(property "ki_keywords" "0402, SMT, CAPACITOR, PASSIVE, CERAMIC, MLCC"
				(at 0 0 0)
				(effects
					(font
						(size 1.27 1.27)
					)
					(hide yes)
				)
			)
			(symbol "C_100n_0402_0_1"
				(polyline
					(pts
						(xy 2.032 -1.524) (xy 2.032 1.524)
					)
					(stroke
						(width 0.3048)
						(type default)
					)
					(fill
						(type none)
					)
				)
				(polyline
					(pts
						(xy 3.048 -1.524) (xy 3.048 1.524)
					)
					(stroke
						(width 0.3302)
						(type default)
					)
					(fill
						(type none)
					)
				)
			)
			(symbol "C_100n_0402_1_1"
				(pin passive line
					(at 0 0 0)
					(length 2.032)
					(name "~"
						(effects
							(font
								(size 1.27 1.27)
							)
						)
					)
					(number "1"
						(effects
							(font
								(size 1.27 1.27)
							)
						)
					)
				)
				(pin passive line
					(at 5.08 0 180)
					(length 2.032)
					(name "~"
						(effects
							(font
								(size 1.27 1.27)
							)
						)
					)
					(number "2"
						(effects
							(font
								(size 1.27 1.27)
							)
						)
					)
				)
			)
		)
	(symbol "antmicroCapacitors0402:C_10p_0402"
			(pin_numbers
				(hide yes)
			)
			(pin_names
				(hide yes)
			)
			(exclude_from_sim no)
			(in_bom yes)
			(on_board yes)
			(property "Reference" "C"
				(at 20.32 -5.08 0)
				(effects
					(font
						(size 1.27 1.27)
						(thickness 0.15)
					)
					(justify left bottom)
				)
			)
			(property "Value" "C_10p_0402"
				(at 20.32 -10.16 0)
				(effects
					(font
						(size 1.27 1.27)
						(thickness 0.15)
					)
					(justify left bottom)
					(hide yes)
				)
			)
			(property "Footprint" "antmicro-footprints:C_0402_1005Metric"
				(at 20.32 -12.7 0)
				(effects
					(font
						(size 1.27 1.27)
						(thickness 0.15)
					)
					(justify left bottom)
					(hide yes)
				)
			)
			(property "Datasheet" "https://www.murata.com/products/productdetail?partno=GCM1555C1H100GA16%23"
				(at 20.32 -15.24 0)
				(effects
					(font
						(size 1.27 1.27)
						(thickness 0.15)
					)
					(justify left bottom)
					(hide yes)
				)
			)
			(property "Description" "SMD Multilayer Ceramic Capacitor, 10 pF, 50 V, 0402 [1005 Metric], ± 2%, C0G / NP0, GCM"
				(at 0 0 0)
				(effects
					(font
						(size 1.27 1.27)
					)
					(hide yes)
				)
			)
			(property "MPN" "GCM1555C1H100GA16D"
				(at 20.32 -17.78 0)
				(effects
					(font
						(size 1.27 1.27)
						(thickness 0.15)
					)
					(justify left bottom)
					(hide yes)
				)
			)
			(property "Manufacturer" "Murata"
				(at 20.32 -20.32 0)
				(effects
					(font
						(size 1.27 1.27)
						(thickness 0.15)
					)
					(justify left bottom)
					(hide yes)
				)
			)
			(property "License" "Apache-2.0"
				(at 20.32 -22.86 0)
				(effects
					(font
						(size 1.27 1.27)
						(thickness 0.15)
					)
					(justify left bottom)
					(hide yes)
				)
			)
			(property "Author" "Antmicro"
				(at 20.32 -25.4 0)
				(effects
					(font
						(size 1.27 1.27)
						(thickness 0.15)
					)
					(justify left bottom)
					(hide yes)
				)
			)
			(property "Val" "10p"
				(at 20.32 -7.62 0)
				(effects
					(font
						(size 1.27 1.27)
						(thickness 0.15)
					)
					(justify left bottom)
				)
			)
			(property "Voltage" "50V"
				(at 20.32 -27.94 0)
				(effects
					(font
						(size 1.27 1.27)
					)
					(justify left bottom)
					(hide yes)
				)
			)
			(property "Dielectric" "C0G"
				(at 20.32 -30.48 0)
				(effects
					(font
						(size 1.27 1.27)
					)
					(justify left bottom)
					(hide yes)
				)
			)
			(property "ki_keywords" "0402, SMT, CAPACITOR, PASSIVE"
				(at 0 0 0)
				(effects
					(font
						(size 1.27 1.27)
					)
					(hide yes)
				)
			)
			(symbol "C_10p_0402_0_1"
				(polyline
					(pts
						(xy 2.032 -1.524) (xy 2.032 1.524)
					)
					(stroke
						(width 0.3048)
						(type default)
					)
					(fill
						(type none)
					)
				)
				(polyline
					(pts
						(xy 3.048 -1.524) (xy 3.048 1.524)
					)
					(stroke
						(width 0.3302)
						(type default)
					)
					(fill
						(type none)
					)
				)
			)
			(symbol "C_10p_0402_1_1"
				(pin passive line
					(at 0 0 0)
					(length 2.032)
					(name "~"
						(effects
							(font
								(size 1.27 1.27)
							)
						)
					)
					(number "1"
						(effects
							(font
								(size 1.27 1.27)
							)
						)
					)
				)
				(pin passive line
					(at 5.08 0 180)
					(length 2.032)
					(name "~"
						(effects
							(font
								(size 1.27 1.27)
							)
						)
					)
					(number "2"
						(effects
							(font
								(size 1.27 1.27)
							)
						)
					)
				)
			)
		)
	(symbol "antmicroCapacitors0402:C_10u_0402"
			(pin_numbers
				(hide yes)
			)
			(pin_names
				(hide yes)
			)
			(exclude_from_sim no)
			(in_bom yes)
			(on_board yes)
			(property "Reference" "C"
				(at 20.32 -5.08 0)
				(effects
					(font
						(size 1.27 1.27)
						(thickness 0.15)
					)
					(justify left bottom)
				)
			)
			(property "Value" "C_10u_0402"
				(at 20.32 -10.16 0)
				(effects
					(font
						(size 1.27 1.27)
						(thickness 0.15)
					)
					(justify left bottom)
					(hide yes)
				)
			)
			(property "Footprint" "antmicro-footprints:C_0402_1005Metric"
				(at 20.32 -12.7 0)
				(effects
					(font
						(size 1.27 1.27)
						(thickness 0.15)
					)
					(justify left bottom)
					(hide yes)
				)
			)
			(property "Datasheet" "https://www.yageo.com/en/Chart/Download/pdf/CC0402MRX5R5BB106"
				(at 20.32 -15.24 0)
				(effects
					(font
						(size 1.27 1.27)
						(thickness 0.15)
					)
					(justify left bottom)
					(hide yes)
				)
			)
			(property "Description" "SMD Multilayer Ceramic Capacitor, 10 µF, 6.3 V, 0402 [1005 Metric], ± 20%, X5R, CC Series"
				(at 0 0 0)
				(effects
					(font
						(size 1.27 1.27)
					)
					(hide yes)
				)
			)
			(property "MPN" "CC0402MRX5R5BB106"
				(at 20.32 -17.78 0)
				(effects
					(font
						(size 1.27 1.27)
						(thickness 0.15)
					)
					(justify left bottom)
					(hide yes)
				)
			)
			(property "Manufacturer" "YAGEO"
				(at 20.32 -20.32 0)
				(effects
					(font
						(size 1.27 1.27)
						(thickness 0.15)
					)
					(justify left bottom)
					(hide yes)
				)
			)
			(property "License" "Apache-2.0"
				(at 20.32 -22.86 0)
				(effects
					(font
						(size 1.27 1.27)
						(thickness 0.15)
					)
					(justify left bottom)
					(hide yes)
				)
			)
			(property "Author" "Antmicro"
				(at 20.32 -25.4 0)
				(effects
					(font
						(size 1.27 1.27)
						(thickness 0.15)
					)
					(justify left bottom)
					(hide yes)
				)
			)
			(property "Val" "10u"
				(at 20.32 -7.62 0)
				(effects
					(font
						(size 1.27 1.27)
						(thickness 0.15)
					)
					(justify left bottom)
				)
			)
			(property "Voltage" ""
				(at 20.32 -27.94 0)
				(effects
					(font
						(size 1.27 1.27)
					)
					(justify left bottom)
					(hide yes)
				)
			)
			(property "Dielectric" ""
				(at 20.32 -30.48 0)
				(effects
					(font
						(size 1.27 1.27)
					)
					(justify left bottom)
					(hide yes)
				)
			)
			(property "ki_keywords" "0402, SMT, CAPACITOR, PASSIVE, MLCC, CERAMIC"
				(at 0 0 0)
				(effects
					(font
						(size 1.27 1.27)
					)
					(hide yes)
				)
			)
			(symbol "C_10u_0402_0_1"
				(polyline
					(pts
						(xy 2.032 -1.524) (xy 2.032 1.524)
					)
					(stroke
						(width 0.3048)
						(type default)
					)
					(fill
						(type none)
					)
				)
				(polyline
					(pts
						(xy 3.048 -1.524) (xy 3.048 1.524)
					)
					(stroke
						(width 0.3302)
						(type default)
					)
					(fill
						(type none)
					)
				)
			)
			(symbol "C_10u_0402_1_1"
				(pin passive line
					(at 0 0 0)
					(length 2.032)
					(name "~"
						(effects
							(font
								(size 1.27 1.27)
							)
						)
					)
					(number "1"
						(effects
							(font
								(size 1.27 1.27)
							)
						)
					)
				)
				(pin passive line
					(at 5.08 0 180)
					(length 2.032)
					(name "~"
						(effects
							(font
								(size 1.27 1.27)
							)
						)
					)
					(number "2"
						(effects
							(font
								(size 1.27 1.27)
							)
						)
					)
				)
			)
		)
	(symbol "antmicroCapacitors0402:C_1n_0402"
			(pin_numbers
				(hide yes)
			)
			(pin_names
				(hide yes)
			)
			(exclude_from_sim no)
			(in_bom yes)
			(on_board yes)
			(property "Reference" "C"
				(at 20.32 -5.08 0)
				(effects
					(font
						(size 1.27 1.27)
						(thickness 0.15)
					)
					(justify left bottom)
				)
			)
			(property "Value" "C_1n_0402"
				(at 20.32 -10.16 0)
				(effects
					(font
						(size 1.27 1.27)
						(thickness 0.15)
					)
					(justify left bottom)
					(hide yes)
				)
			)
			(property "Footprint" "antmicro-footprints:C_0402_1005Metric"
				(at 20.32 -12.7 0)
				(effects
					(font
						(size 1.27 1.27)
						(thickness 0.15)
					)
					(justify left bottom)
					(hide yes)
				)
			)
			(property "Datasheet" "https://www.murata.com/products/productdetail?partno=GRM1555C1H102JA01%23"
				(at 20.32 -15.24 0)
				(effects
					(font
						(size 1.27 1.27)
						(thickness 0.15)
					)
					(justify left bottom)
					(hide yes)
				)
			)
			(property "Description" "SMD Multilayer Ceramic Capacitor, 1000 pF, 50 V, 0402 [1005 Metric], ± 5%, C0G / NP0, GRM Series"
				(at 0 0 0)
				(effects
					(font
						(size 1.27 1.27)
					)
					(hide yes)
				)
			)
			(property "MPN" "GRM1555C1H102JA01D"
				(at 20.32 -17.78 0)
				(effects
					(font
						(size 1.27 1.27)
						(thickness 0.15)
					)
					(justify left bottom)
					(hide yes)
				)
			)
			(property "Manufacturer" "Murata"
				(at 20.32 -20.32 0)
				(effects
					(font
						(size 1.27 1.27)
						(thickness 0.15)
					)
					(justify left bottom)
					(hide yes)
				)
			)
			(property "License" "Apache-2.0"
				(at 20.32 -22.86 0)
				(effects
					(font
						(size 1.27 1.27)
						(thickness 0.15)
					)
					(justify left bottom)
					(hide yes)
				)
			)
			(property "Author" "Antmicro"
				(at 20.32 -25.4 0)
				(effects
					(font
						(size 1.27 1.27)
						(thickness 0.15)
					)
					(justify left bottom)
					(hide yes)
				)
			)
			(property "Val" "1n"
				(at 20.32 -7.62 0)
				(effects
					(font
						(size 1.27 1.27)
						(thickness 0.15)
					)
					(justify left bottom)
				)
			)
			(property "Voltage" "50V"
				(at 20.32 -27.94 0)
				(effects
					(font
						(size 1.27 1.27)
					)
					(justify left bottom)
					(hide yes)
				)
			)
			(property "Dielectric" "C0G"
				(at 20.32 -30.48 0)
				(effects
					(font
						(size 1.27 1.27)
					)
					(justify left bottom)
					(hide yes)
				)
			)
			(property "ki_keywords" "0402, SMT, CAPACITOR, PASSIVE, CERAMIC, MLCC"
				(at 0 0 0)
				(effects
					(font
						(size 1.27 1.27)
					)
					(hide yes)
				)
			)
			(symbol "C_1n_0402_0_1"
				(polyline
					(pts
						(xy 2.032 -1.524) (xy 2.032 1.524)
					)
					(stroke
						(width 0.3048)
						(type default)
					)
					(fill
						(type none)
					)
				)
				(polyline
					(pts
						(xy 3.048 -1.524) (xy 3.048 1.524)
					)
					(stroke
						(width 0.3302)
						(type default)
					)
					(fill
						(type none)
					)
				)
			)
			(symbol "C_1n_0402_1_1"
				(pin passive line
					(at 0 0 0)
					(length 2.032)
					(name "~"
						(effects
							(font
								(size 1.27 1.27)
							)
						)
					)
					(number "1"
						(effects
							(font
								(size 1.27 1.27)
							)
						)
					)
				)
				(pin passive line
					(at 5.08 0 180)
					(length 2.032)
					(name "~"
						(effects
							(font
								(size 1.27 1.27)
							)
						)
					)
					(number "2"
						(effects
							(font
								(size 1.27 1.27)
							)
						)
					)
				)
			)
		)
	(symbol "antmicroCapacitors0402:C_1u_0402"
			(pin_numbers
				(hide yes)
			)
			(pin_names
				(hide yes)
			)
			(exclude_from_sim no)
			(in_bom yes)
			(on_board yes)
			(property "Reference" "C"
				(at 20.32 -5.08 0)
				(effects
					(font
						(size 1.27 1.27)
						(thickness 0.15)
					)
					(justify left bottom)
				)
			)
			(property "Value" "C_1u_0402"
				(at 20.32 -10.16 0)
				(effects
					(font
						(size 1.27 1.27)
						(thickness 0.15)
					)
					(justify left bottom)
					(hide yes)
				)
			)
			(property "Footprint" "antmicro-footprints:C_0402_1005Metric"
				(at 20.32 -12.7 0)
				(effects
					(font
						(size 1.27 1.27)
						(thickness 0.15)
					)
					(justify left bottom)
					(hide yes)
				)
			)
			(property "Datasheet" "https://product.tdk.com/en/search/capacitor/ceramic/mlcc/info?part_no=C1005X6S1A105K050BC"
				(at 20.32 -15.24 0)
				(effects
					(font
						(size 1.27 1.27)
						(thickness 0.15)
					)
					(justify left bottom)
					(hide yes)
				)
			)
			(property "Description" "SMD Multilayer Ceramic Capacitor, 1 µF, 10 V, 0402 [1005 Metric], ± 10%, X6S, C"
				(at 0 0 0)
				(effects
					(font
						(size 1.27 1.27)
					)
					(hide yes)
				)
			)
			(property "MPN" "C1005X6S1A105K050BC"
				(at 20.32 -17.78 0)
				(effects
					(font
						(size 1.27 1.27)
						(thickness 0.15)
					)
					(justify left bottom)
					(hide yes)
				)
			)
			(property "Manufacturer" "TDK"
				(at 20.32 -20.32 0)
				(effects
					(font
						(size 1.27 1.27)
						(thickness 0.15)
					)
					(justify left bottom)
					(hide yes)
				)
			)
			(property "License" "Apache-2.0"
				(at 20.32 -22.86 0)
				(effects
					(font
						(size 1.27 1.27)
						(thickness 0.15)
					)
					(justify left bottom)
					(hide yes)
				)
			)
			(property "Author" "Antmicro"
				(at 20.32 -25.4 0)
				(effects
					(font
						(size 1.27 1.27)
						(thickness 0.15)
					)
					(justify left bottom)
					(hide yes)
				)
			)
			(property "Val" "1u"
				(at 20.32 -7.62 0)
				(effects
					(font
						(size 1.27 1.27)
						(thickness 0.15)
					)
					(justify left bottom)
				)
			)
			(property "Voltage" ""
				(at 20.32 -27.94 0)
				(effects
					(font
						(size 1.27 1.27)
					)
					(justify left bottom)
					(hide yes)
				)
			)
			(property "Dielectric" ""
				(at 20.32 -30.48 0)
				(effects
					(font
						(size 1.27 1.27)
					)
					(justify left bottom)
					(hide yes)
				)
			)
			(property "ki_keywords" "0402, SMT, CAPACITOR, PASSIVE, CERAMIC, MLCC"
				(at 0 0 0)
				(effects
					(font
						(size 1.27 1.27)
					)
					(hide yes)
				)
			)
			(symbol "C_1u_0402_0_1"
				(polyline
					(pts
						(xy 2.032 -1.524) (xy 2.032 1.524)
					)
					(stroke
						(width 0.3048)
						(type default)
					)
					(fill
						(type none)
					)
				)
				(polyline
					(pts
						(xy 3.048 -1.524) (xy 3.048 1.524)
					)
					(stroke
						(width 0.3302)
						(type default)
					)
					(fill
						(type none)
					)
				)
			)
			(symbol "C_1u_0402_1_1"
				(pin passive line
					(at 0 0 0)
					(length 2.032)
					(name "~"
						(effects
							(font
								(size 1.27 1.27)
							)
						)
					)
					(number "1"
						(effects
							(font
								(size 1.27 1.27)
							)
						)
					)
				)
				(pin passive line
					(at 5.08 0 180)
					(length 2.032)
					(name "~"
						(effects
							(font
								(size 1.27 1.27)
							)
						)
					)
					(number "2"
						(effects
							(font
								(size 1.27 1.27)
							)
						)
					)
				)
			)
		)
	(symbol "antmicroCapacitors0402:C_22n_0402"
			(pin_numbers
				(hide yes)
			)
			(pin_names
				(hide yes)
			)
			(exclude_from_sim no)
			(in_bom yes)
			(on_board yes)
			(property "Reference" "C"
				(at 20.32 -5.08 0)
				(effects
					(font
						(size 1.27 1.27)
						(thickness 0.15)
					)
					(justify left bottom)
				)
			)
			(property "Value" "C_22n_0402"
				(at 20.32 -10.16 0)
				(effects
					(font
						(size 1.27 1.27)
						(thickness 0.15)
					)
					(justify left bottom)
					(hide yes)
				)
			)
			(property "Footprint" "antmicro-footprints:C_0402_1005Metric"
				(at 20.32 -12.7 0)
				(effects
					(font
						(size 1.27 1.27)
						(thickness 0.15)
					)
					(justify left bottom)
					(hide yes)
				)
			)
			(property "Datasheet" "https://www.murata.com/products/productdetail?partno=GCM155R71H223MA55%23"
				(at 20.32 -15.24 0)
				(effects
					(font
						(size 1.27 1.27)
						(thickness 0.15)
					)
					(justify left bottom)
					(hide yes)
				)
			)
			(property "Description" "SMD Multilayer Ceramic Capacitors, 0.022 µF, 50 V, 20%, 0402 [1005 Metric], X7R"
				(at 0 0 0)
				(effects
					(font
						(size 1.27 1.27)
					)
					(hide yes)
				)
			)
			(property "MPN" "GCM155R71H223MA55D"
				(at 20.32 -17.78 0)
				(effects
					(font
						(size 1.27 1.27)
						(thickness 0.15)
					)
					(justify left bottom)
					(hide yes)
				)
			)
			(property "Manufacturer" "Murata"
				(at 20.32 -20.32 0)
				(effects
					(font
						(size 1.27 1.27)
						(thickness 0.15)
					)
					(justify left bottom)
					(hide yes)
				)
			)
			(property "License" "Apache-2.0"
				(at 20.32 -22.86 0)
				(effects
					(font
						(size 1.27 1.27)
						(thickness 0.15)
					)
					(justify left bottom)
					(hide yes)
				)
			)
			(property "Author" "Antmicro"
				(at 20.32 -25.4 0)
				(effects
					(font
						(size 1.27 1.27)
						(thickness 0.15)
					)
					(justify left bottom)
					(hide yes)
				)
			)
			(property "Val" "22n"
				(at 20.32 -7.62 0)
				(effects
					(font
						(size 1.27 1.27)
						(thickness 0.15)
					)
					(justify left bottom)
				)
			)
			(property "Voltage" ""
				(at 20.32 -27.94 0)
				(effects
					(font
						(size 1.27 1.27)
					)
					(justify left bottom)
					(hide yes)
				)
			)
			(property "Dielectric" ""
				(at 20.32 -30.48 0)
				(effects
					(font
						(size 1.27 1.27)
					)
					(justify left bottom)
					(hide yes)
				)
			)
			(property "ki_keywords" "0402, SMT, CAPACITOR, PASSIVE, CERAMIC, MLCC"
				(at 0 0 0)
				(effects
					(font
						(size 1.27 1.27)
					)
					(hide yes)
				)
			)
			(symbol "C_22n_0402_0_1"
				(polyline
					(pts
						(xy 2.032 -1.524) (xy 2.032 1.524)
					)
					(stroke
						(width 0.3048)
						(type default)
					)
					(fill
						(type none)
					)
				)
				(polyline
					(pts
						(xy 3.048 -1.524) (xy 3.048 1.524)
					)
					(stroke
						(width 0.3302)
						(type default)
					)
					(fill
						(type none)
					)
				)
			)
			(symbol "C_22n_0402_1_1"
				(pin passive line
					(at 0 0 0)
					(length 2.032)
					(name "~"
						(effects
							(font
								(size 1.27 1.27)
							)
						)
					)
					(number "1"
						(effects
							(font
								(size 1.27 1.27)
							)
						)
					)
				)
				(pin passive line
					(at 5.08 0 180)
					(length 2.032)
					(name "~"
						(effects
							(font
								(size 1.27 1.27)
							)
						)
					)
					(number "2"
						(effects
							(font
								(size 1.27 1.27)
							)
						)
					)
				)
			)
		)
	(symbol "antmicroCapacitors0402:C_22p_0402"
			(pin_numbers
				(hide yes)
			)
			(pin_names
				(hide yes)
			)
			(exclude_from_sim no)
			(in_bom yes)
			(on_board yes)
			(property "Reference" "C"
				(at 20.32 -5.08 0)
				(effects
					(font
						(size 1.27 1.27)
						(thickness 0.15)
					)
					(justify left bottom)
				)
			)
			(property "Value" "C_22p_0402"
				(at 20.32 -10.16 0)
				(effects
					(font
						(size 1.27 1.27)
						(thickness 0.15)
					)
					(justify left bottom)
					(hide yes)
				)
			)
			(property "Footprint" "antmicro-footprints:C_0402_1005Metric"
				(at 20.32 -12.7 0)
				(effects
					(font
						(size 1.27 1.27)
						(thickness 0.15)
					)
					(justify left bottom)
					(hide yes)
				)
			)
			(property "Datasheet" "https://www.yageo.com/en/Chart/Download/pdf/CC0402JRNPO9BN220"
				(at 20.32 -15.24 0)
				(effects
					(font
						(size 1.27 1.27)
						(thickness 0.15)
					)
					(justify left bottom)
					(hide yes)
				)
			)
			(property "Description" "SMD Multilayer Ceramic Capacitor, 22 pF, 50 V, 0402 [1005 Metric], ± 5%, C0G / NP0, CC Series"
				(at 0 0 0)
				(effects
					(font
						(size 1.27 1.27)
					)
					(hide yes)
				)
			)
			(property "MPN" "CC0402JRNPO9BN220"
				(at 20.32 -17.78 0)
				(effects
					(font
						(size 1.27 1.27)
						(thickness 0.15)
					)
					(justify left bottom)
					(hide yes)
				)
			)
			(property "Manufacturer" "YAGEO"
				(at 20.32 -20.32 0)
				(effects
					(font
						(size 1.27 1.27)
						(thickness 0.15)
					)
					(justify left bottom)
					(hide yes)
				)
			)
			(property "License" "Apache-2.0"
				(at 20.32 -22.86 0)
				(effects
					(font
						(size 1.27 1.27)
						(thickness 0.15)
					)
					(justify left bottom)
					(hide yes)
				)
			)
			(property "Author" "Antmicro"
				(at 20.32 -25.4 0)
				(effects
					(font
						(size 1.27 1.27)
						(thickness 0.15)
					)
					(justify left bottom)
					(hide yes)
				)
			)
			(property "Val" "22p"
				(at 20.32 -7.62 0)
				(effects
					(font
						(size 1.27 1.27)
						(thickness 0.15)
					)
					(justify left bottom)
				)
			)
			(property "Voltage" ""
				(at 20.32 -27.94 0)
				(effects
					(font
						(size 1.27 1.27)
					)
					(justify left bottom)
					(hide yes)
				)
			)
			(property "Dielectric" ""
				(at 20.32 -30.48 0)
				(effects
					(font
						(size 1.27 1.27)
					)
					(justify left bottom)
					(hide yes)
				)
			)
			(property "ki_keywords" "0402, SMT, CAPACITOR, PASSIVE, MLCC, CERAMIC"
				(at 0 0 0)
				(effects
					(font
						(size 1.27 1.27)
					)
					(hide yes)
				)
			)
			(symbol "C_22p_0402_0_1"
				(polyline
					(pts
						(xy 2.032 -1.524) (xy 2.032 1.524)
					)
					(stroke
						(width 0.3048)
						(type default)
					)
					(fill
						(type none)
					)
				)
				(polyline
					(pts
						(xy 3.048 -1.524) (xy 3.048 1.524)
					)
					(stroke
						(width 0.3302)
						(type default)
					)
					(fill
						(type none)
					)
				)
			)
			(symbol "C_22p_0402_1_1"
				(pin passive line
					(at 0 0 0)
					(length 2.032)
					(name "~"
						(effects
							(font
								(size 1.27 1.27)
							)
						)
					)
					(number "1"
						(effects
							(font
								(size 1.27 1.27)
							)
						)
					)
				)
				(pin passive line
					(at 5.08 0 180)
					(length 2.032)
					(name "~"
						(effects
							(font
								(size 1.27 1.27)
							)
						)
					)
					(number "2"
						(effects
							(font
								(size 1.27 1.27)
							)
						)
					)
				)
			)
		)
	(symbol "antmicroCapacitors0402:C_2n2_0402"
			(pin_numbers
				(hide yes)
			)
			(pin_names
				(hide yes)
			)
			(exclude_from_sim no)
			(in_bom yes)
			(on_board yes)
			(property "Reference" "C"
				(at 20.32 -5.08 0)
				(effects
					(font
						(size 1.27 1.27)
						(thickness 0.15)
					)
					(justify left bottom)
				)
			)
			(property "Value" "C_2n2_0402"
				(at 20.32 -10.16 0)
				(effects
					(font
						(size 1.27 1.27)
						(thickness 0.15)
					)
					(justify left bottom)
					(hide yes)
				)
			)
			(property "Footprint" "antmicro-footprints:C_0402_1005Metric"
				(at 20.32 -12.7 0)
				(effects
					(font
						(size 1.27 1.27)
						(thickness 0.15)
					)
					(justify left bottom)
					(hide yes)
				)
			)
			(property "Datasheet" "https://www.kemet.com/en/us/capacitors/product/C0402C222J5RACTU.html"
				(at 20.32 -15.24 0)
				(effects
					(font
						(size 1.27 1.27)
						(thickness 0.15)
					)
					(justify left bottom)
					(hide yes)
				)
			)
			(property "Description" "SMD Multilayer Ceramic Capacitor, 2200 pF, 50 V, 0402 [1005 Metric], ± 5%, X7R, C Series KEMET"
				(at 0 0 0)
				(effects
					(font
						(size 1.27 1.27)
					)
					(hide yes)
				)
			)
			(property "MPN" "C0402C222J5RACTU"
				(at 20.32 -17.78 0)
				(effects
					(font
						(size 1.27 1.27)
						(thickness 0.15)
					)
					(justify left bottom)
					(hide yes)
				)
			)
			(property "Manufacturer" "KEMET"
				(at 20.32 -20.32 0)
				(effects
					(font
						(size 1.27 1.27)
						(thickness 0.15)
					)
					(justify left bottom)
					(hide yes)
				)
			)
			(property "License" "Apache-2.0"
				(at 20.32 -22.86 0)
				(effects
					(font
						(size 1.27 1.27)
						(thickness 0.15)
					)
					(justify left bottom)
					(hide yes)
				)
			)
			(property "Author" "Antmicro"
				(at 20.32 -25.4 0)
				(effects
					(font
						(size 1.27 1.27)
						(thickness 0.15)
					)
					(justify left bottom)
					(hide yes)
				)
			)
			(property "Val" "2n2"
				(at 20.32 -7.62 0)
				(effects
					(font
						(size 1.27 1.27)
						(thickness 0.15)
					)
					(justify left bottom)
				)
			)
			(property "Voltage" ""
				(at 20.32 -27.94 0)
				(effects
					(font
						(size 1.27 1.27)
					)
					(justify left bottom)
					(hide yes)
				)
			)
			(property "Dielectric" ""
				(at 20.32 -30.48 0)
				(effects
					(font
						(size 1.27 1.27)
					)
					(justify left bottom)
					(hide yes)
				)
			)
			(symbol "C_2n2_0402_0_1"
				(polyline
					(pts
						(xy 2.032 -1.524) (xy 2.032 1.524)
					)
					(stroke
						(width 0.3048)
						(type default)
					)
					(fill
						(type none)
					)
				)
				(polyline
					(pts
						(xy 3.048 -1.524) (xy 3.048 1.524)
					)
					(stroke
						(width 0.3302)
						(type default)
					)
					(fill
						(type none)
					)
				)
			)
			(symbol "C_2n2_0402_1_1"
				(pin passive line
					(at 0 0 0)
					(length 2.032)
					(name "~"
						(effects
							(font
								(size 1.27 1.27)
							)
						)
					)
					(number "1"
						(effects
							(font
								(size 1.27 1.27)
							)
						)
					)
				)
				(pin passive line
					(at 5.08 0 180)
					(length 2.032)
					(name "~"
						(effects
							(font
								(size 1.27 1.27)
							)
						)
					)
					(number "2"
						(effects
							(font
								(size 1.27 1.27)
							)
						)
					)
				)
			)
		)
	(symbol "antmicroCapacitors0402:C_470n_0402"
			(pin_numbers
				(hide yes)
			)
			(pin_names
				(hide yes)
			)
			(exclude_from_sim no)
			(in_bom yes)
			(on_board yes)
			(property "Reference" "C"
				(at 20.32 -5.08 0)
				(effects
					(font
						(size 1.27 1.27)
						(thickness 0.15)
					)
					(justify left bottom)
				)
			)
			(property "Value" "C_470n_0402"
				(at 20.32 -10.16 0)
				(effects
					(font
						(size 1.27 1.27)
						(thickness 0.15)
					)
					(justify left bottom)
					(hide yes)
				)
			)
			(property "Footprint" "antmicro-footprints:C_0402_1005Metric"
				(at 20.32 -12.7 0)
				(effects
					(font
						(size 1.27 1.27)
						(thickness 0.15)
					)
					(justify left bottom)
					(hide yes)
				)
			)
			(property "Datasheet" "https://product.tdk.com/en/search/capacitor/ceramic/mlcc/info?part_no=C1005X5R1E474M050BB"
				(at 20.32 -15.24 0)
				(effects
					(font
						(size 1.27 1.27)
						(thickness 0.15)
					)
					(justify left bottom)
					(hide yes)
				)
			)
			(property "Description" "SMD Multilayer Ceramic Capacitor, 0.47 µF, 25 V, 0402 [1005 Metric], ± 20%, X5R, C"
				(at 0 0 0)
				(effects
					(font
						(size 1.27 1.27)
					)
					(hide yes)
				)
			)
			(property "MPN" "C1005X5R1E474M050BB"
				(at 20.32 -17.78 0)
				(effects
					(font
						(size 1.27 1.27)
						(thickness 0.15)
					)
					(justify left bottom)
					(hide yes)
				)
			)
			(property "Manufacturer" "TDK"
				(at 20.32 -20.32 0)
				(effects
					(font
						(size 1.27 1.27)
						(thickness 0.15)
					)
					(justify left bottom)
					(hide yes)
				)
			)
			(property "License" "Apache-2.0"
				(at 20.32 -22.86 0)
				(effects
					(font
						(size 1.27 1.27)
						(thickness 0.15)
					)
					(justify left bottom)
					(hide yes)
				)
			)
			(property "Author" "Antmicro"
				(at 20.32 -25.4 0)
				(effects
					(font
						(size 1.27 1.27)
						(thickness 0.15)
					)
					(justify left bottom)
					(hide yes)
				)
			)
			(property "Val" "470n"
				(at 20.32 -7.62 0)
				(effects
					(font
						(size 1.27 1.27)
						(thickness 0.15)
					)
					(justify left bottom)
				)
			)
			(property "Voltage" ""
				(at 20.32 -27.94 0)
				(effects
					(font
						(size 1.27 1.27)
					)
					(justify left bottom)
					(hide yes)
				)
			)
			(property "Dielectric" ""
				(at 20.32 -30.48 0)
				(effects
					(font
						(size 1.27 1.27)
					)
					(justify left bottom)
					(hide yes)
				)
			)
			(property "ki_keywords" "0402, SMT, CAPACITOR, PASSIVE, CERAMIC, MLCC"
				(at 0 0 0)
				(effects
					(font
						(size 1.27 1.27)
					)
					(hide yes)
				)
			)
			(symbol "C_470n_0402_0_1"
				(polyline
					(pts
						(xy 2.032 -1.524) (xy 2.032 1.524)
					)
					(stroke
						(width 0.3048)
						(type default)
					)
					(fill
						(type none)
					)
				)
				(polyline
					(pts
						(xy 3.048 -1.524) (xy 3.048 1.524)
					)
					(stroke
						(width 0.3302)
						(type default)
					)
					(fill
						(type none)
					)
				)
			)
			(symbol "C_470n_0402_1_1"
				(pin passive line
					(at 0 0 0)
					(length 2.032)
					(name "~"
						(effects
							(font
								(size 1.27 1.27)
							)
						)
					)
					(number "1"
						(effects
							(font
								(size 1.27 1.27)
							)
						)
					)
				)
				(pin passive line
					(at 5.08 0 180)
					(length 2.032)
					(name "~"
						(effects
							(font
								(size 1.27 1.27)
							)
						)
					)
					(number "2"
						(effects
							(font
								(size 1.27 1.27)
							)
						)
					)
				)
			)
		)
	(symbol "antmicroCapacitors0603:C_10u_25V_0603"
			(pin_numbers
				(hide yes)
			)
			(pin_names
				(hide yes)
			)
			(exclude_from_sim no)
			(in_bom yes)
			(on_board yes)
			(property "Reference" "C"
				(at 20.32 -5.08 0)
				(effects
					(font
						(size 1.27 1.27)
						(thickness 0.15)
					)
					(justify left bottom)
				)
			)
			(property "Value" "C_10u_25V_0603"
				(at 20.32 -10.16 0)
				(effects
					(font
						(size 1.27 1.27)
						(thickness 0.15)
					)
					(justify left bottom)
					(hide yes)
				)
			)
			(property "Footprint" "antmicro-footprints:C_0603_1608Metric"
				(at 20.32 -12.7 0)
				(effects
					(font
						(size 1.27 1.27)
						(thickness 0.15)
					)
					(justify left bottom)
					(hide yes)
				)
			)
			(property "Datasheet" "https://product.tdk.com/en/search/capacitor/ceramic/mlcc/info?part_no=C1608X5R1E106M080AC"
				(at 20.32 -15.24 0)
				(effects
					(font
						(size 1.27 1.27)
						(thickness 0.15)
					)
					(justify left bottom)
					(hide yes)
				)
			)
			(property "Description" "SMD Multilayer Ceramic Capacitor, 10 µF, 25 V, 0603 [1608 Metric], ± 20%, X5R, C"
				(at 0 0 0)
				(effects
					(font
						(size 1.27 1.27)
					)
					(hide yes)
				)
			)
			(property "MPN" "C1608X5R1E106M080AC"
				(at 20.32 -17.78 0)
				(effects
					(font
						(size 1.27 1.27)
						(thickness 0.15)
					)
					(justify left bottom)
					(hide yes)
				)
			)
			(property "Manufacturer" "TDK"
				(at 20.32 -20.32 0)
				(effects
					(font
						(size 1.27 1.27)
						(thickness 0.15)
					)
					(justify left bottom)
					(hide yes)
				)
			)
			(property "License" "Apache-2.0"
				(at 20.32 -22.86 0)
				(effects
					(font
						(size 1.27 1.27)
						(thickness 0.15)
					)
					(justify left bottom)
					(hide yes)
				)
			)
			(property "Author" "Antmicro"
				(at 20.32 -25.4 0)
				(effects
					(font
						(size 1.27 1.27)
						(thickness 0.15)
					)
					(justify left bottom)
					(hide yes)
				)
			)
			(property "Val" "10u"
				(at 20.32 -7.62 0)
				(effects
					(font
						(size 1.27 1.27)
						(thickness 0.15)
					)
					(justify left bottom)
				)
			)
			(property "Voltage" "25V"
				(at 20.32 -27.94 0)
				(effects
					(font
						(size 1.27 1.27)
					)
					(justify left bottom)
					(hide yes)
				)
			)
			(property "Dielectric" ""
				(at 20.32 -30.48 0)
				(effects
					(font
						(size 1.27 1.27)
					)
					(justify left bottom)
					(hide yes)
				)
			)
			(property "ki_keywords" "0603, SMT, CAPACITOR, PASSIVE, CERAMIC, MLCC"
				(at 0 0 0)
				(effects
					(font
						(size 1.27 1.27)
					)
					(hide yes)
				)
			)
			(symbol "C_10u_25V_0603_0_1"
				(polyline
					(pts
						(xy 2.032 -1.524) (xy 2.032 1.524)
					)
					(stroke
						(width 0.3048)
						(type default)
					)
					(fill
						(type none)
					)
				)
				(polyline
					(pts
						(xy 3.048 -1.524) (xy 3.048 1.524)
					)
					(stroke
						(width 0.3302)
						(type default)
					)
					(fill
						(type none)
					)
				)
			)
			(symbol "C_10u_25V_0603_1_1"
				(pin passive line
					(at 0 0 0)
					(length 2.032)
					(name "~"
						(effects
							(font
								(size 1.27 1.27)
							)
						)
					)
					(number "1"
						(effects
							(font
								(size 1.27 1.27)
							)
						)
					)
				)
				(pin passive line
					(at 5.08 0 180)
					(length 2.032)
					(name "~"
						(effects
							(font
								(size 1.27 1.27)
							)
						)
					)
					(number "2"
						(effects
							(font
								(size 1.27 1.27)
							)
						)
					)
				)
			)
		)
	(symbol "antmicroCapacitors0603:C_1u_25V_0603"
			(pin_numbers
				(hide yes)
			)
			(pin_names
				(hide yes)
			)
			(exclude_from_sim no)
			(in_bom yes)
			(on_board yes)
			(property "Reference" "C"
				(at 20.32 -5.08 0)
				(effects
					(font
						(size 1.27 1.27)
						(thickness 0.15)
					)
					(justify left bottom)
				)
			)
			(property "Value" "C_1u_25V_0603"
				(at 20.32 -10.16 0)
				(effects
					(font
						(size 1.27 1.27)
						(thickness 0.15)
					)
					(justify left bottom)
					(hide yes)
				)
			)
			(property "Footprint" "antmicro-footprints:C_0603_1608Metric"
				(at 20.32 -12.7 0)
				(effects
					(font
						(size 1.27 1.27)
						(thickness 0.15)
					)
					(justify left bottom)
					(hide yes)
				)
			)
			(property "Datasheet" "https://product.samsungsem.com/mlcc/CL10A105KA8NNN.do"
				(at 20.32 -15.24 0)
				(effects
					(font
						(size 1.27 1.27)
						(thickness 0.15)
					)
					(justify left bottom)
					(hide yes)
				)
			)
			(property "Description" "SMD Multilayer Ceramic Capacitor, 1 µF, 25 V, 0603 [1608 Metric], ± 10%, X5R, CL"
				(at 0 0 0)
				(effects
					(font
						(size 1.27 1.27)
					)
					(hide yes)
				)
			)
			(property "MPN" "CL10A105KA8NNNC"
				(at 20.32 -17.78 0)
				(effects
					(font
						(size 1.27 1.27)
						(thickness 0.15)
					)
					(justify left bottom)
					(hide yes)
				)
			)
			(property "Manufacturer" "Samsung Electro-Mechanics"
				(at 20.32 -20.32 0)
				(effects
					(font
						(size 1.27 1.27)
						(thickness 0.15)
					)
					(justify left bottom)
					(hide yes)
				)
			)
			(property "License" "Apache-2.0"
				(at 20.32 -22.86 0)
				(effects
					(font
						(size 1.27 1.27)
						(thickness 0.15)
					)
					(justify left bottom)
					(hide yes)
				)
			)
			(property "Author" "Antmicro"
				(at 20.32 -25.4 0)
				(effects
					(font
						(size 1.27 1.27)
						(thickness 0.15)
					)
					(justify left bottom)
					(hide yes)
				)
			)
			(property "Val" "1u"
				(at 20.32 -7.62 0)
				(effects
					(font
						(size 1.27 1.27)
						(thickness 0.15)
					)
					(justify left bottom)
				)
			)
			(property "Voltage" "25V"
				(at 20.32 -27.94 0)
				(effects
					(font
						(size 1.27 1.27)
					)
					(justify left bottom)
					(hide yes)
				)
			)
			(property "Dielectric" ""
				(at 20.32 -30.48 0)
				(effects
					(font
						(size 1.27 1.27)
					)
					(justify left bottom)
					(hide yes)
				)
			)
			(property "ki_keywords" "0603, SMT, CAPACITOR, PASSIVE, CERAMIC"
				(at 0 0 0)
				(effects
					(font
						(size 1.27 1.27)
					)
					(hide yes)
				)
			)
			(symbol "C_1u_25V_0603_0_1"
				(polyline
					(pts
						(xy 2.032 -1.524) (xy 2.032 1.524)
					)
					(stroke
						(width 0.3048)
						(type default)
					)
					(fill
						(type none)
					)
				)
				(polyline
					(pts
						(xy 3.048 -1.524) (xy 3.048 1.524)
					)
					(stroke
						(width 0.3302)
						(type default)
					)
					(fill
						(type none)
					)
				)
			)
			(symbol "C_1u_25V_0603_1_1"
				(pin passive line
					(at 0 0 0)
					(length 2.032)
					(name "~"
						(effects
							(font
								(size 1.27 1.27)
							)
						)
					)
					(number "1"
						(effects
							(font
								(size 1.27 1.27)
							)
						)
					)
				)
				(pin passive line
					(at 5.08 0 180)
					(length 2.032)
					(name "~"
						(effects
							(font
								(size 1.27 1.27)
							)
						)
					)
					(number "2"
						(effects
							(font
								(size 1.27 1.27)
							)
						)
					)
				)
			)
		)
	(symbol "antmicroCapacitors0603:C_22u_0603"
			(pin_numbers
				(hide yes)
			)
			(pin_names
				(hide yes)
			)
			(exclude_from_sim no)
			(in_bom yes)
			(on_board yes)
			(property "Reference" "C"
				(at 20.32 -5.08 0)
				(effects
					(font
						(size 1.27 1.27)
						(thickness 0.15)
					)
					(justify left bottom)
				)
			)
			(property "Value" "C_22u_0603"
				(at 20.32 -10.16 0)
				(effects
					(font
						(size 1.27 1.27)
						(thickness 0.15)
					)
					(justify left bottom)
					(hide yes)
				)
			)
			(property "Footprint" "antmicro-footprints:C_0603_1608Metric"
				(at 20.32 -12.7 0)
				(effects
					(font
						(size 1.27 1.27)
						(thickness 0.15)
					)
					(justify left bottom)
					(hide yes)
				)
			)
			(property "Datasheet" "https://www.murata.com/products/productdetail?partno=GRM188R60J226MEA0%23"
				(at 20.32 -15.24 0)
				(effects
					(font
						(size 1.27 1.27)
						(thickness 0.15)
					)
					(justify left bottom)
					(hide yes)
				)
			)
			(property "Description" "SMD Multilayer Ceramic Capacitor, 22 µF, 6.3 V, 0603 [1608 Metric], ± 20%, X5R, GRM Series"
				(at 0 0 0)
				(effects
					(font
						(size 1.27 1.27)
					)
					(hide yes)
				)
			)
			(property "MPN" "GRM188R60J226MEA0D"
				(at 20.32 -17.78 0)
				(effects
					(font
						(size 1.27 1.27)
						(thickness 0.15)
					)
					(justify left bottom)
					(hide yes)
				)
			)
			(property "Manufacturer" "Murata"
				(at 20.32 -20.32 0)
				(effects
					(font
						(size 1.27 1.27)
						(thickness 0.15)
					)
					(justify left bottom)
					(hide yes)
				)
			)
			(property "License" "Apache-2.0"
				(at 20.32 -22.86 0)
				(effects
					(font
						(size 1.27 1.27)
						(thickness 0.15)
					)
					(justify left bottom)
					(hide yes)
				)
			)
			(property "Author" "Antmicro"
				(at 20.32 -25.4 0)
				(effects
					(font
						(size 1.27 1.27)
						(thickness 0.15)
					)
					(justify left bottom)
					(hide yes)
				)
			)
			(property "Val" "22u"
				(at 20.32 -7.62 0)
				(effects
					(font
						(size 1.27 1.27)
						(thickness 0.15)
					)
					(justify left bottom)
				)
			)
			(property "Voltage" ""
				(at 20.32 -27.94 0)
				(effects
					(font
						(size 1.27 1.27)
					)
					(justify left bottom)
					(hide yes)
				)
			)
			(property "Dielectric" ""
				(at 20.32 -30.48 0)
				(effects
					(font
						(size 1.27 1.27)
					)
					(justify left bottom)
					(hide yes)
				)
			)
			(property "ki_keywords" "0603, SMT, CAPACITOR, PASSIVE, CERAMIC, MLCC"
				(at 0 0 0)
				(effects
					(font
						(size 1.27 1.27)
					)
					(hide yes)
				)
			)
			(symbol "C_22u_0603_0_1"
				(polyline
					(pts
						(xy 2.032 -1.524) (xy 2.032 1.524)
					)
					(stroke
						(width 0.3048)
						(type default)
					)
					(fill
						(type none)
					)
				)
				(polyline
					(pts
						(xy 3.048 -1.524) (xy 3.048 1.524)
					)
					(stroke
						(width 0.3302)
						(type default)
					)
					(fill
						(type none)
					)
				)
			)
			(symbol "C_22u_0603_1_1"
				(pin passive line
					(at 0 0 0)
					(length 2.032)
					(name "~"
						(effects
							(font
								(size 1.27 1.27)
							)
						)
					)
					(number "1"
						(effects
							(font
								(size 1.27 1.27)
							)
						)
					)
				)
				(pin passive line
					(at 5.08 0 180)
					(length 2.032)
					(name "~"
						(effects
							(font
								(size 1.27 1.27)
							)
						)
					)
					(number "2"
						(effects
							(font
								(size 1.27 1.27)
							)
						)
					)
				)
			)
		)
	(symbol "antmicroCapacitors0603:C_47u_0603"
			(pin_numbers
				(hide yes)
			)
			(pin_names
				(hide yes)
			)
			(exclude_from_sim no)
			(in_bom yes)
			(on_board yes)
			(property "Reference" "C"
				(at 20.32 -5.08 0)
				(effects
					(font
						(size 1.27 1.27)
						(thickness 0.15)
					)
					(justify left bottom)
				)
			)
			(property "Value" "C_47u_0603"
				(at 20.32 -10.16 0)
				(effects
					(font
						(size 1.27 1.27)
						(thickness 0.15)
					)
					(justify left bottom)
					(hide yes)
				)
			)
			(property "Footprint" "antmicro-footprints:C_0603_1608Metric"
				(at 20.32 -12.7 0)
				(effects
					(font
						(size 1.27 1.27)
						(thickness 0.15)
					)
					(justify left bottom)
					(hide yes)
				)
			)
			(property "Datasheet" "https://www.murata.com/products/productdetail?partno=GRM188R60J476ME15%23"
				(at 20.32 -15.24 0)
				(effects
					(font
						(size 1.27 1.27)
						(thickness 0.15)
					)
					(justify left bottom)
					(hide yes)
				)
			)
			(property "Description" "SMD Multilayer Ceramic Capacitor, 47 µF, 6.3 V, 0603 [1608 Metric], ± 20%, X5R, GRM Series"
				(at 0 0 0)
				(effects
					(font
						(size 1.27 1.27)
					)
					(hide yes)
				)
			)
			(property "MPN" "GRM188R60J476ME15D"
				(at 20.32 -17.78 0)
				(effects
					(font
						(size 1.27 1.27)
						(thickness 0.15)
					)
					(justify left bottom)
					(hide yes)
				)
			)
			(property "Manufacturer" "Murata"
				(at 20.32 -20.32 0)
				(effects
					(font
						(size 1.27 1.27)
						(thickness 0.15)
					)
					(justify left bottom)
					(hide yes)
				)
			)
			(property "License" "Apache-2.0"
				(at 20.32 -22.86 0)
				(effects
					(font
						(size 1.27 1.27)
						(thickness 0.15)
					)
					(justify left bottom)
					(hide yes)
				)
			)
			(property "Author" "Antmicro"
				(at 20.32 -25.4 0)
				(effects
					(font
						(size 1.27 1.27)
						(thickness 0.15)
					)
					(justify left bottom)
					(hide yes)
				)
			)
			(property "Val" "47u"
				(at 20.32 -7.62 0)
				(effects
					(font
						(size 1.27 1.27)
						(thickness 0.15)
					)
					(justify left bottom)
				)
			)
			(property "Voltage" ""
				(at 20.32 -27.94 0)
				(effects
					(font
						(size 1.27 1.27)
					)
					(justify left bottom)
					(hide yes)
				)
			)
			(property "Dielectric" ""
				(at 20.32 -30.48 0)
				(effects
					(font
						(size 1.27 1.27)
					)
					(justify left bottom)
					(hide yes)
				)
			)
			(symbol "C_47u_0603_0_1"
				(polyline
					(pts
						(xy 2.032 -1.524) (xy 2.032 1.524)
					)
					(stroke
						(width 0.3048)
						(type default)
					)
					(fill
						(type none)
					)
				)
				(polyline
					(pts
						(xy 3.048 -1.524) (xy 3.048 1.524)
					)
					(stroke
						(width 0.3302)
						(type default)
					)
					(fill
						(type none)
					)
				)
			)
			(symbol "C_47u_0603_1_1"
				(pin passive line
					(at 0 0 0)
					(length 2.032)
					(name "~"
						(effects
							(font
								(size 1.27 1.27)
							)
						)
					)
					(number "1"
						(effects
							(font
								(size 1.27 1.27)
							)
						)
					)
				)
				(pin passive line
					(at 5.08 0 180)
					(length 2.032)
					(name "~"
						(effects
							(font
								(size 1.27 1.27)
							)
						)
					)
					(number "2"
						(effects
							(font
								(size 1.27 1.27)
							)
						)
					)
				)
			)
		)
	(symbol "antmicroCapacitorsmisc:C_100n_0201"
			(pin_numbers
				(hide yes)
			)
			(pin_names
				(hide yes)
			)
			(exclude_from_sim no)
			(in_bom yes)
			(on_board yes)
			(property "Reference" "C"
				(at 20.32 -5.08 0)
				(effects
					(font
						(size 1.27 1.27)
						(thickness 0.15)
					)
					(justify left bottom)
				)
			)
			(property "Value" "C_100n_0201"
				(at 20.32 -10.16 0)
				(effects
					(font
						(size 1.27 1.27)
						(thickness 0.15)
					)
					(justify left bottom)
					(hide yes)
				)
			)
			(property "Footprint" "antmicro-footprints:C_0201"
				(at 20.32 -12.7 0)
				(effects
					(font
						(size 1.27 1.27)
						(thickness 0.15)
					)
					(justify left bottom)
					(hide yes)
				)
			)
			(property "Datasheet" "https://www.yageo.com/en/Chart/Download/pdf/CC0201KRX6S5BB104"
				(at 20.32 -15.24 0)
				(effects
					(font
						(size 1.27 1.27)
						(thickness 0.15)
					)
					(justify left bottom)
					(hide yes)
				)
			)
			(property "Description" "SMD Multilayer Ceramic Capacitor, 0.1 µF, 6.3 V, 0201 [0603 Metric], ± 10%, X6S, CC Series"
				(at 0 0 0)
				(effects
					(font
						(size 1.27 1.27)
					)
					(hide yes)
				)
			)
			(property "MPN" "CC0201KRX6S5BB104"
				(at 20.32 -17.78 0)
				(effects
					(font
						(size 1.27 1.27)
						(thickness 0.15)
					)
					(justify left bottom)
					(hide yes)
				)
			)
			(property "Manufacturer" "YAGEO"
				(at 20.32 -20.32 0)
				(effects
					(font
						(size 1.27 1.27)
						(thickness 0.15)
					)
					(justify left bottom)
					(hide yes)
				)
			)
			(property "License" "Apache-2.0"
				(at 20.32 -22.86 0)
				(effects
					(font
						(size 1.27 1.27)
						(thickness 0.15)
					)
					(justify left bottom)
					(hide yes)
				)
			)
			(property "Author" "Antmicro"
				(at 20.32 -25.4 0)
				(effects
					(font
						(size 1.27 1.27)
						(thickness 0.15)
					)
					(justify left bottom)
					(hide yes)
				)
			)
			(property "Val" "100n"
				(at 20.32 -7.62 0)
				(effects
					(font
						(size 1.27 1.27)
						(thickness 0.15)
					)
					(justify left bottom)
				)
			)
			(property "Voltage" ""
				(at 20.32 -27.94 0)
				(effects
					(font
						(size 1.27 1.27)
					)
					(justify left bottom)
					(hide yes)
				)
			)
			(property "Dielectric" ""
				(at 20.32 -30.48 0)
				(effects
					(font
						(size 1.27 1.27)
					)
					(justify left bottom)
					(hide yes)
				)
			)
			(symbol "C_100n_0201_0_1"
				(polyline
					(pts
						(xy 2.032 -1.524) (xy 2.032 1.524)
					)
					(stroke
						(width 0.3048)
						(type default)
					)
					(fill
						(type none)
					)
				)
				(polyline
					(pts
						(xy 3.048 -1.524) (xy 3.048 1.524)
					)
					(stroke
						(width 0.3302)
						(type default)
					)
					(fill
						(type none)
					)
				)
			)
			(symbol "C_100n_0201_1_1"
				(pin passive line
					(at 0 0 0)
					(length 2.032)
					(name "~"
						(effects
							(font
								(size 1.27 1.27)
							)
						)
					)
					(number "1"
						(effects
							(font
								(size 1.27 1.27)
							)
						)
					)
				)
				(pin passive line
					(at 5.08 0 180)
					(length 2.032)
					(name "~"
						(effects
							(font
								(size 1.27 1.27)
							)
						)
					)
					(number "2"
						(effects
							(font
								(size 1.27 1.27)
							)
						)
					)
				)
			)
		)
	(symbol "antmicroCapacitorsmisc:C_100n_100V_0805"
			(pin_numbers
				(hide yes)
			)
			(pin_names
				(hide yes)
			)
			(exclude_from_sim no)
			(in_bom yes)
			(on_board yes)
			(property "Reference" "C"
				(at 20.32 -5.08 0)
				(effects
					(font
						(size 1.27 1.27)
						(thickness 0.15)
					)
					(justify left bottom)
				)
			)
			(property "Value" "C_100n_100V_0805"
				(at 20.32 -10.16 0)
				(effects
					(font
						(size 1.27 1.27)
						(thickness 0.15)
					)
					(justify left bottom)
					(hide yes)
				)
			)
			(property "Footprint" "antmicro-footprints:C_0805_2012Metric"
				(at 20.32 -12.7 0)
				(effects
					(font
						(size 1.27 1.27)
						(thickness 0.15)
					)
					(justify left bottom)
					(hide yes)
				)
			)
			(property "Datasheet" "https://product.samsungsem.com/mlcc/CL21B104KCFNNN.do"
				(at 20.32 -15.24 0)
				(effects
					(font
						(size 1.27 1.27)
						(thickness 0.15)
					)
					(justify left bottom)
					(hide yes)
				)
			)
			(property "Description" "SMT Multilayer Ceramic Capacitor, 0.1 µF, 100 V, 0805 [2012 Metric], ± 10%, X7R, CL"
				(at 0 0 0)
				(effects
					(font
						(size 1.27 1.27)
					)
					(hide yes)
				)
			)
			(property "MPN" "CL21B104KCFNNNE"
				(at 20.32 -17.78 0)
				(effects
					(font
						(size 1.27 1.27)
						(thickness 0.15)
					)
					(justify left bottom)
					(hide yes)
				)
			)
			(property "Manufacturer" "Samsung Electro-Mechanics"
				(at 20.32 -20.32 0)
				(effects
					(font
						(size 1.27 1.27)
						(thickness 0.15)
					)
					(justify left bottom)
					(hide yes)
				)
			)
			(property "License" "Apache-2.0"
				(at 20.32 -22.86 0)
				(effects
					(font
						(size 1.27 1.27)
						(thickness 0.15)
					)
					(justify left bottom)
					(hide yes)
				)
			)
			(property "Author" "Antmicro"
				(at 20.32 -25.4 0)
				(effects
					(font
						(size 1.27 1.27)
						(thickness 0.15)
					)
					(justify left bottom)
					(hide yes)
				)
			)
			(property "Val" "100n"
				(at 20.32 -7.62 0)
				(effects
					(font
						(size 1.27 1.27)
						(thickness 0.15)
					)
					(justify left bottom)
				)
			)
			(property "Voltage" "100V"
				(at 20.32 -27.94 0)
				(effects
					(font
						(size 1.27 1.27)
					)
					(justify left bottom)
				)
			)
			(property "Dielectric" "X7R"
				(at 20.32 -30.48 0)
				(effects
					(font
						(size 1.27 1.27)
					)
					(justify left bottom)
					(hide yes)
				)
			)
			(property "ki_keywords" "0805, SMT, CAPACITOR, PASSIVE"
				(at 0 0 0)
				(effects
					(font
						(size 1.27 1.27)
					)
					(hide yes)
				)
			)
			(symbol "C_100n_100V_0805_0_1"
				(polyline
					(pts
						(xy 2.032 -1.524) (xy 2.032 1.524)
					)
					(stroke
						(width 0.3048)
						(type default)
					)
					(fill
						(type none)
					)
				)
				(polyline
					(pts
						(xy 3.048 -1.524) (xy 3.048 1.524)
					)
					(stroke
						(width 0.3302)
						(type default)
					)
					(fill
						(type none)
					)
				)
			)
			(symbol "C_100n_100V_0805_1_1"
				(pin passive line
					(at 0 0 0)
					(length 2.032)
					(name "~"
						(effects
							(font
								(size 1.27 1.27)
							)
						)
					)
					(number "1"
						(effects
							(font
								(size 1.27 1.27)
							)
						)
					)
				)
				(pin passive line
					(at 5.08 0 180)
					(length 2.032)
					(name "~"
						(effects
							(font
								(size 1.27 1.27)
							)
						)
					)
					(number "2"
						(effects
							(font
								(size 1.27 1.27)
							)
						)
					)
				)
			)
		)
	(symbol "antmicroCapacitorsmisc:C_22u_100V_2220"
			(pin_numbers
				(hide yes)
			)
			(pin_names
				(hide yes)
			)
			(exclude_from_sim no)
			(in_bom yes)
			(on_board yes)
			(property "Reference" "C"
				(at 20.32 -5.08 0)
				(effects
					(font
						(size 1.27 1.27)
						(thickness 0.15)
					)
					(justify left bottom)
				)
			)
			(property "Value" "C_22u_100V_2220"
				(at 20.32 -10.16 0)
				(effects
					(font
						(size 1.27 1.27)
						(thickness 0.15)
					)
					(justify left bottom)
					(hide yes)
				)
			)
			(property "Footprint" "antmicro-footprints:C_2220_5650Metric"
				(at 20.32 -12.7 0)
				(effects
					(font
						(size 1.27 1.27)
						(thickness 0.15)
					)
					(justify left bottom)
					(hide yes)
				)
			)
			(property "Datasheet" "https://product.tdk.com/en/search/capacitor/ceramic/mlcc/info?part_no=C5750X7S2A226M280KB"
				(at 20.32 -15.24 0)
				(effects
					(font
						(size 1.27 1.27)
						(thickness 0.15)
					)
					(justify left bottom)
					(hide yes)
				)
			)
			(property "Description" "SMT Multilayer Ceramic Capacitor, 22 µF, 100 V, 2220 [5750 Metric], ± 20%, X7S, C"
				(at 0 0 0)
				(effects
					(font
						(size 1.27 1.27)
					)
					(hide yes)
				)
			)
			(property "MPN" "C5750X7S2A226M280KB"
				(at 20.32 -17.78 0)
				(effects
					(font
						(size 1.27 1.27)
						(thickness 0.15)
					)
					(justify left bottom)
					(hide yes)
				)
			)
			(property "Manufacturer" "TDK"
				(at 20.32 -20.32 0)
				(effects
					(font
						(size 1.27 1.27)
						(thickness 0.15)
					)
					(justify left bottom)
					(hide yes)
				)
			)
			(property "License" "Apache-2.0"
				(at 20.32 -22.86 0)
				(effects
					(font
						(size 1.27 1.27)
						(thickness 0.15)
					)
					(justify left bottom)
					(hide yes)
				)
			)
			(property "Author" "Antmicro"
				(at 20.32 -25.4 0)
				(effects
					(font
						(size 1.27 1.27)
						(thickness 0.15)
					)
					(justify left bottom)
					(hide yes)
				)
			)
			(property "Val" "22u"
				(at 20.32 -7.62 0)
				(effects
					(font
						(size 1.27 1.27)
						(thickness 0.15)
					)
					(justify left bottom)
				)
			)
			(property "Voltage" "100V"
				(at 20.32 -27.94 0)
				(effects
					(font
						(size 1.27 1.27)
					)
					(justify left bottom)
				)
			)
			(property "Dielectric" "X7S"
				(at 20.32 -30.48 0)
				(effects
					(font
						(size 1.27 1.27)
					)
					(justify left bottom)
					(hide yes)
				)
			)
			(property "ki_keywords" "SMT, CAPACITOR, PASSIVE"
				(at 0 0 0)
				(effects
					(font
						(size 1.27 1.27)
					)
					(hide yes)
				)
			)
			(symbol "C_22u_100V_2220_0_1"
				(polyline
					(pts
						(xy 2.032 -1.524) (xy 2.032 1.524)
					)
					(stroke
						(width 0.3048)
						(type default)
					)
					(fill
						(type none)
					)
				)
				(polyline
					(pts
						(xy 3.048 -1.524) (xy 3.048 1.524)
					)
					(stroke
						(width 0.3302)
						(type default)
					)
					(fill
						(type none)
					)
				)
			)
			(symbol "C_22u_100V_2220_1_1"
				(pin passive line
					(at 0 0 0)
					(length 2.032)
					(name "~"
						(effects
							(font
								(size 1.27 1.27)
							)
						)
					)
					(number "1"
						(effects
							(font
								(size 1.27 1.27)
							)
						)
					)
				)
				(pin passive line
					(at 5.08 0 180)
					(length 2.032)
					(name "~"
						(effects
							(font
								(size 1.27 1.27)
							)
						)
					)
					(number "2"
						(effects
							(font
								(size 1.27 1.27)
							)
						)
					)
				)
			)
		)
	(symbol "antmicroCapacitorsmisc:C_22u_25V_0805"
			(pin_numbers
				(hide yes)
			)
			(pin_names
				(hide yes)
			)
			(exclude_from_sim no)
			(in_bom yes)
			(on_board yes)
			(property "Reference" "C"
				(at 20.32 -5.08 0)
				(effects
					(font
						(size 1.27 1.27)
						(thickness 0.15)
					)
					(justify left bottom)
				)
			)
			(property "Value" "C_22u_25V_0805"
				(at 20.32 -10.16 0)
				(effects
					(font
						(size 1.27 1.27)
						(thickness 0.15)
					)
					(justify left bottom)
					(hide yes)
				)
			)
			(property "Footprint" "antmicro-footprints:C_0805_2012Metric"
				(at 20.32 -12.7 0)
				(effects
					(font
						(size 1.27 1.27)
						(thickness 0.15)
					)
					(justify left bottom)
					(hide yes)
				)
			)
			(property "Datasheet" "https://product.samsungsem.com/mlcc/CL21A226MAYNNN.do"
				(at 20.32 -15.24 0)
				(effects
					(font
						(size 1.27 1.27)
						(thickness 0.15)
					)
					(justify left bottom)
					(hide yes)
				)
			)
			(property "Description" "SMT Multilayer Ceramic Capacitor, 22uF, +/-20%, 25V, X5R, 0805 [2012 Metric]"
				(at 0 0 0)
				(effects
					(font
						(size 1.27 1.27)
					)
					(hide yes)
				)
			)
			(property "MPN" "CL21A226MAYNNNE"
				(at 20.32 -17.78 0)
				(effects
					(font
						(size 1.27 1.27)
						(thickness 0.15)
					)
					(justify left bottom)
					(hide yes)
				)
			)
			(property "Manufacturer" "Samsung Electro-Mechanics"
				(at 20.32 -20.32 0)
				(effects
					(font
						(size 1.27 1.27)
						(thickness 0.15)
					)
					(justify left bottom)
					(hide yes)
				)
			)
			(property "License" "Apache-2.0"
				(at 20.32 -22.86 0)
				(effects
					(font
						(size 1.27 1.27)
						(thickness 0.15)
					)
					(justify left bottom)
					(hide yes)
				)
			)
			(property "Author" "Antmicro"
				(at 20.32 -25.4 0)
				(effects
					(font
						(size 1.27 1.27)
						(thickness 0.15)
					)
					(justify left bottom)
					(hide yes)
				)
			)
			(property "Val" "22u"
				(at 20.32 -7.62 0)
				(effects
					(font
						(size 1.27 1.27)
						(thickness 0.15)
					)
					(justify left bottom)
				)
			)
			(property "Voltage" "25V"
				(at 20.32 -27.94 0)
				(effects
					(font
						(size 1.27 1.27)
					)
					(justify left bottom)
				)
			)
			(property "Dielectric" "X5R"
				(at 20.32 -30.48 0)
				(effects
					(font
						(size 1.27 1.27)
					)
					(justify left bottom)
					(hide yes)
				)
			)
			(property "ki_keywords" "0805, SMT, CAPACITOR, PASSIVE"
				(at 0 0 0)
				(effects
					(font
						(size 1.27 1.27)
					)
					(hide yes)
				)
			)
			(symbol "C_22u_25V_0805_0_1"
				(polyline
					(pts
						(xy 2.032 -1.524) (xy 2.032 1.524)
					)
					(stroke
						(width 0.3048)
						(type default)
					)
					(fill
						(type none)
					)
				)
				(polyline
					(pts
						(xy 3.048 -1.524) (xy 3.048 1.524)
					)
					(stroke
						(width 0.3302)
						(type default)
					)
					(fill
						(type none)
					)
				)
			)
			(symbol "C_22u_25V_0805_1_1"
				(pin passive line
					(at 0 0 0)
					(length 2.032)
					(name "~"
						(effects
							(font
								(size 1.27 1.27)
							)
						)
					)
					(number "1"
						(effects
							(font
								(size 1.27 1.27)
							)
						)
					)
				)
				(pin passive line
					(at 5.08 0 180)
					(length 2.032)
					(name "~"
						(effects
							(font
								(size 1.27 1.27)
							)
						)
					)
					(number "2"
						(effects
							(font
								(size 1.27 1.27)
							)
						)
					)
				)
			)
		)
	(symbol "antmicroCapacitorsmisc:C_47u_16V_1206"
			(pin_numbers
				(hide yes)
			)
			(pin_names
				(hide yes)
			)
			(exclude_from_sim no)
			(in_bom yes)
			(on_board yes)
			(property "Reference" "C"
				(at 20.32 -5.08 0)
				(effects
					(font
						(size 1.27 1.27)
						(thickness 0.15)
					)
					(justify left bottom)
				)
			)
			(property "Value" "C_47u_16V_1206"
				(at 20.32 -10.16 0)
				(effects
					(font
						(size 1.27 1.27)
						(thickness 0.15)
					)
					(justify left bottom)
					(hide yes)
				)
			)
			(property "Footprint" "antmicro-footprints:C_1206_3216Metric"
				(at 20.32 -12.7 0)
				(effects
					(font
						(size 1.27 1.27)
						(thickness 0.15)
					)
					(justify left bottom)
					(hide yes)
				)
			)
			(property "Datasheet" "https://product.tdk.com/en/search/capacitor/ceramic/mlcc/info?part_no=C3216X5R1C476M160AB"
				(at 20.32 -15.24 0)
				(effects
					(font
						(size 1.27 1.27)
						(thickness 0.15)
					)
					(justify left bottom)
					(hide yes)
				)
			)
			(property "Description" "SMD Multilayer Ceramic Capacitor, 47 µF, 16 V, 1206 [3216 Metric], ± 20%, X5R, C"
				(at 0 0 0)
				(effects
					(font
						(size 1.27 1.27)
					)
					(hide yes)
				)
			)
			(property "MPN" "C3216X5R1C476M160AB"
				(at 20.32 -17.78 0)
				(effects
					(font
						(size 1.27 1.27)
						(thickness 0.15)
					)
					(justify left bottom)
					(hide yes)
				)
			)
			(property "Manufacturer" "TDK"
				(at 20.32 -20.32 0)
				(effects
					(font
						(size 1.27 1.27)
						(thickness 0.15)
					)
					(justify left bottom)
					(hide yes)
				)
			)
			(property "License" "Apache-2.0"
				(at 20.32 -22.86 0)
				(effects
					(font
						(size 1.27 1.27)
						(thickness 0.15)
					)
					(justify left bottom)
					(hide yes)
				)
			)
			(property "Author" "Antmicro"
				(at 20.32 -25.4 0)
				(effects
					(font
						(size 1.27 1.27)
						(thickness 0.15)
					)
					(justify left bottom)
					(hide yes)
				)
			)
			(property "Val" "47u"
				(at 20.32 -7.62 0)
				(effects
					(font
						(size 1.27 1.27)
						(thickness 0.15)
					)
					(justify left bottom)
				)
			)
			(property "Voltage" "16V"
				(at 20.32 -27.94 0)
				(effects
					(font
						(size 1.27 1.27)
					)
					(justify left bottom)
				)
			)
			(property "Dielectric" "X5R"
				(at 20.32 -30.48 0)
				(effects
					(font
						(size 1.27 1.27)
					)
					(justify left bottom)
					(hide yes)
				)
			)
			(property "ki_keywords" "1206, SMT, CAPACITOR, PASSIVE"
				(at 0 0 0)
				(effects
					(font
						(size 1.27 1.27)
					)
					(hide yes)
				)
			)
			(symbol "C_47u_16V_1206_0_1"
				(polyline
					(pts
						(xy 2.032 -1.524) (xy 2.032 1.524)
					)
					(stroke
						(width 0.3048)
						(type default)
					)
					(fill
						(type none)
					)
				)
				(polyline
					(pts
						(xy 3.048 -1.524) (xy 3.048 1.524)
					)
					(stroke
						(width 0.3302)
						(type default)
					)
					(fill
						(type none)
					)
				)
			)
			(symbol "C_47u_16V_1206_1_1"
				(pin passive line
					(at 0 0 0)
					(length 2.032)
					(name "~"
						(effects
							(font
								(size 1.27 1.27)
							)
						)
					)
					(number "1"
						(effects
							(font
								(size 1.27 1.27)
							)
						)
					)
				)
				(pin passive line
					(at 5.08 0 180)
					(length 2.032)
					(name "~"
						(effects
							(font
								(size 1.27 1.27)
							)
						)
					)
					(number "2"
						(effects
							(font
								(size 1.27 1.27)
							)
						)
					)
				)
			)
		)
	(symbol "antmicroCapacitorsmisc:C_4u7_0201"
			(pin_numbers
				(hide yes)
			)
			(pin_names
				(hide yes)
			)
			(exclude_from_sim no)
			(in_bom yes)
			(on_board yes)
			(property "Reference" "C"
				(at 20.32 -5.08 0)
				(effects
					(font
						(size 1.27 1.27)
						(thickness 0.15)
					)
					(justify left bottom)
				)
			)
			(property "Value" "C_4u7_0201"
				(at 20.32 -10.16 0)
				(effects
					(font
						(size 1.27 1.27)
						(thickness 0.15)
					)
					(justify left bottom)
					(hide yes)
				)
			)
			(property "Footprint" "antmicro-footprints:C_0201"
				(at 20.32 -12.7 0)
				(effects
					(font
						(size 1.27 1.27)
						(thickness 0.15)
					)
					(justify left bottom)
					(hide yes)
				)
			)
			(property "Datasheet" "https://www.murata.com/products/productdetail?partno=GRM035R60J475ME15%23"
				(at 20.32 -15.24 0)
				(effects
					(font
						(size 1.27 1.27)
						(thickness 0.15)
					)
					(justify left bottom)
					(hide yes)
				)
			)
			(property "Description" "SMD Multilayer Ceramic Capacitor, 4.7 µF, 6.3 V, 0201 [0603 Metric], ± 20%, X5R, GRM Series"
				(at 0 0 0)
				(effects
					(font
						(size 1.27 1.27)
					)
					(hide yes)
				)
			)
			(property "MPN" "GRM035R60J475ME15D"
				(at 20.32 -17.78 0)
				(effects
					(font
						(size 1.27 1.27)
						(thickness 0.15)
					)
					(justify left bottom)
					(hide yes)
				)
			)
			(property "Manufacturer" "Murata"
				(at 20.32 -20.32 0)
				(effects
					(font
						(size 1.27 1.27)
						(thickness 0.15)
					)
					(justify left bottom)
					(hide yes)
				)
			)
			(property "License" "Apache-2.0"
				(at 20.32 -22.86 0)
				(effects
					(font
						(size 1.27 1.27)
						(thickness 0.15)
					)
					(justify left bottom)
					(hide yes)
				)
			)
			(property "Author" "Antmicro"
				(at 20.32 -25.4 0)
				(effects
					(font
						(size 1.27 1.27)
						(thickness 0.15)
					)
					(justify left bottom)
					(hide yes)
				)
			)
			(property "Val" "4u7"
				(at 20.32 -7.62 0)
				(effects
					(font
						(size 1.27 1.27)
						(thickness 0.15)
					)
					(justify left bottom)
				)
			)
			(property "Voltage" ""
				(at 20.32 -27.94 0)
				(effects
					(font
						(size 1.27 1.27)
					)
					(justify left bottom)
					(hide yes)
				)
			)
			(property "Dielectric" ""
				(at 20.32 -30.48 0)
				(effects
					(font
						(size 1.27 1.27)
					)
					(justify left bottom)
					(hide yes)
				)
			)
			(symbol "C_4u7_0201_0_1"
				(polyline
					(pts
						(xy 2.032 -1.524) (xy 2.032 1.524)
					)
					(stroke
						(width 0.3048)
						(type default)
					)
					(fill
						(type none)
					)
				)
				(polyline
					(pts
						(xy 3.048 -1.524) (xy 3.048 1.524)
					)
					(stroke
						(width 0.3302)
						(type default)
					)
					(fill
						(type none)
					)
				)
			)
			(symbol "C_4u7_0201_1_1"
				(pin passive line
					(at 0 0 0)
					(length 2.032)
					(name "~"
						(effects
							(font
								(size 1.27 1.27)
							)
						)
					)
					(number "1"
						(effects
							(font
								(size 1.27 1.27)
							)
						)
					)
				)
				(pin passive line
					(at 5.08 0 180)
					(length 2.032)
					(name "~"
						(effects
							(font
								(size 1.27 1.27)
							)
						)
					)
					(number "2"
						(effects
							(font
								(size 1.27 1.27)
							)
						)
					)
				)
			)
		)
	(symbol "antmicroCapacitorspol:C_Pol_330u_6.3V_KEMET-T520-B"
			(pin_numbers
				(hide yes)
			)
			(pin_names
				(hide yes)
			)
			(exclude_from_sim no)
			(in_bom yes)
			(on_board yes)
			(property "Reference" "C"
				(at 13.97 0 0)
				(effects
					(font
						(size 1.27 1.27)
						(thickness 0.15)
					)
					(justify left bottom)
				)
			)
			(property "Value" "C_Pol_330u_6.3V_KEMET-T520-B"
				(at 13.97 -5.08 0)
				(effects
					(font
						(size 1.27 1.27)
						(thickness 0.15)
					)
					(justify left bottom)
					(hide yes)
				)
			)
			(property "Footprint" "antmicro-footprints:C_Pol_EIA-B"
				(at 13.97 -7.62 0)
				(effects
					(font
						(size 1.27 1.27)
						(thickness 0.15)
					)
					(justify left bottom)
					(hide yes)
				)
			)
			(property "Datasheet" "https://content.kemet.com/datasheets/KEM_T2076_T52X-530.pdf"
				(at 13.97 -10.16 0)
				(effects
					(font
						(size 1.27 1.27)
						(thickness 0.15)
					)
					(justify left bottom)
					(hide yes)
				)
			)
			(property "Description" "Tantalum Polymer Capacitor, KO-CAP®, 330 µF, ± 20%, 6.3 V, B, 0.04 ohm, 1411 [3528 Metric]"
				(at 0 0 0)
				(effects
					(font
						(size 1.27 1.27)
					)
					(hide yes)
				)
			)
			(property "MPN" "T520B337M006ATE040"
				(at 13.97 -12.7 0)
				(effects
					(font
						(size 1.27 1.27)
						(thickness 0.15)
					)
					(justify left bottom)
					(hide yes)
				)
			)
			(property "Manufacturer" "KEMET"
				(at 13.97 -15.24 0)
				(effects
					(font
						(size 1.27 1.27)
						(thickness 0.15)
					)
					(justify left bottom)
					(hide yes)
				)
			)
			(property "License" "Apache-2.0"
				(at 13.97 -17.78 0)
				(effects
					(font
						(size 1.27 1.27)
						(thickness 0.15)
					)
					(justify left bottom)
					(hide yes)
				)
			)
			(property "Author" "Antmicro"
				(at 13.97 -20.32 0)
				(effects
					(font
						(size 1.27 1.27)
						(thickness 0.15)
					)
					(justify left bottom)
					(hide yes)
				)
			)
			(property "Val" "330u"
				(at 13.97 -2.54 0)
				(effects
					(font
						(size 1.27 1.27)
						(thickness 0.15)
					)
					(justify left bottom)
				)
			)
			(property "Voltage" "6.3V"
				(at 13.97 -22.86 0)
				(effects
					(font
						(size 1.27 1.27)
					)
					(justify left bottom)
					(hide yes)
				)
			)
			(property "Dielectric" ""
				(at 13.97 -25.4 0)
				(effects
					(font
						(size 1.27 1.27)
					)
					(justify left bottom)
					(hide yes)
				)
			)
			(symbol "C_Pol_330u_6.3V_KEMET-T520-B_0_1"
				(rectangle
					(start -1.524 -1.905)
					(end 1.524 -2.286)
					(stroke
						(width 0)
						(type default)
					)
					(fill
						(type none)
					)
				)
				(rectangle
					(start -1.524 -2.921)
					(end 1.524 -3.302)
					(stroke
						(width 0)
						(type default)
					)
					(fill
						(type outline)
					)
				)
				(polyline
					(pts
						(xy -1.27 -0.9652) (xy -0.762 -0.9652)
					)
					(stroke
						(width 0)
						(type default)
					)
					(fill
						(type none)
					)
				)
				(polyline
					(pts
						(xy -1.016 -1.2192) (xy -1.016 -0.7112)
					)
					(stroke
						(width 0)
						(type default)
					)
					(fill
						(type none)
					)
				)
			)
			(symbol "C_Pol_330u_6.3V_KEMET-T520-B_1_1"
				(pin passive line
					(at 0 0 270)
					(length 1.8542)
					(name "~"
						(effects
							(font
								(size 1.27 1.27)
							)
						)
					)
					(number "1"
						(effects
							(font
								(size 1.27 1.27)
							)
						)
					)
				)
				(pin passive line
					(at 0 -5.08 90)
					(length 1.8542)
					(name "~"
						(effects
							(font
								(size 1.27 1.27)
							)
						)
					)
					(number "2"
						(effects
							(font
								(size 1.27 1.27)
							)
						)
					)
				)
			)
		)
	(symbol "antmicroClockTimingClockGeneratorsPLLsFrequencySynthesizers:CDCE906PWR"
			(exclude_from_sim no)
			(in_bom yes)
			(on_board yes)
			(property "Reference" "U"
				(at 38.1 -5.08 0)
				(effects
					(font
						(size 1.27 1.27)
						(thickness 0.15)
					)
					(justify left bottom)
				)
			)
			(property "Value" "CDCE906PWR"
				(at 38.1 -7.62 0)
				(effects
					(font
						(size 1.27 1.27)
						(thickness 0.15)
					)
					(justify left bottom)
				)
			)
			(property "Footprint" "antmicro-footprints:TSSOP-20_W4.4mm"
				(at 38.1 -10.16 0)
				(effects
					(font
						(size 1.27 1.27)
						(thickness 0.15)
					)
					(justify left bottom)
					(hide yes)
				)
			)
			(property "Datasheet" "https://www.ti.com/lit/ds/symlink/cdce906.pdf?HQS=dis-mous-null-mousermode-dsf-pf-null-wwe&ts=1672406494449&ref_url=https%253A%252F%252Feu.mouser.com%252F"
				(at 38.1 -12.7 0)
				(effects
					(font
						(size 1.27 1.27)
						(thickness 0.15)
					)
					(justify left bottom)
					(hide yes)
				)
			)
			(property "Description" "Clock generator/frequency synthesizer (PLL)"
				(at 0 0 0)
				(effects
					(font
						(size 1.27 1.27)
					)
					(hide yes)
				)
			)
			(property "MPN" "CDCE906PWR"
				(at 38.1 -15.24 0)
				(effects
					(font
						(size 1.27 1.27)
						(thickness 0.15)
					)
					(justify left bottom)
					(hide yes)
				)
			)
			(property "Manufacturer" "Texas Instruments"
				(at 38.1 -17.78 0)
				(effects
					(font
						(size 1.27 1.27)
						(thickness 0.15)
					)
					(justify left bottom)
					(hide yes)
				)
			)
			(property "Author" "Antmicro"
				(at 38.1 -20.32 0)
				(effects
					(font
						(size 1.27 1.27)
						(thickness 0.15)
					)
					(justify left bottom)
					(hide yes)
				)
			)
			(property "License" "Apache-2.0"
				(at 38.1 -22.86 0)
				(effects
					(font
						(size 1.27 1.27)
						(thickness 0.15)
					)
					(justify left bottom)
					(hide yes)
				)
			)
			(property "ki_keywords" "SMT, PLL, IC, CLOCK"
				(at 0 0 0)
				(effects
					(font
						(size 1.27 1.27)
					)
					(hide yes)
				)
			)
			(property "ki_fp_filters" "SOIC*3.9x4.9mm*P1.27mm* TSSOP*4.4x3mm*P0.65mm*"
				(at 0 0 0)
				(effects
					(font
						(size 1.27 1.27)
					)
					(hide yes)
				)
			)
			(symbol "CDCE906PWR_1_1"
				(rectangle
					(start 2.54 2.54)
					(end 22.86 -22.86)
					(stroke
						(width 0.254)
						(type default)
					)
					(fill
						(type background)
					)
				)
				(pin power_in line
					(at 0 0 0)
					(length 2.54)
					(name "VCC"
						(effects
							(font
								(size 1.27 1.27)
							)
						)
					)
					(number "3"
						(effects
							(font
								(size 1.27 1.27)
							)
						)
					)
				)
				(pin passive line
					(at 0 0 0)
					(length 2.54)
					(hide yes)
					(name "VCC"
						(effects
							(font
								(size 1.27 1.27)
							)
						)
					)
					(number "7"
						(effects
							(font
								(size 1.27 1.27)
							)
						)
					)
				)
				(pin input line
					(at 0 -5.08 0)
					(length 2.54)
					(name "S0/A0/CLK_SEL"
						(effects
							(font
								(size 1.27 1.27)
							)
						)
					)
					(number "1"
						(effects
							(font
								(size 1.27 1.27)
							)
						)
					)
				)
				(pin input line
					(at 0 -7.62 0)
					(length 2.54)
					(name "S1/A1"
						(effects
							(font
								(size 1.27 1.27)
							)
						)
					)
					(number "2"
						(effects
							(font
								(size 1.27 1.27)
							)
						)
					)
				)
				(pin input line
					(at 0 -11.43 0)
					(length 2.54)
					(name "CLK_IN0"
						(effects
							(font
								(size 1.27 1.27)
							)
						)
					)
					(number "5"
						(effects
							(font
								(size 1.27 1.27)
							)
						)
					)
				)
				(pin input line
					(at 0 -13.97 0)
					(length 2.54)
					(name "CLK_IN1"
						(effects
							(font
								(size 1.27 1.27)
							)
						)
					)
					(number "6"
						(effects
							(font
								(size 1.27 1.27)
							)
						)
					)
				)
				(pin bidirectional line
					(at 0 -17.78 0)
					(length 2.54)
					(name "SDA"
						(effects
							(font
								(size 1.27 1.27)
							)
						)
					)
					(number "9"
						(effects
							(font
								(size 1.27 1.27)
							)
						)
					)
				)
				(pin bidirectional line
					(at 0 -20.32 0)
					(length 2.54)
					(name "SCK"
						(effects
							(font
								(size 1.27 1.27)
							)
						)
					)
					(number "10"
						(effects
							(font
								(size 1.27 1.27)
							)
						)
					)
				)
				(pin passive line
					(at 12.7 -25.4 90)
					(length 2.54)
					(name "GND"
						(effects
							(font
								(size 1.27 1.27)
							)
						)
					)
					(number "13"
						(effects
							(font
								(size 1.27 1.27)
							)
						)
					)
				)
				(pin passive line
					(at 12.7 -25.4 90)
					(length 2.54)
					(hide yes)
					(name "GND"
						(effects
							(font
								(size 1.27 1.27)
							)
						)
					)
					(number "17"
						(effects
							(font
								(size 1.27 1.27)
							)
						)
					)
				)
				(pin passive line
					(at 12.7 -25.4 90)
					(length 2.54)
					(hide yes)
					(name "GND"
						(effects
							(font
								(size 1.27 1.27)
							)
						)
					)
					(number "4"
						(effects
							(font
								(size 1.27 1.27)
							)
						)
					)
				)
				(pin passive line
					(at 12.7 -25.4 90)
					(length 2.54)
					(hide yes)
					(name "GND"
						(effects
							(font
								(size 1.27 1.27)
							)
						)
					)
					(number "8"
						(effects
							(font
								(size 1.27 1.27)
							)
						)
					)
				)
				(pin power_in line
					(at 25.4 0 180)
					(length 2.54)
					(name "VCCOUT1"
						(effects
							(font
								(size 1.27 1.27)
							)
						)
					)
					(number "14"
						(effects
							(font
								(size 1.27 1.27)
							)
						)
					)
				)
				(pin power_in line
					(at 25.4 -2.54 180)
					(length 2.54)
					(name "VCCOUT2"
						(effects
							(font
								(size 1.27 1.27)
							)
						)
					)
					(number "18"
						(effects
							(font
								(size 1.27 1.27)
							)
						)
					)
				)
				(pin tri_state line
					(at 25.4 -7.62 180)
					(length 2.54)
					(name "Y0"
						(effects
							(font
								(size 1.27 1.27)
							)
						)
					)
					(number "11"
						(effects
							(font
								(size 1.27 1.27)
							)
						)
					)
				)
				(pin tri_state line
					(at 25.4 -10.16 180)
					(length 2.54)
					(name "Y1"
						(effects
							(font
								(size 1.27 1.27)
							)
						)
					)
					(number "12"
						(effects
							(font
								(size 1.27 1.27)
							)
						)
					)
				)
				(pin tri_state line
					(at 25.4 -12.7 180)
					(length 2.54)
					(name "Y2"
						(effects
							(font
								(size 1.27 1.27)
							)
						)
					)
					(number "15"
						(effects
							(font
								(size 1.27 1.27)
							)
						)
					)
				)
				(pin tri_state line
					(at 25.4 -15.24 180)
					(length 2.54)
					(name "Y3"
						(effects
							(font
								(size 1.27 1.27)
							)
						)
					)
					(number "16"
						(effects
							(font
								(size 1.27 1.27)
							)
						)
					)
				)
				(pin tri_state line
					(at 25.4 -17.78 180)
					(length 2.54)
					(name "Y4"
						(effects
							(font
								(size 1.27 1.27)
							)
						)
					)
					(number "19"
						(effects
							(font
								(size 1.27 1.27)
							)
						)
					)
				)
				(pin tri_state line
					(at 25.4 -20.32 180)
					(length 2.54)
					(name "Y5"
						(effects
							(font
								(size 1.27 1.27)
							)
						)
					)
					(number "20"
						(effects
							(font
								(size 1.27 1.27)
							)
						)
					)
				)
			)
		)
	(symbol "antmicroCoaxialConnectorsRF:U_FL-R-SMT-1"
			(exclude_from_sim no)
			(in_bom yes)
			(on_board yes)
			(property "Reference" "J"
				(at 20.32 -2.54 0)
				(effects
					(font
						(size 1.27 1.27)
						(thickness 0.15)
					)
					(justify left bottom)
				)
			)
			(property "Value" "U_FL-R-SMT-1"
				(at 20.32 -7.62 0)
				(effects
					(font
						(size 1.27 1.27)
						(thickness 0.15)
					)
					(justify left bottom)
					(hide yes)
				)
			)
			(property "Footprint" "antmicro-footprints:Coax_Conn_U.FL"
				(at 20.32 -10.16 0)
				(effects
					(font
						(size 1.27 1.27)
						(thickness 0.15)
					)
					(justify left bottom)
					(hide yes)
				)
			)
			(property "Datasheet" "https://media.digikey.com/pdf/Data%20Sheets/Hirose%20PDFs/UFL%20Series.pdf"
				(at 20.32 -12.7 0)
				(effects
					(font
						(size 1.27 1.27)
						(thickness 0.15)
					)
					(justify left bottom)
					(hide yes)
				)
			)
			(property "Description" "U.FL (UMCC) Connector Receptacle, Male Pin 50Ohm Surface Mount Solder"
				(at 0 0 0)
				(effects
					(font
						(size 1.27 1.27)
					)
					(hide yes)
				)
			)
			(property "MPN" "U.FL-R-SMT-1(10)"
				(at 20.32 -5.08 0)
				(effects
					(font
						(size 1.27 1.27)
						(thickness 0.15)
					)
					(justify left bottom)
				)
			)
			(property "Manufacturer" "Hirose Electric"
				(at 20.32 -15.24 0)
				(effects
					(font
						(size 1.27 1.27)
						(thickness 0.15)
					)
					(justify left bottom)
					(hide yes)
				)
			)
			(property "Author" "Antmicro"
				(at 20.32 -17.78 0)
				(effects
					(font
						(size 1.27 1.27)
						(thickness 0.15)
					)
					(justify left bottom)
					(hide yes)
				)
			)
			(property "License" "Apache-2.0"
				(at 20.32 -20.32 0)
				(effects
					(font
						(size 1.27 1.27)
						(thickness 0.15)
					)
					(justify left bottom)
					(hide yes)
				)
			)
			(property "ki_keywords" "UFL, COAXIAL, CONNECTOR"
				(at 0 0 0)
				(effects
					(font
						(size 1.27 1.27)
					)
					(hide yes)
				)
			)
			(symbol "U_FL-R-SMT-1_0_0"
				(pin passive line
					(at 0 0 0)
					(length 3.81)
					(name "~"
						(effects
							(font
								(size 1.27 1.27)
							)
						)
					)
					(number "1"
						(effects
							(font
								(size 1.27 1.27)
							)
						)
					)
				)
				(pin passive line
					(at 6.35 -6.35 90)
					(length 3.81)
					(name "~"
						(effects
							(font
								(size 1.27 1.27)
							)
						)
					)
					(number "SH1"
						(effects
							(font
								(size 1.27 1.27)
							)
						)
					)
				)
				(pin passive line
					(at 6.35 -6.35 90)
					(length 3.81)
					(hide yes)
					(name "~"
						(effects
							(font
								(size 1.27 1.27)
							)
						)
					)
					(number "SH2"
						(effects
							(font
								(size 1.27 1.27)
							)
						)
					)
				)
			)
			(symbol "U_FL-R-SMT-1_1_1"
				(polyline
					(pts
						(xy 3.81 0) (xy 5.842 0)
					)
					(stroke
						(width 0.254)
						(type default)
					)
					(fill
						(type background)
					)
				)
				(arc
					(start 4.6063 0.5218)
					(mid 6.6063 1.8221)
					(end 8.1623 0.0138)
					(stroke
						(width 0.254)
						(type default)
					)
					(fill
						(type none)
					)
				)
				(circle
					(center 6.35 0)
					(radius 0.508)
					(stroke
						(width 0.254)
						(type default)
					)
					(fill
						(type outline)
					)
				)
				(arc
					(start 8.1623 0.0138)
					(mid 6.6063 -1.7941)
					(end 4.6063 -0.4942)
					(stroke
						(width 0.254)
						(type default)
					)
					(fill
						(type none)
					)
				)
				(polyline
					(pts
						(xy 6.35 -2.54) (xy 6.35 -1.905)
					)
					(stroke
						(width 0.254)
						(type default)
					)
					(fill
						(type background)
					)
				)
			)
		)
	(symbol "antmicroDCDCConverters:ULS-12_8.3-D48N-C"
			(exclude_from_sim no)
			(in_bom yes)
			(on_board yes)
			(property "Reference" "U"
				(at 35.56 -2.54 0)
				(effects
					(font
						(size 1.27 1.27)
						(thickness 0.15)
					)
					(justify left bottom)
				)
			)
			(property "Value" "ULS-12_8.3-D48N-C"
				(at 35.56 -7.62 0)
				(effects
					(font
						(size 1.27 1.27)
						(thickness 0.15)
					)
					(justify left bottom)
					(hide yes)
				)
			)
			(property "Footprint" "antmicro-footprints:ULS-12_5-D48N-C"
				(at 35.56 -10.16 0)
				(effects
					(font
						(size 1.27 1.27)
						(thickness 0.15)
					)
					(justify left bottom)
					(hide yes)
				)
			)
			(property "Datasheet" "https://www.murata.com/products/productdata/8807040286750/uls.pdf?1649388617000"
				(at 35.56 -12.7 0)
				(effects
					(font
						(size 1.27 1.27)
						(thickness 0.15)
					)
					(justify left bottom)
					(hide yes)
				)
			)
			(property "Description" "DC/DC converter"
				(at 0 0 0)
				(effects
					(font
						(size 1.27 1.27)
					)
					(hide yes)
				)
			)
			(property "MPN" "ULS-12/8.3-D48N-C"
				(at 35.56 -5.08 0)
				(effects
					(font
						(size 1.27 1.27)
						(thickness 0.15)
					)
					(justify left bottom)
				)
			)
			(property "Manufacturer" "Murata"
				(at 35.56 -15.24 0)
				(effects
					(font
						(size 1.27 1.27)
						(thickness 0.15)
					)
					(justify left bottom)
					(hide yes)
				)
			)
			(property "Author" "Antmicro"
				(at 35.56 -17.78 0)
				(effects
					(font
						(size 1.27 1.27)
						(thickness 0.15)
					)
					(justify left bottom)
					(hide yes)
				)
			)
			(property "License" "Apache-2.0"
				(at 35.56 -20.32 0)
				(effects
					(font
						(size 1.27 1.27)
						(thickness 0.15)
					)
					(justify left bottom)
					(hide yes)
				)
			)
			(property "ki_keywords" "THT, PMIC, IC, DC-DC, CONVERTER, MODULE"
				(at 0 0 0)
				(effects
					(font
						(size 1.27 1.27)
					)
					(hide yes)
				)
			)
			(symbol "ULS-12_8.3-D48N-C_1_1"
				(rectangle
					(start 2.413 2.54)
					(end 17.653 -17.78)
					(stroke
						(width 0.254)
						(type default)
					)
					(fill
						(type background)
					)
				)
				(pin power_in line
					(at 0 0 0)
					(length 2.54)
					(name "VIN+"
						(effects
							(font
								(size 1.27 1.27)
							)
						)
					)
					(number "1"
						(effects
							(font
								(size 1.27 1.27)
							)
						)
					)
				)
				(pin input line
					(at 0 -7.62 0)
					(length 2.54)
					(name "CTRL"
						(effects
							(font
								(size 1.27 1.27)
							)
						)
					)
					(number "2"
						(effects
							(font
								(size 1.27 1.27)
							)
						)
					)
				)
				(pin power_in line
					(at 0 -15.24 0)
					(length 2.54)
					(name "VIN-"
						(effects
							(font
								(size 1.27 1.27)
							)
						)
					)
					(number "3"
						(effects
							(font
								(size 1.27 1.27)
							)
						)
					)
				)
				(pin power_out line
					(at 20.32 0 180)
					(length 2.54)
					(name "VOUT+"
						(effects
							(font
								(size 1.27 1.27)
							)
						)
					)
					(number "8"
						(effects
							(font
								(size 1.27 1.27)
							)
						)
					)
				)
				(pin passive line
					(at 20.32 -2.54 180)
					(length 2.54)
					(name "SENSE+"
						(effects
							(font
								(size 1.27 1.27)
							)
						)
					)
					(number "7"
						(effects
							(font
								(size 1.27 1.27)
							)
						)
					)
				)
				(pin input line
					(at 20.32 -7.62 180)
					(length 2.54)
					(name "TRIM"
						(effects
							(font
								(size 1.27 1.27)
							)
						)
					)
					(number "6"
						(effects
							(font
								(size 1.27 1.27)
							)
						)
					)
				)
				(pin passive line
					(at 20.32 -12.7 180)
					(length 2.54)
					(name "SENSE-"
						(effects
							(font
								(size 1.27 1.27)
							)
						)
					)
					(number "5"
						(effects
							(font
								(size 1.27 1.27)
							)
						)
					)
				)
				(pin power_out line
					(at 20.32 -15.24 180)
					(length 2.54)
					(name "VOUT-"
						(effects
							(font
								(size 1.27 1.27)
							)
						)
					)
					(number "4"
						(effects
							(font
								(size 1.27 1.27)
							)
						)
					)
				)
			)
		)
	(symbol "antmicroDiodesRectifiersSingle:BAT54-02V-G3-08"
			(pin_numbers
				(hide yes)
			)
			(pin_names
				(hide yes)
			)
			(exclude_from_sim no)
			(in_bom yes)
			(on_board yes)
			(property "Reference" "D"
				(at 21.59 -5.08 0)
				(effects
					(font
						(size 1.27 1.27)
						(thickness 0.15)
					)
					(justify left bottom)
				)
			)
			(property "Value" "BAT54-02V-G3-08"
				(at 21.59 -15.24 0)
				(effects
					(font
						(size 1.27 1.27)
						(thickness 0.15)
					)
					(justify left bottom)
					(hide yes)
				)
			)
			(property "Footprint" "antmicro-footprints:SOD-523"
				(at 21.59 -10.16 0)
				(effects
					(font
						(size 1.27 1.27)
						(thickness 0.15)
					)
					(justify left bottom)
					(hide yes)
				)
			)
			(property "Datasheet" "https://www.vishay.com/docs/85633/bat5402v.pdf"
				(at 21.59 -12.7 0)
				(effects
					(font
						(size 1.27 1.27)
						(thickness 0.15)
					)
					(justify left bottom)
					(hide yes)
				)
			)
			(property "Description" "Small Signal Schottky Diode, Single, 30 V, 200 mA, 800 mV, 600 mA, 125 °C"
				(at 0 0 0)
				(effects
					(font
						(size 1.27 1.27)
					)
					(hide yes)
				)
			)
			(property "MPN" "BAT54-02V-G3-08"
				(at 21.59 -7.62 0)
				(effects
					(font
						(size 1.27 1.27)
						(thickness 0.15)
					)
					(justify left bottom)
				)
			)
			(property "Manufacturer" "Vishay"
				(at 21.59 -17.78 0)
				(effects
					(font
						(size 1.27 1.27)
						(thickness 0.15)
					)
					(justify left bottom)
					(hide yes)
				)
			)
			(property "Author" "Antmicro"
				(at 21.59 -20.32 0)
				(effects
					(font
						(size 1.27 1.27)
						(thickness 0.15)
					)
					(justify left bottom)
					(hide yes)
				)
			)
			(property "Public" "False"
				(at 20.32 -17.78 0)
				(effects
					(font
						(size 1.27 1.27)
					)
					(justify left bottom)
					(hide yes)
				)
			)
			(property "License" "Apache-2.0"
				(at 21.59 -22.86 0)
				(effects
					(font
						(size 1.27 1.27)
						(thickness 0.15)
					)
					(justify left bottom)
					(hide yes)
				)
			)
			(property "ki_keywords" "SMT, SEMICONDUCTOR, DIODE, SCHOTTKY"
				(at 0 0 0)
				(effects
					(font
						(size 1.27 1.27)
					)
					(hide yes)
				)
			)
			(symbol "BAT54-02V-G3-08_0_1"
				(polyline
					(pts
						(xy 1.905 0) (xy 0.635 0)
					)
					(stroke
						(width 0)
						(type default)
					)
					(fill
						(type none)
					)
				)
				(polyline
					(pts
						(xy 4.445 0) (xy 3.175 0)
					)
					(stroke
						(width 0)
						(type default)
					)
					(fill
						(type none)
					)
				)
			)
			(symbol "BAT54-02V-G3-08_1_1"
				(polyline
					(pts
						(xy 1.778 1.016) (xy 1.778 -1.016)
					)
					(stroke
						(width 0.254)
						(type default)
					)
					(fill
						(type none)
					)
				)
				(polyline
					(pts
						(xy 1.778 1.016) (xy 1.397 1.016) (xy 1.397 0.762)
					)
					(stroke
						(width 0.254)
						(type default)
					)
					(fill
						(type none)
					)
				)
				(polyline
					(pts
						(xy 1.778 -1.016) (xy 2.159 -1.016) (xy 2.159 -0.762)
					)
					(stroke
						(width 0.254)
						(type default)
					)
					(fill
						(type none)
					)
				)
				(polyline
					(pts
						(xy 3.302 1.016) (xy 3.302 -1.016) (xy 1.778 0) (xy 3.302 1.016)
					)
					(stroke
						(width 0.254)
						(type default)
					)
					(fill
						(type outline)
					)
				)
				(pin passive line
					(at 0 0 0)
					(length 0.635)
					(name "C"
						(effects
							(font
								(size 1.27 1.27)
							)
						)
					)
					(number "1"
						(effects
							(font
								(size 1.27 1.27)
							)
						)
					)
				)
				(pin passive line
					(at 5.08 0 180)
					(length 0.635)
					(name "A"
						(effects
							(font
								(size 1.27 1.27)
							)
						)
					)
					(number "2"
						(effects
							(font
								(size 1.27 1.27)
							)
						)
					)
				)
			)
		)
	(symbol "antmicroDiodesRectifiersSingle:PMEG3050EP,115"
			(pin_names
				(hide yes)
			)
			(exclude_from_sim no)
			(in_bom yes)
			(on_board yes)
			(property "Reference" "D"
				(at 21.59 -5.08 0)
				(effects
					(font
						(size 1.27 1.27)
						(thickness 0.15)
					)
					(justify left bottom)
				)
			)
			(property "Value" "PMEG3050EP,115"
				(at 21.59 -7.62 0)
				(effects
					(font
						(size 1.27 1.27)
						(thickness 0.15)
					)
					(justify left bottom)
				)
			)
			(property "Footprint" "antmicro-footprints:Nexperia_SOD128"
				(at 21.59 -10.16 0)
				(effects
					(font
						(size 1.27 1.27)
						(thickness 0.15)
					)
					(justify left bottom)
					(hide yes)
				)
			)
			(property "Datasheet" "https://www.mouser.com/datasheet/2/916/PMEG3050EP-2938519.pdf"
				(at 21.59 -12.7 0)
				(effects
					(font
						(size 1.27 1.27)
						(thickness 0.15)
					)
					(justify left bottom)
					(hide yes)
				)
			)
			(property "Description" "Schottky Rectifier, 30 V, 5 A, Single, SOD-128, 2 Pins, 360 mV"
				(at 0 0 0)
				(effects
					(font
						(size 1.27 1.27)
					)
					(hide yes)
				)
			)
			(property "MPN" "PMEG3050EP,115"
				(at 21.59 -15.24 0)
				(effects
					(font
						(size 1.27 1.27)
						(thickness 0.15)
					)
					(justify left bottom)
					(hide yes)
				)
			)
			(property "Manufacturer" "Nexperia"
				(at 21.59 -17.78 0)
				(effects
					(font
						(size 1.27 1.27)
						(thickness 0.15)
					)
					(justify left bottom)
					(hide yes)
				)
			)
			(property "Author" "Antmicro"
				(at 21.59 -20.32 0)
				(effects
					(font
						(size 1.27 1.27)
						(thickness 0.15)
					)
					(justify left bottom)
					(hide yes)
				)
			)
			(property "License" "Apache-2.0"
				(at 21.59 -22.86 0)
				(effects
					(font
						(size 1.27 1.27)
						(thickness 0.15)
					)
					(justify left bottom)
					(hide yes)
				)
			)
			(property "ki_keywords" "SMT, DIODE, SEMICONDUCTOR, RECTIFIER, SCHOTTKY"
				(at 0 0 0)
				(effects
					(font
						(size 1.27 1.27)
					)
					(hide yes)
				)
			)
			(symbol "PMEG3050EP,115_0_1"
				(polyline
					(pts
						(xy 1.778 1.016) (xy 3.302 0) (xy 1.778 -1.016) (xy 1.778 1.016)
					)
					(stroke
						(width 0.254)
						(type default)
					)
					(fill
						(type outline)
					)
				)
				(polyline
					(pts
						(xy 3.302 1.016) (xy 3.302 -1.016)
					)
					(stroke
						(width 0.254)
						(type default)
					)
					(fill
						(type none)
					)
				)
				(polyline
					(pts
						(xy 3.302 0) (xy 1.778 0)
					)
					(stroke
						(width 0)
						(type default)
					)
					(fill
						(type none)
					)
				)
			)
			(symbol "PMEG3050EP,115_1_1"
				(polyline
					(pts
						(xy 3.302 1.016) (xy 3.302 1.651) (xy 2.667 1.651) (xy 2.667 1.016)
					)
					(stroke
						(width 0.254)
						(type default)
					)
					(fill
						(type none)
					)
				)
				(polyline
					(pts
						(xy 3.302 -1.016) (xy 3.302 -1.651) (xy 3.937 -1.651) (xy 3.937 -1.016)
					)
					(stroke
						(width 0.254)
						(type default)
					)
					(fill
						(type none)
					)
				)
				(pin passive line
					(at 0 0 0)
					(length 1.778)
					(name "2"
						(effects
							(font
								(size 1.27 1.27)
							)
						)
					)
					(number "2"
						(effects
							(font
								(size 1.27 1.27)
							)
						)
					)
				)
				(pin passive line
					(at 5.08 0 180)
					(length 1.778)
					(name "1"
						(effects
							(font
								(size 1.27 1.27)
							)
						)
					)
					(number "1"
						(effects
							(font
								(size 1.27 1.27)
							)
						)
					)
				)
			)
		)
	(symbol "antmicroDiodesZenerSingle:BZX84C5V1-TP"
			(pin_numbers
				(hide yes)
			)
			(pin_names
				(hide yes)
			)
			(exclude_from_sim no)
			(in_bom yes)
			(on_board yes)
			(property "Reference" "D"
				(at 22.86 -5.08 0)
				(effects
					(font
						(size 1.27 1.27)
						(thickness 0.15)
					)
					(justify left bottom)
				)
			)
			(property "Value" "BZX84C5V1-TP"
				(at 22.86 -15.24 0)
				(effects
					(font
						(size 1.27 1.27)
						(thickness 0.15)
					)
					(justify left bottom)
					(hide yes)
				)
			)
			(property "Footprint" "antmicro-footprints:SOT-23-3"
				(at 22.86 -10.16 0)
				(effects
					(font
						(size 1.27 1.27)
						(thickness 0.15)
					)
					(justify left bottom)
					(hide yes)
				)
			)
			(property "Datasheet" "https://www.mccsemi.com/pdf/Products/BZX84C(B)2V4~BZX84C(B)75(SOT-23).pdf"
				(at 22.86 -12.7 0)
				(effects
					(font
						(size 1.27 1.27)
						(thickness 0.15)
					)
					(justify left bottom)
					(hide yes)
				)
			)
			(property "Description" "Zener Single Diode, 5.1 V, 350 mW, SOT-23, 3 Pins, 150 °C, Surface Mount"
				(at 0 0 0)
				(effects
					(font
						(size 1.27 1.27)
					)
					(hide yes)
				)
			)
			(property "MPN" "BZX84C5V1-TP"
				(at 22.86 -7.62 0)
				(effects
					(font
						(size 1.27 1.27)
						(thickness 0.15)
					)
					(justify left bottom)
				)
			)
			(property "Manufacturer" "Micro Commercial Components"
				(at 22.86 -17.78 0)
				(effects
					(font
						(size 1.27 1.27)
						(thickness 0.15)
					)
					(justify left bottom)
					(hide yes)
				)
			)
			(property "Author" "Antmicro"
				(at 22.86 -20.32 0)
				(effects
					(font
						(size 1.27 1.27)
						(thickness 0.15)
					)
					(justify left bottom)
					(hide yes)
				)
			)
			(property "License" "Apache-2.0"
				(at 22.86 -22.86 0)
				(effects
					(font
						(size 1.27 1.27)
						(thickness 0.15)
					)
					(justify left bottom)
					(hide yes)
				)
			)
			(property "ki_keywords" "SMT, DIODE, SEMICONDUCTOR, ZENER"
				(at 0 0 0)
				(effects
					(font
						(size 1.27 1.27)
					)
					(hide yes)
				)
			)
			(symbol "BZX84C5V1-TP_0_1"
				(polyline
					(pts
						(xy 0.635 0) (xy 1.905 0)
					)
					(stroke
						(width 0)
						(type default)
					)
					(fill
						(type none)
					)
				)
				(polyline
					(pts
						(xy 3.175 0) (xy 4.445 0)
					)
					(stroke
						(width 0)
						(type default)
					)
					(fill
						(type none)
					)
				)
			)
			(symbol "BZX84C5V1-TP_1_1"
				(polyline
					(pts
						(xy 1.778 -1.016) (xy 1.778 1.016) (xy 3.302 0) (xy 1.778 -1.016)
					)
					(stroke
						(width 0.254)
						(type default)
					)
					(fill
						(type outline)
					)
				)
				(polyline
					(pts
						(xy 2.921 1.016) (xy 3.302 1.016)
					)
					(stroke
						(width 0.254)
						(type default)
					)
					(fill
						(type none)
					)
				)
				(polyline
					(pts
						(xy 3.302 -1.016) (xy 3.302 1.016)
					)
					(stroke
						(width 0.254)
						(type default)
					)
					(fill
						(type none)
					)
				)
				(pin passive line
					(at 0 0 0)
					(length 0.635)
					(name "A"
						(effects
							(font
								(size 1.27 1.27)
							)
						)
					)
					(number "1"
						(effects
							(font
								(size 1.27 1.27)
							)
						)
					)
				)
				(pin no_connect line
					(at 2.54 0 180)
					(length 2.54)
					(hide yes)
					(name "2"
						(effects
							(font
								(size 1.27 1.27)
							)
						)
					)
					(number "2"
						(effects
							(font
								(size 1.27 1.27)
							)
						)
					)
				)
				(pin passive line
					(at 5.08 0 180)
					(length 0.635)
					(name "C"
						(effects
							(font
								(size 1.27 1.27)
							)
						)
					)
					(number "3"
						(effects
							(font
								(size 1.27 1.27)
							)
						)
					)
				)
			)
		)
	(symbol "antmicroFPGAChips:XC7K410T-2FFG900I"
			(exclude_from_sim no)
			(in_bom yes)
			(on_board yes)
			(property "Reference" "U"
				(at 82.55 -2.54 0)
				(effects
					(font
						(size 1.27 1.27)
						(thickness 0.15)
					)
					(justify left bottom)
				)
			)
			(property "Value" "XC7K410T-2FFG900I"
				(at 82.55 -7.62 0)
				(effects
					(font
						(size 1.27 1.27)
						(thickness 0.15)
					)
					(justify left bottom)
					(hide yes)
				)
			)
			(property "Footprint" "antmicro-footprints:BGA-900_31x31mm_Layout30x30_P1x1mm_FFG900"
				(at 82.55 -10.16 0)
				(effects
					(font
						(size 1.27 1.27)
						(thickness 0.15)
					)
					(justify left bottom)
					(hide yes)
				)
			)
			(property "Datasheet" "https://eu.mouser.com/datasheet/2/903/ds180_7Series_Overview-1591537.pdf"
				(at 82.55 -12.7 0)
				(effects
					(font
						(size 1.27 1.27)
						(thickness 0.15)
					)
					(justify left bottom)
					(hide yes)
				)
			)
			(property "Description" "FPGA, Kintex-7, MMCM, PLL, 350 I/O's, 710 MHz, 406720 Cells, 970 mV to 1.03 V, FCBGA-900"
				(at 0 0 0)
				(effects
					(font
						(size 1.27 1.27)
					)
					(hide yes)
				)
			)
			(property "MPN" "XC7K410T-2FFG900I"
				(at 82.55 -5.08 0)
				(effects
					(font
						(size 1.27 1.27)
						(thickness 0.15)
					)
					(justify left bottom)
				)
			)
			(property "Manufacturer" "AMD-Xilinx"
				(at 82.55 -15.24 0)
				(effects
					(font
						(size 1.27 1.27)
						(thickness 0.15)
					)
					(justify left bottom)
					(hide yes)
				)
			)
			(property "Author" "Antmicro"
				(at 82.55 -17.78 0)
				(effects
					(font
						(size 1.27 1.27)
						(thickness 0.15)
					)
					(justify left bottom)
					(hide yes)
				)
			)
			(property "License" "Apache-2.0"
				(at 82.55 -20.32 0)
				(effects
					(font
						(size 1.27 1.27)
						(thickness 0.15)
					)
					(justify left bottom)
					(hide yes)
				)
			)
			(property "ki_locked" ""
				(at 0 0 0)
				(effects
					(font
						(size 1.27 1.27)
					)
				)
			)
			(property "ki_keywords" "SMT, MICROCONTROLLER, IC, FPGA"
				(at 0 0 0)
				(effects
					(font
						(size 1.27 1.27)
					)
					(hide yes)
				)
			)
			(symbol "XC7K410T-2FFG900I_1_1"
				(rectangle
					(start 5.08 5.08)
					(end 50.8 -130.81)
					(stroke
						(width 0.254)
						(type default)
					)
					(fill
						(type background)
					)
				)
				(text "BANK 12"
					(at 15.24 2.54 0)
					(effects
						(font
							(size 1.27 1.27)
							(thickness 0.15)
						)
						(justify left bottom)
					)
				)
				(text "BANK 13"
					(at 31.75 2.54 0)
					(effects
						(font
							(size 1.27 1.27)
							(thickness 0.15)
						)
						(justify left bottom)
					)
				)
				(pin bidirectional line
					(at 0 0 0)
					(length 5.08)
					(name "VCCO_12"
						(effects
							(font
								(size 1.27 1.27)
							)
						)
					)
					(number "AC23"
						(effects
							(font
								(size 1.27 1.27)
							)
						)
					)
				)
				(pin passive line
					(at 0 0 0)
					(length 5.08)
					(hide yes)
					(name "VCCO_12"
						(effects
							(font
								(size 1.27 1.27)
							)
						)
					)
					(number "AD20"
						(effects
							(font
								(size 1.27 1.27)
							)
						)
					)
				)
				(pin passive line
					(at 0 0 0)
					(length 5.08)
					(hide yes)
					(name "VCCO_12"
						(effects
							(font
								(size 1.27 1.27)
							)
						)
					)
					(number "AF24"
						(effects
							(font
								(size 1.27 1.27)
							)
						)
					)
				)
				(pin passive line
					(at 0 0 0)
					(length 5.08)
					(hide yes)
					(name "VCCO_12"
						(effects
							(font
								(size 1.27 1.27)
							)
						)
					)
					(number "AG21"
						(effects
							(font
								(size 1.27 1.27)
							)
						)
					)
				)
				(pin passive line
					(at 0 0 0)
					(length 5.08)
					(hide yes)
					(name "VCCO_12"
						(effects
							(font
								(size 1.27 1.27)
							)
						)
					)
					(number "AK22"
						(effects
							(font
								(size 1.27 1.27)
							)
						)
					)
				)
				(pin passive line
					(at 0 0 0)
					(length 5.08)
					(hide yes)
					(name "VCCO_12"
						(effects
							(font
								(size 1.27 1.27)
							)
						)
					)
					(number "Y22"
						(effects
							(font
								(size 1.27 1.27)
							)
						)
					)
				)
				(pin bidirectional line
					(at 0 -3.81 0)
					(length 5.08)
					(name "IO_0_12"
						(effects
							(font
								(size 1.27 1.27)
							)
						)
					)
					(number "Y20"
						(effects
							(font
								(size 1.27 1.27)
							)
						)
					)
				)
				(pin bidirectional line
					(at 0 -6.35 0)
					(length 5.08)
					(name "IO_L1P_T0_12"
						(effects
							(font
								(size 1.27 1.27)
							)
						)
					)
					(number "Y23"
						(effects
							(font
								(size 1.27 1.27)
							)
						)
					)
				)
				(pin bidirectional line
					(at 0 -8.89 0)
					(length 5.08)
					(name "IO_L1N_T0_12"
						(effects
							(font
								(size 1.27 1.27)
							)
						)
					)
					(number "Y24"
						(effects
							(font
								(size 1.27 1.27)
							)
						)
					)
				)
				(pin bidirectional line
					(at 0 -11.43 0)
					(length 5.08)
					(name "IO_L2P_T0_12"
						(effects
							(font
								(size 1.27 1.27)
							)
						)
					)
					(number "Y21"
						(effects
							(font
								(size 1.27 1.27)
							)
						)
					)
				)
				(pin bidirectional line
					(at 0 -13.97 0)
					(length 5.08)
					(name "IO_L2N_T0_12"
						(effects
							(font
								(size 1.27 1.27)
							)
						)
					)
					(number "AA21"
						(effects
							(font
								(size 1.27 1.27)
							)
						)
					)
				)
				(pin bidirectional line
					(at 0 -16.51 0)
					(length 5.08)
					(name "IO_L3P_T0_DQS_12"
						(effects
							(font
								(size 1.27 1.27)
							)
						)
					)
					(number "AB22"
						(effects
							(font
								(size 1.27 1.27)
							)
						)
					)
				)
				(pin bidirectional line
					(at 0 -19.05 0)
					(length 5.08)
					(name "IO_L3N_T0_DQS_12"
						(effects
							(font
								(size 1.27 1.27)
							)
						)
					)
					(number "AB23"
						(effects
							(font
								(size 1.27 1.27)
							)
						)
					)
				)
				(pin bidirectional line
					(at 0 -21.59 0)
					(length 5.08)
					(name "IO_L4P_T0_12"
						(effects
							(font
								(size 1.27 1.27)
							)
						)
					)
					(number "AA22"
						(effects
							(font
								(size 1.27 1.27)
							)
						)
					)
				)
				(pin bidirectional line
					(at 0 -24.13 0)
					(length 5.08)
					(name "IO_L4N_T0_12"
						(effects
							(font
								(size 1.27 1.27)
							)
						)
					)
					(number "AA23"
						(effects
							(font
								(size 1.27 1.27)
							)
						)
					)
				)
				(pin bidirectional line
					(at 0 -26.67 0)
					(length 5.08)
					(name "IO_L5P_T0_12"
						(effects
							(font
								(size 1.27 1.27)
							)
						)
					)
					(number "AC20"
						(effects
							(font
								(size 1.27 1.27)
							)
						)
					)
				)
				(pin bidirectional line
					(at 0 -29.21 0)
					(length 5.08)
					(name "IO_L5N_T0_12"
						(effects
							(font
								(size 1.27 1.27)
							)
						)
					)
					(number "AC21"
						(effects
							(font
								(size 1.27 1.27)
							)
						)
					)
				)
				(pin bidirectional line
					(at 0 -31.75 0)
					(length 5.08)
					(name "IO_L6P_T0_12"
						(effects
							(font
								(size 1.27 1.27)
							)
						)
					)
					(number "AA20"
						(effects
							(font
								(size 1.27 1.27)
							)
						)
					)
				)
				(pin bidirectional line
					(at 0 -34.29 0)
					(length 5.08)
					(name "IO_L6N_T0_VREF_12"
						(effects
							(font
								(size 1.27 1.27)
							)
						)
					)
					(number "AB20"
						(effects
							(font
								(size 1.27 1.27)
							)
						)
					)
				)
				(pin bidirectional line
					(at 0 -36.83 0)
					(length 5.08)
					(name "IO_L7P_T1_12"
						(effects
							(font
								(size 1.27 1.27)
							)
						)
					)
					(number "AB24"
						(effects
							(font
								(size 1.27 1.27)
							)
						)
					)
				)
				(pin bidirectional line
					(at 0 -39.37 0)
					(length 5.08)
					(name "IO_L7N_T1_12"
						(effects
							(font
								(size 1.27 1.27)
							)
						)
					)
					(number "AC25"
						(effects
							(font
								(size 1.27 1.27)
							)
						)
					)
				)
				(pin bidirectional line
					(at 0 -41.91 0)
					(length 5.08)
					(name "IO_L8P_T1_12"
						(effects
							(font
								(size 1.27 1.27)
							)
						)
					)
					(number "AC22"
						(effects
							(font
								(size 1.27 1.27)
							)
						)
					)
				)
				(pin bidirectional line
					(at 0 -44.45 0)
					(length 5.08)
					(name "IO_L8N_T1_12"
						(effects
							(font
								(size 1.27 1.27)
							)
						)
					)
					(number "AD22"
						(effects
							(font
								(size 1.27 1.27)
							)
						)
					)
				)
				(pin bidirectional line
					(at 0 -46.99 0)
					(length 5.08)
					(name "IO_L9P_T1_DQS_12"
						(effects
							(font
								(size 1.27 1.27)
							)
						)
					)
					(number "AC24"
						(effects
							(font
								(size 1.27 1.27)
							)
						)
					)
				)
				(pin bidirectional line
					(at 0 -49.53 0)
					(length 5.08)
					(name "IO_L9N_T1_DQS_12"
						(effects
							(font
								(size 1.27 1.27)
							)
						)
					)
					(number "AD24"
						(effects
							(font
								(size 1.27 1.27)
							)
						)
					)
				)
				(pin bidirectional line
					(at 0 -52.07 0)
					(length 5.08)
					(name "IO_L10P_T1_12"
						(effects
							(font
								(size 1.27 1.27)
							)
						)
					)
					(number "AD21"
						(effects
							(font
								(size 1.27 1.27)
							)
						)
					)
				)
				(pin bidirectional line
					(at 0 -54.61 0)
					(length 5.08)
					(name "IO_L10N_T1_12"
						(effects
							(font
								(size 1.27 1.27)
							)
						)
					)
					(number "AE21"
						(effects
							(font
								(size 1.27 1.27)
							)
						)
					)
				)
				(pin bidirectional line
					(at 0 -57.15 0)
					(length 5.08)
					(name "IO_L11P_T1_SRCC_12"
						(effects
							(font
								(size 1.27 1.27)
							)
						)
					)
					(number "AE23"
						(effects
							(font
								(size 1.27 1.27)
							)
						)
					)
				)
				(pin bidirectional line
					(at 0 -59.69 0)
					(length 5.08)
					(name "IO_L11N_T1_SRCC_12"
						(effects
							(font
								(size 1.27 1.27)
							)
						)
					)
					(number "AF23"
						(effects
							(font
								(size 1.27 1.27)
							)
						)
					)
				)
				(pin bidirectional line
					(at 0 -62.23 0)
					(length 5.08)
					(name "IO_L12P_T1_MRCC_12"
						(effects
							(font
								(size 1.27 1.27)
							)
						)
					)
					(number "AD23"
						(effects
							(font
								(size 1.27 1.27)
							)
						)
					)
				)
				(pin bidirectional line
					(at 0 -64.77 0)
					(length 5.08)
					(name "IO_L12N_T1_MRCC_12"
						(effects
							(font
								(size 1.27 1.27)
							)
						)
					)
					(number "AE24"
						(effects
							(font
								(size 1.27 1.27)
							)
						)
					)
				)
				(pin bidirectional line
					(at 0 -67.31 0)
					(length 5.08)
					(name "IO_L13P_T2_MRCC_12"
						(effects
							(font
								(size 1.27 1.27)
							)
						)
					)
					(number "AF22"
						(effects
							(font
								(size 1.27 1.27)
							)
						)
					)
				)
				(pin bidirectional line
					(at 0 -69.85 0)
					(length 5.08)
					(name "IO_L13N_T2_MRCC_12"
						(effects
							(font
								(size 1.27 1.27)
							)
						)
					)
					(number "AG23"
						(effects
							(font
								(size 1.27 1.27)
							)
						)
					)
				)
				(pin bidirectional line
					(at 0 -72.39 0)
					(length 5.08)
					(name "IO_L14P_T2_SRCC_12"
						(effects
							(font
								(size 1.27 1.27)
							)
						)
					)
					(number "AG24"
						(effects
							(font
								(size 1.27 1.27)
							)
						)
					)
				)
				(pin bidirectional line
					(at 0 -74.93 0)
					(length 5.08)
					(name "IO_L14N_T2_SRCC_12"
						(effects
							(font
								(size 1.27 1.27)
							)
						)
					)
					(number "AH24"
						(effects
							(font
								(size 1.27 1.27)
							)
						)
					)
				)
				(pin bidirectional line
					(at 0 -77.47 0)
					(length 5.08)
					(name "IO_L15P_T2_DQS_12"
						(effects
							(font
								(size 1.27 1.27)
							)
						)
					)
					(number "AJ24"
						(effects
							(font
								(size 1.27 1.27)
							)
						)
					)
				)
				(pin bidirectional line
					(at 0 -80.01 0)
					(length 5.08)
					(name "IO_L15N_T2_DQS_12"
						(effects
							(font
								(size 1.27 1.27)
							)
						)
					)
					(number "AK25"
						(effects
							(font
								(size 1.27 1.27)
							)
						)
					)
				)
				(pin bidirectional line
					(at 0 -82.55 0)
					(length 5.08)
					(name "IO_L16P_T2_12"
						(effects
							(font
								(size 1.27 1.27)
							)
						)
					)
					(number "AE25"
						(effects
							(font
								(size 1.27 1.27)
							)
						)
					)
				)
				(pin bidirectional line
					(at 0 -85.09 0)
					(length 5.08)
					(name "IO_L16N_T2_12"
						(effects
							(font
								(size 1.27 1.27)
							)
						)
					)
					(number "AF25"
						(effects
							(font
								(size 1.27 1.27)
							)
						)
					)
				)
				(pin bidirectional line
					(at 0 -87.63 0)
					(length 5.08)
					(name "IO_L17P_T2_12"
						(effects
							(font
								(size 1.27 1.27)
							)
						)
					)
					(number "AK23"
						(effects
							(font
								(size 1.27 1.27)
							)
						)
					)
				)
				(pin bidirectional line
					(at 0 -90.17 0)
					(length 5.08)
					(name "IO_L17N_T2_12"
						(effects
							(font
								(size 1.27 1.27)
							)
						)
					)
					(number "AK24"
						(effects
							(font
								(size 1.27 1.27)
							)
						)
					)
				)
				(pin bidirectional line
					(at 0 -92.71 0)
					(length 5.08)
					(name "IO_L18P_T2_12"
						(effects
							(font
								(size 1.27 1.27)
							)
						)
					)
					(number "AG25"
						(effects
							(font
								(size 1.27 1.27)
							)
						)
					)
				)
				(pin bidirectional line
					(at 0 -95.25 0)
					(length 5.08)
					(name "IO_L18N_T2_12"
						(effects
							(font
								(size 1.27 1.27)
							)
						)
					)
					(number "AH25"
						(effects
							(font
								(size 1.27 1.27)
							)
						)
					)
				)
				(pin bidirectional line
					(at 0 -97.79 0)
					(length 5.08)
					(name "IO_L19P_T3_12"
						(effects
							(font
								(size 1.27 1.27)
							)
						)
					)
					(number "AF20"
						(effects
							(font
								(size 1.27 1.27)
							)
						)
					)
				)
				(pin bidirectional line
					(at 0 -100.33 0)
					(length 5.08)
					(name "IO_L19N_T3_VREF_12"
						(effects
							(font
								(size 1.27 1.27)
							)
						)
					)
					(number "AF21"
						(effects
							(font
								(size 1.27 1.27)
							)
						)
					)
				)
				(pin bidirectional line
					(at 0 -102.87 0)
					(length 5.08)
					(name "IO_L20P_T3_12"
						(effects
							(font
								(size 1.27 1.27)
							)
						)
					)
					(number "AG22"
						(effects
							(font
								(size 1.27 1.27)
							)
						)
					)
				)
				(pin bidirectional line
					(at 0 -105.41 0)
					(length 5.08)
					(name "IO_L20N_T3_12"
						(effects
							(font
								(size 1.27 1.27)
							)
						)
					)
					(number "AH22"
						(effects
							(font
								(size 1.27 1.27)
							)
						)
					)
				)
				(pin bidirectional line
					(at 0 -107.95 0)
					(length 5.08)
					(name "IO_L21P_T3_DQS_12"
						(effects
							(font
								(size 1.27 1.27)
							)
						)
					)
					(number "AJ22"
						(effects
							(font
								(size 1.27 1.27)
							)
						)
					)
				)
				(pin bidirectional line
					(at 0 -110.49 0)
					(length 5.08)
					(name "IO_L21N_T3_DQS_12"
						(effects
							(font
								(size 1.27 1.27)
							)
						)
					)
					(number "AJ23"
						(effects
							(font
								(size 1.27 1.27)
							)
						)
					)
				)
				(pin bidirectional line
					(at 0 -113.03 0)
					(length 5.08)
					(name "IO_L22P_T3_12"
						(effects
							(font
								(size 1.27 1.27)
							)
						)
					)
					(number "AG20"
						(effects
							(font
								(size 1.27 1.27)
							)
						)
					)
				)
				(pin bidirectional line
					(at 0 -115.57 0)
					(length 5.08)
					(name "IO_L22N_T3_12"
						(effects
							(font
								(size 1.27 1.27)
							)
						)
					)
					(number "AH20"
						(effects
							(font
								(size 1.27 1.27)
							)
						)
					)
				)
				(pin bidirectional line
					(at 0 -118.11 0)
					(length 5.08)
					(name "IO_L23P_T3_12"
						(effects
							(font
								(size 1.27 1.27)
							)
						)
					)
					(number "AH21"
						(effects
							(font
								(size 1.27 1.27)
							)
						)
					)
				)
				(pin bidirectional line
					(at 0 -120.65 0)
					(length 5.08)
					(name "IO_L23N_T3_12"
						(effects
							(font
								(size 1.27 1.27)
							)
						)
					)
					(number "AJ21"
						(effects
							(font
								(size 1.27 1.27)
							)
						)
					)
				)
				(pin bidirectional line
					(at 0 -123.19 0)
					(length 5.08)
					(name "IO_L24P_T3_12"
						(effects
							(font
								(size 1.27 1.27)
							)
						)
					)
					(number "AK20"
						(effects
							(font
								(size 1.27 1.27)
							)
						)
					)
				)
				(pin bidirectional line
					(at 0 -125.73 0)
					(length 5.08)
					(name "IO_L24N_T3_12"
						(effects
							(font
								(size 1.27 1.27)
							)
						)
					)
					(number "AK21"
						(effects
							(font
								(size 1.27 1.27)
							)
						)
					)
				)
				(pin bidirectional line
					(at 0 -128.27 0)
					(length 5.08)
					(name "IO_25_12"
						(effects
							(font
								(size 1.27 1.27)
							)
						)
					)
					(number "AE20"
						(effects
							(font
								(size 1.27 1.27)
							)
						)
					)
				)
				(pin bidirectional line
					(at 55.88 0 180)
					(length 5.08)
					(name "VCCO_13"
						(effects
							(font
								(size 1.27 1.27)
							)
						)
					)
					(number "AA29"
						(effects
							(font
								(size 1.27 1.27)
							)
						)
					)
				)
				(pin passive line
					(at 55.88 0 180)
					(length 5.08)
					(hide yes)
					(name "VCCO_13"
						(effects
							(font
								(size 1.27 1.27)
							)
						)
					)
					(number "AB26"
						(effects
							(font
								(size 1.27 1.27)
							)
						)
					)
				)
				(pin passive line
					(at 55.88 0 180)
					(length 5.08)
					(hide yes)
					(name "VCCO_13"
						(effects
							(font
								(size 1.27 1.27)
							)
						)
					)
					(number "AD30"
						(effects
							(font
								(size 1.27 1.27)
							)
						)
					)
				)
				(pin passive line
					(at 55.88 0 180)
					(length 5.08)
					(hide yes)
					(name "VCCO_13"
						(effects
							(font
								(size 1.27 1.27)
							)
						)
					)
					(number "AE27"
						(effects
							(font
								(size 1.27 1.27)
							)
						)
					)
				)
				(pin passive line
					(at 55.88 0 180)
					(length 5.08)
					(hide yes)
					(name "VCCO_13"
						(effects
							(font
								(size 1.27 1.27)
							)
						)
					)
					(number "AH28"
						(effects
							(font
								(size 1.27 1.27)
							)
						)
					)
				)
				(pin passive line
					(at 55.88 0 180)
					(length 5.08)
					(hide yes)
					(name "VCCO_13"
						(effects
							(font
								(size 1.27 1.27)
							)
						)
					)
					(number "AJ25"
						(effects
							(font
								(size 1.27 1.27)
							)
						)
					)
				)
				(pin bidirectional line
					(at 55.88 -3.81 180)
					(length 5.08)
					(name "IO_0_13"
						(effects
							(font
								(size 1.27 1.27)
							)
						)
					)
					(number "Y25"
						(effects
							(font
								(size 1.27 1.27)
							)
						)
					)
				)
				(pin bidirectional line
					(at 55.88 -6.35 180)
					(length 5.08)
					(name "IO_L1P_T0_13"
						(effects
							(font
								(size 1.27 1.27)
							)
						)
					)
					(number "Y26"
						(effects
							(font
								(size 1.27 1.27)
							)
						)
					)
				)
				(pin bidirectional line
					(at 55.88 -8.89 180)
					(length 5.08)
					(name "IO_L1N_T0_13"
						(effects
							(font
								(size 1.27 1.27)
							)
						)
					)
					(number "AA26"
						(effects
							(font
								(size 1.27 1.27)
							)
						)
					)
				)
				(pin bidirectional line
					(at 55.88 -11.43 180)
					(length 5.08)
					(name "IO_L2P_T0_13"
						(effects
							(font
								(size 1.27 1.27)
							)
						)
					)
					(number "W27"
						(effects
							(font
								(size 1.27 1.27)
							)
						)
					)
				)
				(pin bidirectional line
					(at 55.88 -13.97 180)
					(length 5.08)
					(name "IO_L2N_T0_13"
						(effects
							(font
								(size 1.27 1.27)
							)
						)
					)
					(number "W28"
						(effects
							(font
								(size 1.27 1.27)
							)
						)
					)
				)
				(pin bidirectional line
					(at 55.88 -16.51 180)
					(length 5.08)
					(name "IO_L3P_T0_DQS_13"
						(effects
							(font
								(size 1.27 1.27)
							)
						)
					)
					(number "Y28"
						(effects
							(font
								(size 1.27 1.27)
							)
						)
					)
				)
				(pin bidirectional line
					(at 55.88 -19.05 180)
					(length 5.08)
					(name "IO_L3N_T0_DQS_13"
						(effects
							(font
								(size 1.27 1.27)
							)
						)
					)
					(number "AA28"
						(effects
							(font
								(size 1.27 1.27)
							)
						)
					)
				)
				(pin bidirectional line
					(at 55.88 -21.59 180)
					(length 5.08)
					(name "IO_L4P_T0_13"
						(effects
							(font
								(size 1.27 1.27)
							)
						)
					)
					(number "W29"
						(effects
							(font
								(size 1.27 1.27)
							)
						)
					)
				)
				(pin bidirectional line
					(at 55.88 -24.13 180)
					(length 5.08)
					(name "IO_L4N_T0_13"
						(effects
							(font
								(size 1.27 1.27)
							)
						)
					)
					(number "Y29"
						(effects
							(font
								(size 1.27 1.27)
							)
						)
					)
				)
				(pin bidirectional line
					(at 55.88 -26.67 180)
					(length 5.08)
					(name "IO_L5P_T0_13"
						(effects
							(font
								(size 1.27 1.27)
							)
						)
					)
					(number "AA27"
						(effects
							(font
								(size 1.27 1.27)
							)
						)
					)
				)
				(pin bidirectional line
					(at 55.88 -29.21 180)
					(length 5.08)
					(name "IO_L5N_T0_13"
						(effects
							(font
								(size 1.27 1.27)
							)
						)
					)
					(number "AB28"
						(effects
							(font
								(size 1.27 1.27)
							)
						)
					)
				)
				(pin bidirectional line
					(at 55.88 -31.75 180)
					(length 5.08)
					(name "IO_L6P_T0_13"
						(effects
							(font
								(size 1.27 1.27)
							)
						)
					)
					(number "AA25"
						(effects
							(font
								(size 1.27 1.27)
							)
						)
					)
				)
				(pin bidirectional line
					(at 55.88 -34.29 180)
					(length 5.08)
					(name "IO_L6N_T0_VREF_13"
						(effects
							(font
								(size 1.27 1.27)
							)
						)
					)
					(number "AB25"
						(effects
							(font
								(size 1.27 1.27)
							)
						)
					)
				)
				(pin bidirectional line
					(at 55.88 -36.83 180)
					(length 5.08)
					(name "IO_L7P_T1_13"
						(effects
							(font
								(size 1.27 1.27)
							)
						)
					)
					(number "AC29"
						(effects
							(font
								(size 1.27 1.27)
							)
						)
					)
				)
				(pin bidirectional line
					(at 55.88 -39.37 180)
					(length 5.08)
					(name "IO_L7N_T1_13"
						(effects
							(font
								(size 1.27 1.27)
							)
						)
					)
					(number "AC30"
						(effects
							(font
								(size 1.27 1.27)
							)
						)
					)
				)
				(pin bidirectional line
					(at 55.88 -41.91 180)
					(length 5.08)
					(name "IO_L8P_T1_13"
						(effects
							(font
								(size 1.27 1.27)
							)
						)
					)
					(number "Y30"
						(effects
							(font
								(size 1.27 1.27)
							)
						)
					)
				)
				(pin bidirectional line
					(at 55.88 -44.45 180)
					(length 5.08)
					(name "IO_L8N_T1_13"
						(effects
							(font
								(size 1.27 1.27)
							)
						)
					)
					(number "AA30"
						(effects
							(font
								(size 1.27 1.27)
							)
						)
					)
				)
				(pin bidirectional line
					(at 55.88 -46.99 180)
					(length 5.08)
					(name "IO_L9P_T1_DQS_13"
						(effects
							(font
								(size 1.27 1.27)
							)
						)
					)
					(number "AD29"
						(effects
							(font
								(size 1.27 1.27)
							)
						)
					)
				)
				(pin bidirectional line
					(at 55.88 -49.53 180)
					(length 5.08)
					(name "IO_L9N_T1_DQS_13"
						(effects
							(font
								(size 1.27 1.27)
							)
						)
					)
					(number "AE29"
						(effects
							(font
								(size 1.27 1.27)
							)
						)
					)
				)
				(pin bidirectional line
					(at 55.88 -52.07 180)
					(length 5.08)
					(name "IO_L10P_T1_13"
						(effects
							(font
								(size 1.27 1.27)
							)
						)
					)
					(number "AB29"
						(effects
							(font
								(size 1.27 1.27)
							)
						)
					)
				)
				(pin bidirectional line
					(at 55.88 -54.61 180)
					(length 5.08)
					(name "IO_L10N_T1_13"
						(effects
							(font
								(size 1.27 1.27)
							)
						)
					)
					(number "AB30"
						(effects
							(font
								(size 1.27 1.27)
							)
						)
					)
				)
				(pin bidirectional line
					(at 55.88 -57.15 180)
					(length 5.08)
					(name "IO_L11P_T1_SRCC_13"
						(effects
							(font
								(size 1.27 1.27)
							)
						)
					)
					(number "AD27"
						(effects
							(font
								(size 1.27 1.27)
							)
						)
					)
				)
				(pin bidirectional line
					(at 55.88 -59.69 180)
					(length 5.08)
					(name "IO_L11N_T1_SRCC_13"
						(effects
							(font
								(size 1.27 1.27)
							)
						)
					)
					(number "AD28"
						(effects
							(font
								(size 1.27 1.27)
							)
						)
					)
				)
				(pin bidirectional line
					(at 55.88 -62.23 180)
					(length 5.08)
					(name "IO_L12P_T1_MRCC_13"
						(effects
							(font
								(size 1.27 1.27)
							)
						)
					)
					(number "AB27"
						(effects
							(font
								(size 1.27 1.27)
							)
						)
					)
				)
				(pin bidirectional line
					(at 55.88 -64.77 180)
					(length 5.08)
					(name "IO_L12N_T1_MRCC_13"
						(effects
							(font
								(size 1.27 1.27)
							)
						)
					)
					(number "AC27"
						(effects
							(font
								(size 1.27 1.27)
							)
						)
					)
				)
				(pin bidirectional line
					(at 55.88 -67.31 180)
					(length 5.08)
					(name "IO_L13P_T2_MRCC_13"
						(effects
							(font
								(size 1.27 1.27)
							)
						)
					)
					(number "AG29"
						(effects
							(font
								(size 1.27 1.27)
							)
						)
					)
				)
				(pin bidirectional line
					(at 55.88 -69.85 180)
					(length 5.08)
					(name "IO_L13N_T2_MRCC_13"
						(effects
							(font
								(size 1.27 1.27)
							)
						)
					)
					(number "AH29"
						(effects
							(font
								(size 1.27 1.27)
							)
						)
					)
				)
				(pin bidirectional line
					(at 55.88 -72.39 180)
					(length 5.08)
					(name "IO_L14P_T2_SRCC_13"
						(effects
							(font
								(size 1.27 1.27)
							)
						)
					)
					(number "AE28"
						(effects
							(font
								(size 1.27 1.27)
							)
						)
					)
				)
				(pin bidirectional line
					(at 55.88 -74.93 180)
					(length 5.08)
					(name "IO_L14N_T2_SRCC_13"
						(effects
							(font
								(size 1.27 1.27)
							)
						)
					)
					(number "AF28"
						(effects
							(font
								(size 1.27 1.27)
							)
						)
					)
				)
				(pin bidirectional line
					(at 55.88 -77.47 180)
					(length 5.08)
					(name "IO_L15P_T2_DQS_13"
						(effects
							(font
								(size 1.27 1.27)
							)
						)
					)
					(number "AK29"
						(effects
							(font
								(size 1.27 1.27)
							)
						)
					)
				)
				(pin bidirectional line
					(at 55.88 -80.01 180)
					(length 5.08)
					(name "IO_L15N_T2_DQS_13"
						(effects
							(font
								(size 1.27 1.27)
							)
						)
					)
					(number "AK30"
						(effects
							(font
								(size 1.27 1.27)
							)
						)
					)
				)
				(pin bidirectional line
					(at 55.88 -82.55 180)
					(length 5.08)
					(name "IO_L16P_T2_13"
						(effects
							(font
								(size 1.27 1.27)
							)
						)
					)
					(number "AE30"
						(effects
							(font
								(size 1.27 1.27)
							)
						)
					)
				)
				(pin bidirectional line
					(at 55.88 -85.09 180)
					(length 5.08)
					(name "IO_L16N_T2_13"
						(effects
							(font
								(size 1.27 1.27)
							)
						)
					)
					(number "AF30"
						(effects
							(font
								(size 1.27 1.27)
							)
						)
					)
				)
				(pin bidirectional line
					(at 55.88 -87.63 180)
					(length 5.08)
					(name "IO_L17P_T2_13"
						(effects
							(font
								(size 1.27 1.27)
							)
						)
					)
					(number "AJ28"
						(effects
							(font
								(size 1.27 1.27)
							)
						)
					)
				)
				(pin bidirectional line
					(at 55.88 -90.17 180)
					(length 5.08)
					(name "IO_L17N_T2_13"
						(effects
							(font
								(size 1.27 1.27)
							)
						)
					)
					(number "AJ29"
						(effects
							(font
								(size 1.27 1.27)
							)
						)
					)
				)
				(pin bidirectional line
					(at 55.88 -92.71 180)
					(length 5.08)
					(name "IO_L18P_T2_13"
						(effects
							(font
								(size 1.27 1.27)
							)
						)
					)
					(number "AG30"
						(effects
							(font
								(size 1.27 1.27)
							)
						)
					)
				)
				(pin bidirectional line
					(at 55.88 -95.25 180)
					(length 5.08)
					(name "IO_L18N_T2_13"
						(effects
							(font
								(size 1.27 1.27)
							)
						)
					)
					(number "AH30"
						(effects
							(font
								(size 1.27 1.27)
							)
						)
					)
				)
				(pin bidirectional line
					(at 55.88 -97.79 180)
					(length 5.08)
					(name "IO_L19P_T3_13"
						(effects
							(font
								(size 1.27 1.27)
							)
						)
					)
					(number "AC26"
						(effects
							(font
								(size 1.27 1.27)
							)
						)
					)
				)
				(pin bidirectional line
					(at 55.88 -100.33 180)
					(length 5.08)
					(name "IO_L19N_T3_VREF_13"
						(effects
							(font
								(size 1.27 1.27)
							)
						)
					)
					(number "AD26"
						(effects
							(font
								(size 1.27 1.27)
							)
						)
					)
				)
				(pin bidirectional line
					(at 55.88 -102.87 180)
					(length 5.08)
					(name "IO_L20P_T3_13"
						(effects
							(font
								(size 1.27 1.27)
							)
						)
					)
					(number "AJ27"
						(effects
							(font
								(size 1.27 1.27)
							)
						)
					)
				)
				(pin bidirectional line
					(at 55.88 -105.41 180)
					(length 5.08)
					(name "IO_L20N_T3_13"
						(effects
							(font
								(size 1.27 1.27)
							)
						)
					)
					(number "AK28"
						(effects
							(font
								(size 1.27 1.27)
							)
						)
					)
				)
				(pin bidirectional line
					(at 55.88 -107.95 180)
					(length 5.08)
					(name "IO_L21P_T3_DQS_13"
						(effects
							(font
								(size 1.27 1.27)
							)
						)
					)
					(number "AG27"
						(effects
							(font
								(size 1.27 1.27)
							)
						)
					)
				)
				(pin bidirectional line
					(at 55.88 -110.49 180)
					(length 5.08)
					(name "IO_L21N_T3_DQS_13"
						(effects
							(font
								(size 1.27 1.27)
							)
						)
					)
					(number "AG28"
						(effects
							(font
								(size 1.27 1.27)
							)
						)
					)
				)
				(pin bidirectional line
					(at 55.88 -113.03 180)
					(length 5.08)
					(name "IO_L22P_T3_13"
						(effects
							(font
								(size 1.27 1.27)
							)
						)
					)
					(number "AH26"
						(effects
							(font
								(size 1.27 1.27)
							)
						)
					)
				)
				(pin bidirectional line
					(at 55.88 -115.57 180)
					(length 5.08)
					(name "IO_L22N_T3_13"
						(effects
							(font
								(size 1.27 1.27)
							)
						)
					)
					(number "AH27"
						(effects
							(font
								(size 1.27 1.27)
							)
						)
					)
				)
				(pin bidirectional line
					(at 55.88 -118.11 180)
					(length 5.08)
					(name "IO_L23P_T3_13"
						(effects
							(font
								(size 1.27 1.27)
							)
						)
					)
					(number "AF26"
						(effects
							(font
								(size 1.27 1.27)
							)
						)
					)
				)
				(pin bidirectional line
					(at 55.88 -120.65 180)
					(length 5.08)
					(name "IO_L23N_T3_13"
						(effects
							(font
								(size 1.27 1.27)
							)
						)
					)
					(number "AF27"
						(effects
							(font
								(size 1.27 1.27)
							)
						)
					)
				)
				(pin bidirectional line
					(at 55.88 -123.19 180)
					(length 5.08)
					(name "IO_L24P_T3_13"
						(effects
							(font
								(size 1.27 1.27)
							)
						)
					)
					(number "AJ26"
						(effects
							(font
								(size 1.27 1.27)
							)
						)
					)
				)
				(pin bidirectional line
					(at 55.88 -125.73 180)
					(length 5.08)
					(name "IO_L24N_T3_13"
						(effects
							(font
								(size 1.27 1.27)
							)
						)
					)
					(number "AK26"
						(effects
							(font
								(size 1.27 1.27)
							)
						)
					)
				)
				(pin bidirectional line
					(at 55.88 -128.27 180)
					(length 5.08)
					(name "IO_25_13"
						(effects
							(font
								(size 1.27 1.27)
							)
						)
					)
					(number "AE26"
						(effects
							(font
								(size 1.27 1.27)
							)
						)
					)
				)
			)
			(symbol "XC7K410T-2FFG900I_2_1"
				(rectangle
					(start 5.08 5.08)
					(end 64.77 -130.81)
					(stroke
						(width 0.254)
						(type default)
					)
					(fill
						(type background)
					)
				)
				(text "BANK 14"
					(at 15.24 2.54 0)
					(effects
						(font
							(size 1.27 1.27)
							(thickness 0.15)
						)
						(justify left bottom)
					)
				)
				(text "BANK 15"
					(at 45.72 2.54 0)
					(effects
						(font
							(size 1.27 1.27)
							(thickness 0.15)
						)
						(justify left bottom)
					)
				)
				(pin bidirectional line
					(at 0 0 0)
					(length 5.08)
					(name "VCCO_14"
						(effects
							(font
								(size 1.27 1.27)
							)
						)
					)
					(number "P30"
						(effects
							(font
								(size 1.27 1.27)
							)
						)
					)
				)
				(pin passive line
					(at 0 0 0)
					(length 5.08)
					(hide yes)
					(name "VCCO_14"
						(effects
							(font
								(size 1.27 1.27)
							)
						)
					)
					(number "R27"
						(effects
							(font
								(size 1.27 1.27)
							)
						)
					)
				)
				(pin passive line
					(at 0 0 0)
					(length 5.08)
					(hide yes)
					(name "VCCO_14"
						(effects
							(font
								(size 1.27 1.27)
							)
						)
					)
					(number "T24"
						(effects
							(font
								(size 1.27 1.27)
							)
						)
					)
				)
				(pin passive line
					(at 0 0 0)
					(length 5.08)
					(hide yes)
					(name "VCCO_14"
						(effects
							(font
								(size 1.27 1.27)
							)
						)
					)
					(number "U21"
						(effects
							(font
								(size 1.27 1.27)
							)
						)
					)
				)
				(pin passive line
					(at 0 0 0)
					(length 5.08)
					(hide yes)
					(name "VCCO_14"
						(effects
							(font
								(size 1.27 1.27)
							)
						)
					)
					(number "V28"
						(effects
							(font
								(size 1.27 1.27)
							)
						)
					)
				)
				(pin passive line
					(at 0 0 0)
					(length 5.08)
					(hide yes)
					(name "VCCO_14"
						(effects
							(font
								(size 1.27 1.27)
							)
						)
					)
					(number "W25"
						(effects
							(font
								(size 1.27 1.27)
							)
						)
					)
				)
				(pin bidirectional line
					(at 0 -3.81 0)
					(length 5.08)
					(name "IO_0_14"
						(effects
							(font
								(size 1.27 1.27)
							)
						)
					)
					(number "R19"
						(effects
							(font
								(size 1.27 1.27)
							)
						)
					)
				)
				(pin bidirectional line
					(at 0 -6.35 0)
					(length 5.08)
					(name "IO_L1P_T0_D00_MOSI_14"
						(effects
							(font
								(size 1.27 1.27)
							)
						)
					)
					(number "P24"
						(effects
							(font
								(size 1.27 1.27)
							)
						)
					)
				)
				(pin bidirectional line
					(at 0 -8.89 0)
					(length 5.08)
					(name "IO_L1N_T0_D01_DIN_14"
						(effects
							(font
								(size 1.27 1.27)
							)
						)
					)
					(number "R25"
						(effects
							(font
								(size 1.27 1.27)
							)
						)
					)
				)
				(pin bidirectional line
					(at 0 -11.43 0)
					(length 5.08)
					(name "IO_L2P_T0_D02_14"
						(effects
							(font
								(size 1.27 1.27)
							)
						)
					)
					(number "R20"
						(effects
							(font
								(size 1.27 1.27)
							)
						)
					)
				)
				(pin bidirectional line
					(at 0 -13.97 0)
					(length 5.08)
					(name "IO_L2N_T0_D03_14"
						(effects
							(font
								(size 1.27 1.27)
							)
						)
					)
					(number "R21"
						(effects
							(font
								(size 1.27 1.27)
							)
						)
					)
				)
				(pin bidirectional line
					(at 0 -16.51 0)
					(length 5.08)
					(name "IO_L3P_T0_DQS_PUDC_B_14"
						(effects
							(font
								(size 1.27 1.27)
							)
						)
					)
					(number "R23"
						(effects
							(font
								(size 1.27 1.27)
							)
						)
					)
				)
				(pin bidirectional line
					(at 0 -19.05 0)
					(length 5.08)
					(name "IO_L3N_T0_DQS_EMCCLK_14"
						(effects
							(font
								(size 1.27 1.27)
							)
						)
					)
					(number "R24"
						(effects
							(font
								(size 1.27 1.27)
							)
						)
					)
				)
				(pin bidirectional line
					(at 0 -21.59 0)
					(length 5.08)
					(name "IO_L4P_T0_D04_14"
						(effects
							(font
								(size 1.27 1.27)
							)
						)
					)
					(number "T20"
						(effects
							(font
								(size 1.27 1.27)
							)
						)
					)
				)
				(pin bidirectional line
					(at 0 -24.13 0)
					(length 5.08)
					(name "IO_L4N_T0_D05_14"
						(effects
							(font
								(size 1.27 1.27)
							)
						)
					)
					(number "T21"
						(effects
							(font
								(size 1.27 1.27)
							)
						)
					)
				)
				(pin bidirectional line
					(at 0 -26.67 0)
					(length 5.08)
					(name "IO_L5P_T0_D06_14"
						(effects
							(font
								(size 1.27 1.27)
							)
						)
					)
					(number "T22"
						(effects
							(font
								(size 1.27 1.27)
							)
						)
					)
				)
				(pin bidirectional line
					(at 0 -29.21 0)
					(length 5.08)
					(name "IO_L5N_T0_D07_14"
						(effects
							(font
								(size 1.27 1.27)
							)
						)
					)
					(number "T23"
						(effects
							(font
								(size 1.27 1.27)
							)
						)
					)
				)
				(pin bidirectional line
					(at 0 -31.75 0)
					(length 5.08)
					(name "IO_L6P_T0_FCS_B_14"
						(effects
							(font
								(size 1.27 1.27)
							)
						)
					)
					(number "U19"
						(effects
							(font
								(size 1.27 1.27)
							)
						)
					)
				)
				(pin bidirectional line
					(at 0 -34.29 0)
					(length 5.08)
					(name "IO_L6N_T0_D08_VREF_14"
						(effects
							(font
								(size 1.27 1.27)
							)
						)
					)
					(number "U20"
						(effects
							(font
								(size 1.27 1.27)
							)
						)
					)
				)
				(pin bidirectional line
					(at 0 -36.83 0)
					(length 5.08)
					(name "IO_L7P_T1_D09_14"
						(effects
							(font
								(size 1.27 1.27)
							)
						)
					)
					(number "P29"
						(effects
							(font
								(size 1.27 1.27)
							)
						)
					)
				)
				(pin bidirectional line
					(at 0 -39.37 0)
					(length 5.08)
					(name "IO_L7N_T1_D10_14"
						(effects
							(font
								(size 1.27 1.27)
							)
						)
					)
					(number "R29"
						(effects
							(font
								(size 1.27 1.27)
							)
						)
					)
				)
				(pin bidirectional line
					(at 0 -41.91 0)
					(length 5.08)
					(name "IO_L8P_T1_D11_14"
						(effects
							(font
								(size 1.27 1.27)
							)
						)
					)
					(number "P27"
						(effects
							(font
								(size 1.27 1.27)
							)
						)
					)
				)
				(pin bidirectional line
					(at 0 -44.45 0)
					(length 5.08)
					(name "IO_L8N_T1_D12_14"
						(effects
							(font
								(size 1.27 1.27)
							)
						)
					)
					(number "P28"
						(effects
							(font
								(size 1.27 1.27)
							)
						)
					)
				)
				(pin bidirectional line
					(at 0 -46.99 0)
					(length 5.08)
					(name "IO_L9P_T1_DQS_14"
						(effects
							(font
								(size 1.27 1.27)
							)
						)
					)
					(number "R30"
						(effects
							(font
								(size 1.27 1.27)
							)
						)
					)
				)
				(pin bidirectional line
					(at 0 -49.53 0)
					(length 5.08)
					(name "IO_L9N_T1_DQS_D13_14"
						(effects
							(font
								(size 1.27 1.27)
							)
						)
					)
					(number "T30"
						(effects
							(font
								(size 1.27 1.27)
							)
						)
					)
				)
				(pin bidirectional line
					(at 0 -52.07 0)
					(length 5.08)
					(name "IO_L10P_T1_D14_14"
						(effects
							(font
								(size 1.27 1.27)
							)
						)
					)
					(number "P26"
						(effects
							(font
								(size 1.27 1.27)
							)
						)
					)
				)
				(pin bidirectional line
					(at 0 -54.61 0)
					(length 5.08)
					(name "IO_L10N_T1_D15_14"
						(effects
							(font
								(size 1.27 1.27)
							)
						)
					)
					(number "R26"
						(effects
							(font
								(size 1.27 1.27)
							)
						)
					)
				)
				(pin bidirectional line
					(at 0 -57.15 0)
					(length 5.08)
					(name "IO_L11P_T1_SRCC_14"
						(effects
							(font
								(size 1.27 1.27)
							)
						)
					)
					(number "R28"
						(effects
							(font
								(size 1.27 1.27)
							)
						)
					)
				)
				(pin bidirectional line
					(at 0 -59.69 0)
					(length 5.08)
					(name "IO_L11N_T1_SRCC_14"
						(effects
							(font
								(size 1.27 1.27)
							)
						)
					)
					(number "T28"
						(effects
							(font
								(size 1.27 1.27)
							)
						)
					)
				)
				(pin bidirectional line
					(at 0 -62.23 0)
					(length 5.08)
					(name "IO_L12P_T1_MRCC_14"
						(effects
							(font
								(size 1.27 1.27)
							)
						)
					)
					(number "T26"
						(effects
							(font
								(size 1.27 1.27)
							)
						)
					)
				)
				(pin bidirectional line
					(at 0 -64.77 0)
					(length 5.08)
					(name "IO_L12N_T1_MRCC_14"
						(effects
							(font
								(size 1.27 1.27)
							)
						)
					)
					(number "T27"
						(effects
							(font
								(size 1.27 1.27)
							)
						)
					)
				)
				(pin bidirectional line
					(at 0 -67.31 0)
					(length 5.08)
					(name "IO_L13P_T2_MRCC_14"
						(effects
							(font
								(size 1.27 1.27)
							)
						)
					)
					(number "U27"
						(effects
							(font
								(size 1.27 1.27)
							)
						)
					)
				)
				(pin bidirectional line
					(at 0 -69.85 0)
					(length 5.08)
					(name "IO_L13N_T2_MRCC_14"
						(effects
							(font
								(size 1.27 1.27)
							)
						)
					)
					(number "U28"
						(effects
							(font
								(size 1.27 1.27)
							)
						)
					)
				)
				(pin bidirectional line
					(at 0 -72.39 0)
					(length 5.08)
					(name "IO_L14P_T2_SRCC_14"
						(effects
							(font
								(size 1.27 1.27)
							)
						)
					)
					(number "T25"
						(effects
							(font
								(size 1.27 1.27)
							)
						)
					)
				)
				(pin bidirectional line
					(at 0 -74.93 0)
					(length 5.08)
					(name "IO_L14N_T2_SRCC_14"
						(effects
							(font
								(size 1.27 1.27)
							)
						)
					)
					(number "U25"
						(effects
							(font
								(size 1.27 1.27)
							)
						)
					)
				)
				(pin bidirectional line
					(at 0 -77.47 0)
					(length 5.08)
					(name "IO_L15P_T2_DQS_RDWR_B_14"
						(effects
							(font
								(size 1.27 1.27)
							)
						)
					)
					(number "U29"
						(effects
							(font
								(size 1.27 1.27)
							)
						)
					)
				)
				(pin bidirectional line
					(at 0 -80.01 0)
					(length 5.08)
					(name "IO_L15N_T2_DQS_DOUT_CSO_B_14"
						(effects
							(font
								(size 1.27 1.27)
							)
						)
					)
					(number "U30"
						(effects
							(font
								(size 1.27 1.27)
							)
						)
					)
				)
				(pin bidirectional line
					(at 0 -82.55 0)
					(length 5.08)
					(name "IO_L16P_T2_CSI_B_14"
						(effects
							(font
								(size 1.27 1.27)
							)
						)
					)
					(number "V26"
						(effects
							(font
								(size 1.27 1.27)
							)
						)
					)
				)
				(pin bidirectional line
					(at 0 -85.09 0)
					(length 5.08)
					(name "IO_L16N_T2_A15_D31_14"
						(effects
							(font
								(size 1.27 1.27)
							)
						)
					)
					(number "V27"
						(effects
							(font
								(size 1.27 1.27)
							)
						)
					)
				)
				(pin bidirectional line
					(at 0 -87.63 0)
					(length 5.08)
					(name "IO_L17P_T2_A14_D30_14"
						(effects
							(font
								(size 1.27 1.27)
							)
						)
					)
					(number "V29"
						(effects
							(font
								(size 1.27 1.27)
							)
						)
					)
				)
				(pin bidirectional line
					(at 0 -90.17 0)
					(length 5.08)
					(name "IO_L17N_T2_A13_D29_14"
						(effects
							(font
								(size 1.27 1.27)
							)
						)
					)
					(number "V30"
						(effects
							(font
								(size 1.27 1.27)
							)
						)
					)
				)
				(pin bidirectional line
					(at 0 -92.71 0)
					(length 5.08)
					(name "IO_L18P_T2_A12_D28_14"
						(effects
							(font
								(size 1.27 1.27)
							)
						)
					)
					(number "V25"
						(effects
							(font
								(size 1.27 1.27)
							)
						)
					)
				)
				(pin bidirectional line
					(at 0 -95.25 0)
					(length 5.08)
					(name "IO_L18N_T2_A11_D27_14"
						(effects
							(font
								(size 1.27 1.27)
							)
						)
					)
					(number "W26"
						(effects
							(font
								(size 1.27 1.27)
							)
						)
					)
				)
				(pin bidirectional line
					(at 0 -97.79 0)
					(length 5.08)
					(name "IO_L19P_T3_A10_D26_14"
						(effects
							(font
								(size 1.27 1.27)
							)
						)
					)
					(number "V19"
						(effects
							(font
								(size 1.27 1.27)
							)
						)
					)
				)
				(pin bidirectional line
					(at 0 -100.33 0)
					(length 5.08)
					(name "IO_L19N_T3_A09_D25_VREF_14"
						(effects
							(font
								(size 1.27 1.27)
							)
						)
					)
					(number "V20"
						(effects
							(font
								(size 1.27 1.27)
							)
						)
					)
				)
				(pin bidirectional line
					(at 0 -102.87 0)
					(length 5.08)
					(name "IO_L20P_T3_A08_D24_14"
						(effects
							(font
								(size 1.27 1.27)
							)
						)
					)
					(number "W23"
						(effects
							(font
								(size 1.27 1.27)
							)
						)
					)
				)
				(pin bidirectional line
					(at 0 -105.41 0)
					(length 5.08)
					(name "IO_L20N_T3_A07_D23_14"
						(effects
							(font
								(size 1.27 1.27)
							)
						)
					)
					(number "W24"
						(effects
							(font
								(size 1.27 1.27)
							)
						)
					)
				)
				(pin bidirectional line
					(at 0 -107.95 0)
					(length 5.08)
					(name "IO_L21P_T3_DQS_14"
						(effects
							(font
								(size 1.27 1.27)
							)
						)
					)
					(number "U22"
						(effects
							(font
								(size 1.27 1.27)
							)
						)
					)
				)
				(pin bidirectional line
					(at 0 -110.49 0)
					(length 5.08)
					(name "IO_L21N_T3_DQS_A06_D22_14"
						(effects
							(font
								(size 1.27 1.27)
							)
						)
					)
					(number "U23"
						(effects
							(font
								(size 1.27 1.27)
							)
						)
					)
				)
				(pin bidirectional line
					(at 0 -113.03 0)
					(length 5.08)
					(name "IO_L22P_T3_A05_D21_14"
						(effects
							(font
								(size 1.27 1.27)
							)
						)
					)
					(number "V21"
						(effects
							(font
								(size 1.27 1.27)
							)
						)
					)
				)
				(pin bidirectional line
					(at 0 -115.57 0)
					(length 5.08)
					(name "IO_L22N_T3_A04_D20_14"
						(effects
							(font
								(size 1.27 1.27)
							)
						)
					)
					(number "V22"
						(effects
							(font
								(size 1.27 1.27)
							)
						)
					)
				)
				(pin bidirectional line
					(at 0 -118.11 0)
					(length 5.08)
					(name "IO_L23P_T3_A03_D19_14"
						(effects
							(font
								(size 1.27 1.27)
							)
						)
					)
					(number "U24"
						(effects
							(font
								(size 1.27 1.27)
							)
						)
					)
				)
				(pin bidirectional line
					(at 0 -120.65 0)
					(length 5.08)
					(name "IO_L23N_T3_A02_D18_14"
						(effects
							(font
								(size 1.27 1.27)
							)
						)
					)
					(number "V24"
						(effects
							(font
								(size 1.27 1.27)
							)
						)
					)
				)
				(pin bidirectional line
					(at 0 -123.19 0)
					(length 5.08)
					(name "IO_L24P_T3_A01_D17_14"
						(effects
							(font
								(size 1.27 1.27)
							)
						)
					)
					(number "W21"
						(effects
							(font
								(size 1.27 1.27)
							)
						)
					)
				)
				(pin bidirectional line
					(at 0 -125.73 0)
					(length 5.08)
					(name "IO_L24N_T3_A00_D16_14"
						(effects
							(font
								(size 1.27 1.27)
							)
						)
					)
					(number "W22"
						(effects
							(font
								(size 1.27 1.27)
							)
						)
					)
				)
				(pin bidirectional line
					(at 0 -128.27 0)
					(length 5.08)
					(name "IO_25_14"
						(effects
							(font
								(size 1.27 1.27)
							)
						)
					)
					(number "W19"
						(effects
							(font
								(size 1.27 1.27)
							)
						)
					)
				)
				(pin bidirectional line
					(at 69.85 0 180)
					(length 5.08)
					(name "VCCO_15"
						(effects
							(font
								(size 1.27 1.27)
							)
						)
					)
					(number "J25"
						(effects
							(font
								(size 1.27 1.27)
							)
						)
					)
				)
				(pin passive line
					(at 69.85 0 180)
					(length 5.08)
					(hide yes)
					(name "VCCO_15"
						(effects
							(font
								(size 1.27 1.27)
							)
						)
					)
					(number "K22"
						(effects
							(font
								(size 1.27 1.27)
							)
						)
					)
				)
				(pin passive line
					(at 69.85 0 180)
					(length 5.08)
					(hide yes)
					(name "VCCO_15"
						(effects
							(font
								(size 1.27 1.27)
							)
						)
					)
					(number "L29"
						(effects
							(font
								(size 1.27 1.27)
							)
						)
					)
				)
				(pin passive line
					(at 69.85 0 180)
					(length 5.08)
					(hide yes)
					(name "VCCO_15"
						(effects
							(font
								(size 1.27 1.27)
							)
						)
					)
					(number "M26"
						(effects
							(font
								(size 1.27 1.27)
							)
						)
					)
				)
				(pin passive line
					(at 69.85 0 180)
					(length 5.08)
					(hide yes)
					(name "VCCO_15"
						(effects
							(font
								(size 1.27 1.27)
							)
						)
					)
					(number "N23"
						(effects
							(font
								(size 1.27 1.27)
							)
						)
					)
				)
				(pin passive line
					(at 69.85 0 180)
					(length 5.08)
					(hide yes)
					(name "VCCO_15"
						(effects
							(font
								(size 1.27 1.27)
							)
						)
					)
					(number "P20"
						(effects
							(font
								(size 1.27 1.27)
							)
						)
					)
				)
				(pin bidirectional line
					(at 69.85 -3.81 180)
					(length 5.08)
					(name "IO_0_15"
						(effects
							(font
								(size 1.27 1.27)
							)
						)
					)
					(number "M19"
						(effects
							(font
								(size 1.27 1.27)
							)
						)
					)
				)
				(pin bidirectional line
					(at 69.85 -6.35 180)
					(length 5.08)
					(name "IO_L1P_T0_AD0P_15"
						(effects
							(font
								(size 1.27 1.27)
							)
						)
					)
					(number "J23"
						(effects
							(font
								(size 1.27 1.27)
							)
						)
					)
				)
				(pin bidirectional line
					(at 69.85 -8.89 180)
					(length 5.08)
					(name "IO_L1N_T0_AD0N_15"
						(effects
							(font
								(size 1.27 1.27)
							)
						)
					)
					(number "J24"
						(effects
							(font
								(size 1.27 1.27)
							)
						)
					)
				)
				(pin bidirectional line
					(at 69.85 -11.43 180)
					(length 5.08)
					(name "IO_L2P_T0_AD8P_15"
						(effects
							(font
								(size 1.27 1.27)
							)
						)
					)
					(number "L22"
						(effects
							(font
								(size 1.27 1.27)
							)
						)
					)
				)
				(pin bidirectional line
					(at 69.85 -13.97 180)
					(length 5.08)
					(name "IO_L2N_T0_AD8N_15"
						(effects
							(font
								(size 1.27 1.27)
							)
						)
					)
					(number "L23"
						(effects
							(font
								(size 1.27 1.27)
							)
						)
					)
				)
				(pin bidirectional line
					(at 69.85 -16.51 180)
					(length 5.08)
					(name "IO_L3P_T0_DQS_AD1P_15"
						(effects
							(font
								(size 1.27 1.27)
							)
						)
					)
					(number "K23"
						(effects
							(font
								(size 1.27 1.27)
							)
						)
					)
				)
				(pin bidirectional line
					(at 69.85 -19.05 180)
					(length 5.08)
					(name "IO_L3N_T0_DQS_AD1N_15"
						(effects
							(font
								(size 1.27 1.27)
							)
						)
					)
					(number "K24"
						(effects
							(font
								(size 1.27 1.27)
							)
						)
					)
				)
				(pin bidirectional line
					(at 69.85 -21.59 180)
					(length 5.08)
					(name "IO_L4P_T0_AD9P_15"
						(effects
							(font
								(size 1.27 1.27)
							)
						)
					)
					(number "L21"
						(effects
							(font
								(size 1.27 1.27)
							)
						)
					)
				)
				(pin bidirectional line
					(at 69.85 -24.13 180)
					(length 5.08)
					(name "IO_L4N_T0_AD9N_15"
						(effects
							(font
								(size 1.27 1.27)
							)
						)
					)
					(number "K21"
						(effects
							(font
								(size 1.27 1.27)
							)
						)
					)
				)
				(pin bidirectional line
					(at 69.85 -26.67 180)
					(length 5.08)
					(name "IO_L5P_T0_AD2P_15"
						(effects
							(font
								(size 1.27 1.27)
							)
						)
					)
					(number "J21"
						(effects
							(font
								(size 1.27 1.27)
							)
						)
					)
				)
				(pin bidirectional line
					(at 69.85 -29.21 180)
					(length 5.08)
					(name "IO_L5N_T0_AD2N_15"
						(effects
							(font
								(size 1.27 1.27)
							)
						)
					)
					(number "J22"
						(effects
							(font
								(size 1.27 1.27)
							)
						)
					)
				)
				(pin bidirectional line
					(at 69.85 -31.75 180)
					(length 5.08)
					(name "IO_L6P_T0_15"
						(effects
							(font
								(size 1.27 1.27)
							)
						)
					)
					(number "M20"
						(effects
							(font
								(size 1.27 1.27)
							)
						)
					)
				)
				(pin bidirectional line
					(at 69.85 -34.29 180)
					(length 5.08)
					(name "IO_L6N_T0_VREF_15"
						(effects
							(font
								(size 1.27 1.27)
							)
						)
					)
					(number "L20"
						(effects
							(font
								(size 1.27 1.27)
							)
						)
					)
				)
				(pin bidirectional line
					(at 69.85 -36.83 180)
					(length 5.08)
					(name "IO_L7P_T1_AD10P_15"
						(effects
							(font
								(size 1.27 1.27)
							)
						)
					)
					(number "J29"
						(effects
							(font
								(size 1.27 1.27)
							)
						)
					)
				)
				(pin bidirectional line
					(at 69.85 -39.37 180)
					(length 5.08)
					(name "IO_L7N_T1_AD10N_15"
						(effects
							(font
								(size 1.27 1.27)
							)
						)
					)
					(number "H29"
						(effects
							(font
								(size 1.27 1.27)
							)
						)
					)
				)
				(pin bidirectional line
					(at 69.85 -41.91 180)
					(length 5.08)
					(name "IO_L8P_T1_AD3P_15"
						(effects
							(font
								(size 1.27 1.27)
							)
						)
					)
					(number "J27"
						(effects
							(font
								(size 1.27 1.27)
							)
						)
					)
				)
				(pin bidirectional line
					(at 69.85 -44.45 180)
					(length 5.08)
					(name "IO_L8N_T1_AD3N_15"
						(effects
							(font
								(size 1.27 1.27)
							)
						)
					)
					(number "J28"
						(effects
							(font
								(size 1.27 1.27)
							)
						)
					)
				)
				(pin bidirectional line
					(at 69.85 -46.99 180)
					(length 5.08)
					(name "IO_L9P_T1_DQS_AD11P_15"
						(effects
							(font
								(size 1.27 1.27)
							)
						)
					)
					(number "L30"
						(effects
							(font
								(size 1.27 1.27)
							)
						)
					)
				)
				(pin bidirectional line
					(at 69.85 -49.53 180)
					(length 5.08)
					(name "IO_L9N_T1_DQS_AD11N_15"
						(effects
							(font
								(size 1.27 1.27)
							)
						)
					)
					(number "K30"
						(effects
							(font
								(size 1.27 1.27)
							)
						)
					)
				)
				(pin bidirectional line
					(at 69.85 -52.07 180)
					(length 5.08)
					(name "IO_L10P_T1_AD4P_15"
						(effects
							(font
								(size 1.27 1.27)
							)
						)
					)
					(number "K26"
						(effects
							(font
								(size 1.27 1.27)
							)
						)
					)
				)
				(pin bidirectional line
					(at 69.85 -54.61 180)
					(length 5.08)
					(name "IO_L10N_T1_AD4N_15"
						(effects
							(font
								(size 1.27 1.27)
							)
						)
					)
					(number "J26"
						(effects
							(font
								(size 1.27 1.27)
							)
						)
					)
				)
				(pin bidirectional line
					(at 69.85 -57.15 180)
					(length 5.08)
					(name "IO_L11P_T1_SRCC_AD12P_15"
						(effects
							(font
								(size 1.27 1.27)
							)
						)
					)
					(number "L26"
						(effects
							(font
								(size 1.27 1.27)
							)
						)
					)
				)
				(pin bidirectional line
					(at 69.85 -59.69 180)
					(length 5.08)
					(name "IO_L11N_T1_SRCC_AD12N_15"
						(effects
							(font
								(size 1.27 1.27)
							)
						)
					)
					(number "L27"
						(effects
							(font
								(size 1.27 1.27)
							)
						)
					)
				)
				(pin bidirectional line
					(at 69.85 -62.23 180)
					(length 5.08)
					(name "IO_L12P_T1_MRCC_AD5P_15"
						(effects
							(font
								(size 1.27 1.27)
							)
						)
					)
					(number "L25"
						(effects
							(font
								(size 1.27 1.27)
							)
						)
					)
				)
				(pin bidirectional line
					(at 69.85 -64.77 180)
					(length 5.08)
					(name "IO_L12N_T1_MRCC_AD5N_15"
						(effects
							(font
								(size 1.27 1.27)
							)
						)
					)
					(number "K25"
						(effects
							(font
								(size 1.27 1.27)
							)
						)
					)
				)
				(pin bidirectional line
					(at 69.85 -67.31 180)
					(length 5.08)
					(name "IO_L13P_T2_MRCC_15"
						(effects
							(font
								(size 1.27 1.27)
							)
						)
					)
					(number "K28"
						(effects
							(font
								(size 1.27 1.27)
							)
						)
					)
				)
				(pin bidirectional line
					(at 69.85 -69.85 180)
					(length 5.08)
					(name "IO_L13N_T2_MRCC_15"
						(effects
							(font
								(size 1.27 1.27)
							)
						)
					)
					(number "K29"
						(effects
							(font
								(size 1.27 1.27)
							)
						)
					)
				)
				(pin bidirectional line
					(at 69.85 -72.39 180)
					(length 5.08)
					(name "IO_L14P_T2_SRCC_15"
						(effects
							(font
								(size 1.27 1.27)
							)
						)
					)
					(number "M28"
						(effects
							(font
								(size 1.27 1.27)
							)
						)
					)
				)
				(pin bidirectional line
					(at 69.85 -74.93 180)
					(length 5.08)
					(name "IO_L14N_T2_SRCC_15"
						(effects
							(font
								(size 1.27 1.27)
							)
						)
					)
					(number "L28"
						(effects
							(font
								(size 1.27 1.27)
							)
						)
					)
				)
				(pin bidirectional line
					(at 69.85 -77.47 180)
					(length 5.08)
					(name "IO_L15P_T2_DQS_15"
						(effects
							(font
								(size 1.27 1.27)
							)
						)
					)
					(number "M29"
						(effects
							(font
								(size 1.27 1.27)
							)
						)
					)
				)
				(pin bidirectional line
					(at 69.85 -80.01 180)
					(length 5.08)
					(name "IO_L15N_T2_DQS_ADV_B_15"
						(effects
							(font
								(size 1.27 1.27)
							)
						)
					)
					(number "M30"
						(effects
							(font
								(size 1.27 1.27)
							)
						)
					)
				)
				(pin bidirectional line
					(at 69.85 -82.55 180)
					(length 5.08)
					(name "IO_L16P_T2_A28_15"
						(effects
							(font
								(size 1.27 1.27)
							)
						)
					)
					(number "N27"
						(effects
							(font
								(size 1.27 1.27)
							)
						)
					)
				)
				(pin bidirectional line
					(at 69.85 -85.09 180)
					(length 5.08)
					(name "IO_L16N_T2_A27_15"
						(effects
							(font
								(size 1.27 1.27)
							)
						)
					)
					(number "M27"
						(effects
							(font
								(size 1.27 1.27)
							)
						)
					)
				)
				(pin bidirectional line
					(at 69.85 -87.63 180)
					(length 5.08)
					(name "IO_L17P_T2_A26_15"
						(effects
							(font
								(size 1.27 1.27)
							)
						)
					)
					(number "N29"
						(effects
							(font
								(size 1.27 1.27)
							)
						)
					)
				)
				(pin bidirectional line
					(at 69.85 -90.17 180)
					(length 5.08)
					(name "IO_L17N_T2_A25_15"
						(effects
							(font
								(size 1.27 1.27)
							)
						)
					)
					(number "N30"
						(effects
							(font
								(size 1.27 1.27)
							)
						)
					)
				)
				(pin bidirectional line
					(at 69.85 -92.71 180)
					(length 5.08)
					(name "IO_L18P_T2_A24_15"
						(effects
							(font
								(size 1.27 1.27)
							)
						)
					)
					(number "N25"
						(effects
							(font
								(size 1.27 1.27)
							)
						)
					)
				)
				(pin bidirectional line
					(at 69.85 -95.25 180)
					(length 5.08)
					(name "IO_L18N_T2_A23_15"
						(effects
							(font
								(size 1.27 1.27)
							)
						)
					)
					(number "N26"
						(effects
							(font
								(size 1.27 1.27)
							)
						)
					)
				)
				(pin bidirectional line
					(at 69.85 -97.79 180)
					(length 5.08)
					(name "IO_L19P_T3_A22_15"
						(effects
							(font
								(size 1.27 1.27)
							)
						)
					)
					(number "N19"
						(effects
							(font
								(size 1.27 1.27)
							)
						)
					)
				)
				(pin bidirectional line
					(at 69.85 -100.33 180)
					(length 5.08)
					(name "IO_L19N_T3_A21_VREF_15"
						(effects
							(font
								(size 1.27 1.27)
							)
						)
					)
					(number "N20"
						(effects
							(font
								(size 1.27 1.27)
							)
						)
					)
				)
				(pin bidirectional line
					(at 69.85 -102.87 180)
					(length 5.08)
					(name "IO_L20P_T3_A20_15"
						(effects
							(font
								(size 1.27 1.27)
							)
						)
					)
					(number "N21"
						(effects
							(font
								(size 1.27 1.27)
							)
						)
					)
				)
				(pin bidirectional line
					(at 69.85 -105.41 180)
					(length 5.08)
					(name "IO_L20N_T3_A19_15"
						(effects
							(font
								(size 1.27 1.27)
							)
						)
					)
					(number "N22"
						(effects
							(font
								(size 1.27 1.27)
							)
						)
					)
				)
				(pin bidirectional line
					(at 69.85 -107.95 180)
					(length 5.08)
					(name "IO_L21P_T3_DQS_15"
						(effects
							(font
								(size 1.27 1.27)
							)
						)
					)
					(number "P23"
						(effects
							(font
								(size 1.27 1.27)
							)
						)
					)
				)
				(pin bidirectional line
					(at 69.85 -110.49 180)
					(length 5.08)
					(name "IO_L21N_T3_DQS_A18_15"
						(effects
							(font
								(size 1.27 1.27)
							)
						)
					)
					(number "N24"
						(effects
							(font
								(size 1.27 1.27)
							)
						)
					)
				)
				(pin bidirectional line
					(at 69.85 -113.03 180)
					(length 5.08)
					(name "IO_L22P_T3_A17_15"
						(effects
							(font
								(size 1.27 1.27)
							)
						)
					)
					(number "P21"
						(effects
							(font
								(size 1.27 1.27)
							)
						)
					)
				)
				(pin bidirectional line
					(at 69.85 -115.57 180)
					(length 5.08)
					(name "IO_L22N_T3_A16_15"
						(effects
							(font
								(size 1.27 1.27)
							)
						)
					)
					(number "P22"
						(effects
							(font
								(size 1.27 1.27)
							)
						)
					)
				)
				(pin bidirectional line
					(at 69.85 -118.11 180)
					(length 5.08)
					(name "IO_L23P_T3_FOE_B_15"
						(effects
							(font
								(size 1.27 1.27)
							)
						)
					)
					(number "M24"
						(effects
							(font
								(size 1.27 1.27)
							)
						)
					)
				)
				(pin bidirectional line
					(at 69.85 -120.65 180)
					(length 5.08)
					(name "IO_L23N_T3_FWE_B_15"
						(effects
							(font
								(size 1.27 1.27)
							)
						)
					)
					(number "M25"
						(effects
							(font
								(size 1.27 1.27)
							)
						)
					)
				)
				(pin bidirectional line
					(at 69.85 -123.19 180)
					(length 5.08)
					(name "IO_L24P_T3_RS1_15"
						(effects
							(font
								(size 1.27 1.27)
							)
						)
					)
					(number "M22"
						(effects
							(font
								(size 1.27 1.27)
							)
						)
					)
				)
				(pin bidirectional line
					(at 69.85 -125.73 180)
					(length 5.08)
					(name "IO_L24N_T3_RS0_15"
						(effects
							(font
								(size 1.27 1.27)
							)
						)
					)
					(number "M23"
						(effects
							(font
								(size 1.27 1.27)
							)
						)
					)
				)
				(pin bidirectional line
					(at 69.85 -128.27 180)
					(length 5.08)
					(name "IO_25_15"
						(effects
							(font
								(size 1.27 1.27)
							)
						)
					)
					(number "P19"
						(effects
							(font
								(size 1.27 1.27)
							)
						)
					)
				)
			)
			(symbol "XC7K410T-2FFG900I_3_1"
				(rectangle
					(start 5.08 5.08)
					(end 49.53 -130.81)
					(stroke
						(width 0.254)
						(type default)
					)
					(fill
						(type background)
					)
				)
				(text "BANK 16"
					(at 15.24 2.54 0)
					(effects
						(font
							(size 1.27 1.27)
							(thickness 0.15)
						)
						(justify left bottom)
					)
				)
				(text "BANK 17"
					(at 30.48 2.54 0)
					(effects
						(font
							(size 1.27 1.27)
							(thickness 0.15)
						)
						(justify left bottom)
					)
				)
				(pin bidirectional line
					(at 0 0 0)
					(length 5.08)
					(name "VCCO_16"
						(effects
							(font
								(size 1.27 1.27)
							)
						)
					)
					(number "A29"
						(effects
							(font
								(size 1.27 1.27)
							)
						)
					)
				)
				(pin passive line
					(at 0 0 0)
					(length 5.08)
					(hide yes)
					(name "VCCO_16"
						(effects
							(font
								(size 1.27 1.27)
							)
						)
					)
					(number "B26"
						(effects
							(font
								(size 1.27 1.27)
							)
						)
					)
				)
				(pin passive line
					(at 0 0 0)
					(length 5.08)
					(hide yes)
					(name "VCCO_16"
						(effects
							(font
								(size 1.27 1.27)
							)
						)
					)
					(number "C23"
						(effects
							(font
								(size 1.27 1.27)
							)
						)
					)
				)
				(pin passive line
					(at 0 0 0)
					(length 5.08)
					(hide yes)
					(name "VCCO_16"
						(effects
							(font
								(size 1.27 1.27)
							)
						)
					)
					(number "D30"
						(effects
							(font
								(size 1.27 1.27)
							)
						)
					)
				)
				(pin passive line
					(at 0 0 0)
					(length 5.08)
					(hide yes)
					(name "VCCO_16"
						(effects
							(font
								(size 1.27 1.27)
							)
						)
					)
					(number "E27"
						(effects
							(font
								(size 1.27 1.27)
							)
						)
					)
				)
				(pin passive line
					(at 0 0 0)
					(length 5.08)
					(hide yes)
					(name "VCCO_16"
						(effects
							(font
								(size 1.27 1.27)
							)
						)
					)
					(number "F24"
						(effects
							(font
								(size 1.27 1.27)
							)
						)
					)
				)
				(pin passive line
					(at 0 0 0)
					(length 5.08)
					(hide yes)
					(name "VCCO_16"
						(effects
							(font
								(size 1.27 1.27)
							)
						)
					)
					(number "H28"
						(effects
							(font
								(size 1.27 1.27)
							)
						)
					)
				)
				(pin bidirectional line
					(at 0 -3.81 0)
					(length 5.08)
					(name "IO_0_16"
						(effects
							(font
								(size 1.27 1.27)
							)
						)
					)
					(number "F23"
						(effects
							(font
								(size 1.27 1.27)
							)
						)
					)
				)
				(pin bidirectional line
					(at 0 -6.35 0)
					(length 5.08)
					(name "IO_L1P_T0_16"
						(effects
							(font
								(size 1.27 1.27)
							)
						)
					)
					(number "B23"
						(effects
							(font
								(size 1.27 1.27)
							)
						)
					)
				)
				(pin bidirectional line
					(at 0 -8.89 0)
					(length 5.08)
					(name "IO_L1N_T0_16"
						(effects
							(font
								(size 1.27 1.27)
							)
						)
					)
					(number "A23"
						(effects
							(font
								(size 1.27 1.27)
							)
						)
					)
				)
				(pin bidirectional line
					(at 0 -11.43 0)
					(length 5.08)
					(name "IO_L2P_T0_16"
						(effects
							(font
								(size 1.27 1.27)
							)
						)
					)
					(number "E23"
						(effects
							(font
								(size 1.27 1.27)
							)
						)
					)
				)
				(pin bidirectional line
					(at 0 -13.97 0)
					(length 5.08)
					(name "IO_L2N_T0_16"
						(effects
							(font
								(size 1.27 1.27)
							)
						)
					)
					(number "D23"
						(effects
							(font
								(size 1.27 1.27)
							)
						)
					)
				)
				(pin bidirectional line
					(at 0 -16.51 0)
					(length 5.08)
					(name "IO_L3P_T0_DQS_16"
						(effects
							(font
								(size 1.27 1.27)
							)
						)
					)
					(number "F25"
						(effects
							(font
								(size 1.27 1.27)
							)
						)
					)
				)
				(pin bidirectional line
					(at 0 -19.05 0)
					(length 5.08)
					(name "IO_L3N_T0_DQS_16"
						(effects
							(font
								(size 1.27 1.27)
							)
						)
					)
					(number "E25"
						(effects
							(font
								(size 1.27 1.27)
							)
						)
					)
				)
				(pin bidirectional line
					(at 0 -21.59 0)
					(length 5.08)
					(name "IO_L4P_T0_16"
						(effects
							(font
								(size 1.27 1.27)
							)
						)
					)
					(number "E24"
						(effects
							(font
								(size 1.27 1.27)
							)
						)
					)
				)
				(pin bidirectional line
					(at 0 -24.13 0)
					(length 5.08)
					(name "IO_L4N_T0_16"
						(effects
							(font
								(size 1.27 1.27)
							)
						)
					)
					(number "D24"
						(effects
							(font
								(size 1.27 1.27)
							)
						)
					)
				)
				(pin bidirectional line
					(at 0 -26.67 0)
					(length 5.08)
					(name "IO_L5P_T0_16"
						(effects
							(font
								(size 1.27 1.27)
							)
						)
					)
					(number "F26"
						(effects
							(font
								(size 1.27 1.27)
							)
						)
					)
				)
				(pin bidirectional line
					(at 0 -29.21 0)
					(length 5.08)
					(name "IO_L5N_T0_16"
						(effects
							(font
								(size 1.27 1.27)
							)
						)
					)
					(number "E26"
						(effects
							(font
								(size 1.27 1.27)
							)
						)
					)
				)
				(pin bidirectional line
					(at 0 -31.75 0)
					(length 5.08)
					(name "IO_L6P_T0_16"
						(effects
							(font
								(size 1.27 1.27)
							)
						)
					)
					(number "G23"
						(effects
							(font
								(size 1.27 1.27)
							)
						)
					)
				)
				(pin bidirectional line
					(at 0 -34.29 0)
					(length 5.08)
					(name "IO_L6N_T0_VREF_16"
						(effects
							(font
								(size 1.27 1.27)
							)
						)
					)
					(number "G24"
						(effects
							(font
								(size 1.27 1.27)
							)
						)
					)
				)
				(pin bidirectional line
					(at 0 -36.83 0)
					(length 5.08)
					(name "IO_L7P_T1_16"
						(effects
							(font
								(size 1.27 1.27)
							)
						)
					)
					(number "B27"
						(effects
							(font
								(size 1.27 1.27)
							)
						)
					)
				)
				(pin bidirectional line
					(at 0 -39.37 0)
					(length 5.08)
					(name "IO_L7N_T1_16"
						(effects
							(font
								(size 1.27 1.27)
							)
						)
					)
					(number "A27"
						(effects
							(font
								(size 1.27 1.27)
							)
						)
					)
				)
				(pin bidirectional line
					(at 0 -41.91 0)
					(length 5.08)
					(name "IO_L8P_T1_16"
						(effects
							(font
								(size 1.27 1.27)
							)
						)
					)
					(number "C24"
						(effects
							(font
								(size 1.27 1.27)
							)
						)
					)
				)
				(pin bidirectional line
					(at 0 -44.45 0)
					(length 5.08)
					(name "IO_L8N_T1_16"
						(effects
							(font
								(size 1.27 1.27)
							)
						)
					)
					(number "B24"
						(effects
							(font
								(size 1.27 1.27)
							)
						)
					)
				)
				(pin bidirectional line
					(at 0 -46.99 0)
					(length 5.08)
					(name "IO_L9P_T1_DQS_16"
						(effects
							(font
								(size 1.27 1.27)
							)
						)
					)
					(number "B28"
						(effects
							(font
								(size 1.27 1.27)
							)
						)
					)
				)
				(pin bidirectional line
					(at 0 -49.53 0)
					(length 5.08)
					(name "IO_L9N_T1_DQS_16"
						(effects
							(font
								(size 1.27 1.27)
							)
						)
					)
					(number "A28"
						(effects
							(font
								(size 1.27 1.27)
							)
						)
					)
				)
				(pin bidirectional line
					(at 0 -52.07 0)
					(length 5.08)
					(name "IO_L10P_T1_16"
						(effects
							(font
								(size 1.27 1.27)
							)
						)
					)
					(number "A25"
						(effects
							(font
								(size 1.27 1.27)
							)
						)
					)
				)
				(pin bidirectional line
					(at 0 -54.61 0)
					(length 5.08)
					(name "IO_L10N_T1_16"
						(effects
							(font
								(size 1.27 1.27)
							)
						)
					)
					(number "A26"
						(effects
							(font
								(size 1.27 1.27)
							)
						)
					)
				)
				(pin bidirectional line
					(at 0 -57.15 0)
					(length 5.08)
					(name "IO_L11P_T1_SRCC_16"
						(effects
							(font
								(size 1.27 1.27)
							)
						)
					)
					(number "D26"
						(effects
							(font
								(size 1.27 1.27)
							)
						)
					)
				)
				(pin bidirectional line
					(at 0 -59.69 0)
					(length 5.08)
					(name "IO_L11N_T1_SRCC_16"
						(effects
							(font
								(size 1.27 1.27)
							)
						)
					)
					(number "C26"
						(effects
							(font
								(size 1.27 1.27)
							)
						)
					)
				)
				(pin bidirectional line
					(at 0 -62.23 0)
					(length 5.08)
					(name "IO_L12P_T1_MRCC_16"
						(effects
							(font
								(size 1.27 1.27)
							)
						)
					)
					(number "C25"
						(effects
							(font
								(size 1.27 1.27)
							)
						)
					)
				)
				(pin bidirectional line
					(at 0 -64.77 0)
					(length 5.08)
					(name "IO_L12N_T1_MRCC_16"
						(effects
							(font
								(size 1.27 1.27)
							)
						)
					)
					(number "B25"
						(effects
							(font
								(size 1.27 1.27)
							)
						)
					)
				)
				(pin bidirectional line
					(at 0 -67.31 0)
					(length 5.08)
					(name "IO_L13P_T2_MRCC_16"
						(effects
							(font
								(size 1.27 1.27)
							)
						)
					)
					(number "D27"
						(effects
							(font
								(size 1.27 1.27)
							)
						)
					)
				)
				(pin bidirectional line
					(at 0 -69.85 0)
					(length 5.08)
					(name "IO_L13N_T2_MRCC_16"
						(effects
							(font
								(size 1.27 1.27)
							)
						)
					)
					(number "C27"
						(effects
							(font
								(size 1.27 1.27)
							)
						)
					)
				)
				(pin bidirectional line
					(at 0 -72.39 0)
					(length 5.08)
					(name "IO_L14P_T2_SRCC_16"
						(effects
							(font
								(size 1.27 1.27)
							)
						)
					)
					(number "E28"
						(effects
							(font
								(size 1.27 1.27)
							)
						)
					)
				)
				(pin bidirectional line
					(at 0 -74.93 0)
					(length 5.08)
					(name "IO_L14N_T2_SRCC_16"
						(effects
							(font
								(size 1.27 1.27)
							)
						)
					)
					(number "D28"
						(effects
							(font
								(size 1.27 1.27)
							)
						)
					)
				)
				(pin bidirectional line
					(at 0 -77.47 0)
					(length 5.08)
					(name "IO_L15P_T2_DQS_16"
						(effects
							(font
								(size 1.27 1.27)
							)
						)
					)
					(number "C29"
						(effects
							(font
								(size 1.27 1.27)
							)
						)
					)
				)
				(pin bidirectional line
					(at 0 -80.01 0)
					(length 5.08)
					(name "IO_L15N_T2_DQS_16"
						(effects
							(font
								(size 1.27 1.27)
							)
						)
					)
					(number "B29"
						(effects
							(font
								(size 1.27 1.27)
							)
						)
					)
				)
				(pin bidirectional line
					(at 0 -82.55 0)
					(length 5.08)
					(name "IO_L16P_T2_16"
						(effects
							(font
								(size 1.27 1.27)
							)
						)
					)
					(number "D29"
						(effects
							(font
								(size 1.27 1.27)
							)
						)
					)
				)
				(pin bidirectional line
					(at 0 -85.09 0)
					(length 5.08)
					(name "IO_L16N_T2_16"
						(effects
							(font
								(size 1.27 1.27)
							)
						)
					)
					(number "C30"
						(effects
							(font
								(size 1.27 1.27)
							)
						)
					)
				)
				(pin bidirectional line
					(at 0 -87.63 0)
					(length 5.08)
					(name "IO_L17P_T2_16"
						(effects
							(font
								(size 1.27 1.27)
							)
						)
					)
					(number "B30"
						(effects
							(font
								(size 1.27 1.27)
							)
						)
					)
				)
				(pin bidirectional line
					(at 0 -90.17 0)
					(length 5.08)
					(name "IO_L17N_T2_16"
						(effects
							(font
								(size 1.27 1.27)
							)
						)
					)
					(number "A30"
						(effects
							(font
								(size 1.27 1.27)
							)
						)
					)
				)
				(pin bidirectional line
					(at 0 -92.71 0)
					(length 5.08)
					(name "IO_L18P_T2_16"
						(effects
							(font
								(size 1.27 1.27)
							)
						)
					)
					(number "E29"
						(effects
							(font
								(size 1.27 1.27)
							)
						)
					)
				)
				(pin bidirectional line
					(at 0 -95.25 0)
					(length 5.08)
					(name "IO_L18N_T2_16"
						(effects
							(font
								(size 1.27 1.27)
							)
						)
					)
					(number "E30"
						(effects
							(font
								(size 1.27 1.27)
							)
						)
					)
				)
				(pin bidirectional line
					(at 0 -97.79 0)
					(length 5.08)
					(name "IO_L19P_T3_16"
						(effects
							(font
								(size 1.27 1.27)
							)
						)
					)
					(number "H24"
						(effects
							(font
								(size 1.27 1.27)
							)
						)
					)
				)
				(pin bidirectional line
					(at 0 -100.33 0)
					(length 5.08)
					(name "IO_L19N_T3_VREF_16"
						(effects
							(font
								(size 1.27 1.27)
							)
						)
					)
					(number "H25"
						(effects
							(font
								(size 1.27 1.27)
							)
						)
					)
				)
				(pin bidirectional line
					(at 0 -102.87 0)
					(length 5.08)
					(name "IO_L20P_T3_16"
						(effects
							(font
								(size 1.27 1.27)
							)
						)
					)
					(number "G28"
						(effects
							(font
								(size 1.27 1.27)
							)
						)
					)
				)
				(pin bidirectional line
					(at 0 -105.41 0)
					(length 5.08)
					(name "IO_L20N_T3_16"
						(effects
							(font
								(size 1.27 1.27)
							)
						)
					)
					(number "F28"
						(effects
							(font
								(size 1.27 1.27)
							)
						)
					)
				)
				(pin bidirectional line
					(at 0 -107.95 0)
					(length 5.08)
					(name "IO_L21P_T3_DQS_16"
						(effects
							(font
								(size 1.27 1.27)
							)
						)
					)
					(number "G27"
						(effects
							(font
								(size 1.27 1.27)
							)
						)
					)
				)
				(pin bidirectional line
					(at 0 -110.49 0)
					(length 5.08)
					(name "IO_L21N_T3_DQS_16"
						(effects
							(font
								(size 1.27 1.27)
							)
						)
					)
					(number "F27"
						(effects
							(font
								(size 1.27 1.27)
							)
						)
					)
				)
				(pin bidirectional line
					(at 0 -113.03 0)
					(length 5.08)
					(name "IO_L22P_T3_16"
						(effects
							(font
								(size 1.27 1.27)
							)
						)
					)
					(number "G29"
						(effects
							(font
								(size 1.27 1.27)
							)
						)
					)
				)
				(pin bidirectional line
					(at 0 -115.57 0)
					(length 5.08)
					(name "IO_L22N_T3_16"
						(effects
							(font
								(size 1.27 1.27)
							)
						)
					)
					(number "F30"
						(effects
							(font
								(size 1.27 1.27)
							)
						)
					)
				)
				(pin bidirectional line
					(at 0 -118.11 0)
					(length 5.08)
					(name "IO_L23P_T3_16"
						(effects
							(font
								(size 1.27 1.27)
							)
						)
					)
					(number "H26"
						(effects
							(font
								(size 1.27 1.27)
							)
						)
					)
				)
				(pin bidirectional line
					(at 0 -120.65 0)
					(length 5.08)
					(name "IO_L23N_T3_16"
						(effects
							(font
								(size 1.27 1.27)
							)
						)
					)
					(number "H27"
						(effects
							(font
								(size 1.27 1.27)
							)
						)
					)
				)
				(pin bidirectional line
					(at 0 -123.19 0)
					(length 5.08)
					(name "IO_L24P_T3_16"
						(effects
							(font
								(size 1.27 1.27)
							)
						)
					)
					(number "H30"
						(effects
							(font
								(size 1.27 1.27)
							)
						)
					)
				)
				(pin bidirectional line
					(at 0 -125.73 0)
					(length 5.08)
					(name "IO_L24N_T3_16"
						(effects
							(font
								(size 1.27 1.27)
							)
						)
					)
					(number "G30"
						(effects
							(font
								(size 1.27 1.27)
							)
						)
					)
				)
				(pin bidirectional line
					(at 0 -128.27 0)
					(length 5.08)
					(name "IO_25_16"
						(effects
							(font
								(size 1.27 1.27)
							)
						)
					)
					(number "G25"
						(effects
							(font
								(size 1.27 1.27)
							)
						)
					)
				)
				(pin bidirectional line
					(at 54.61 0 180)
					(length 5.08)
					(name "VCCO_17"
						(effects
							(font
								(size 1.27 1.27)
							)
						)
					)
					(number "A19"
						(effects
							(font
								(size 1.27 1.27)
							)
						)
					)
				)
				(pin passive line
					(at 54.61 0 180)
					(length 5.08)
					(hide yes)
					(name "VCCO_17"
						(effects
							(font
								(size 1.27 1.27)
							)
						)
					)
					(number "B16"
						(effects
							(font
								(size 1.27 1.27)
							)
						)
					)
				)
				(pin passive line
					(at 54.61 0 180)
					(length 5.08)
					(hide yes)
					(name "VCCO_17"
						(effects
							(font
								(size 1.27 1.27)
							)
						)
					)
					(number "D20"
						(effects
							(font
								(size 1.27 1.27)
							)
						)
					)
				)
				(pin passive line
					(at 54.61 0 180)
					(length 5.08)
					(hide yes)
					(name "VCCO_17"
						(effects
							(font
								(size 1.27 1.27)
							)
						)
					)
					(number "E17"
						(effects
							(font
								(size 1.27 1.27)
							)
						)
					)
				)
				(pin passive line
					(at 54.61 0 180)
					(length 5.08)
					(hide yes)
					(name "VCCO_17"
						(effects
							(font
								(size 1.27 1.27)
							)
						)
					)
					(number "G21"
						(effects
							(font
								(size 1.27 1.27)
							)
						)
					)
				)
				(pin passive line
					(at 54.61 0 180)
					(length 5.08)
					(hide yes)
					(name "VCCO_17"
						(effects
							(font
								(size 1.27 1.27)
							)
						)
					)
					(number "H18"
						(effects
							(font
								(size 1.27 1.27)
							)
						)
					)
				)
				(pin passive line
					(at 54.61 0 180)
					(length 5.08)
					(hide yes)
					(name "VCCO_17"
						(effects
							(font
								(size 1.27 1.27)
							)
						)
					)
					(number "L19"
						(effects
							(font
								(size 1.27 1.27)
							)
						)
					)
				)
				(pin bidirectional line
					(at 54.61 -3.81 180)
					(length 5.08)
					(name "IO_0_17"
						(effects
							(font
								(size 1.27 1.27)
							)
						)
					)
					(number "G19"
						(effects
							(font
								(size 1.27 1.27)
							)
						)
					)
				)
				(pin bidirectional line
					(at 54.61 -6.35 180)
					(length 5.08)
					(name "IO_L1P_T0_17"
						(effects
							(font
								(size 1.27 1.27)
							)
						)
					)
					(number "K18"
						(effects
							(font
								(size 1.27 1.27)
							)
						)
					)
				)
				(pin bidirectional line
					(at 54.61 -8.89 180)
					(length 5.08)
					(name "IO_L1N_T0_17"
						(effects
							(font
								(size 1.27 1.27)
							)
						)
					)
					(number "J18"
						(effects
							(font
								(size 1.27 1.27)
							)
						)
					)
				)
				(pin bidirectional line
					(at 54.61 -11.43 180)
					(length 5.08)
					(name "IO_L2P_T0_17"
						(effects
							(font
								(size 1.27 1.27)
							)
						)
					)
					(number "H20"
						(effects
							(font
								(size 1.27 1.27)
							)
						)
					)
				)
				(pin bidirectional line
					(at 54.61 -13.97 180)
					(length 5.08)
					(name "IO_L2N_T0_17"
						(effects
							(font
								(size 1.27 1.27)
							)
						)
					)
					(number "G20"
						(effects
							(font
								(size 1.27 1.27)
							)
						)
					)
				)
				(pin bidirectional line
					(at 54.61 -16.51 180)
					(length 5.08)
					(name "IO_L3P_T0_DQS_17"
						(effects
							(font
								(size 1.27 1.27)
							)
						)
					)
					(number "J17"
						(effects
							(font
								(size 1.27 1.27)
							)
						)
					)
				)
				(pin bidirectional line
					(at 54.61 -19.05 180)
					(length 5.08)
					(name "IO_L3N_T0_DQS_17"
						(effects
							(font
								(size 1.27 1.27)
							)
						)
					)
					(number "H17"
						(effects
							(font
								(size 1.27 1.27)
							)
						)
					)
				)
				(pin bidirectional line
					(at 54.61 -21.59 180)
					(length 5.08)
					(name "IO_L4P_T0_17"
						(effects
							(font
								(size 1.27 1.27)
							)
						)
					)
					(number "J19"
						(effects
							(font
								(size 1.27 1.27)
							)
						)
					)
				)
				(pin bidirectional line
					(at 54.61 -24.13 180)
					(length 5.08)
					(name "IO_L4N_T0_17"
						(effects
							(font
								(size 1.27 1.27)
							)
						)
					)
					(number "H19"
						(effects
							(font
								(size 1.27 1.27)
							)
						)
					)
				)
				(pin bidirectional line
					(at 54.61 -26.67 180)
					(length 5.08)
					(name "IO_L5P_T0_17"
						(effects
							(font
								(size 1.27 1.27)
							)
						)
					)
					(number "L17"
						(effects
							(font
								(size 1.27 1.27)
							)
						)
					)
				)
				(pin bidirectional line
					(at 54.61 -29.21 180)
					(length 5.08)
					(name "IO_L5N_T0_17"
						(effects
							(font
								(size 1.27 1.27)
							)
						)
					)
					(number "L18"
						(effects
							(font
								(size 1.27 1.27)
							)
						)
					)
				)
				(pin bidirectional line
					(at 54.61 -31.75 180)
					(length 5.08)
					(name "IO_L6P_T0_17"
						(effects
							(font
								(size 1.27 1.27)
							)
						)
					)
					(number "K19"
						(effects
							(font
								(size 1.27 1.27)
							)
						)
					)
				)
				(pin bidirectional line
					(at 54.61 -34.29 180)
					(length 5.08)
					(name "IO_L6N_T0_VREF_17"
						(effects
							(font
								(size 1.27 1.27)
							)
						)
					)
					(number "K20"
						(effects
							(font
								(size 1.27 1.27)
							)
						)
					)
				)
				(pin bidirectional line
					(at 54.61 -36.83 180)
					(length 5.08)
					(name "IO_L7P_T1_17"
						(effects
							(font
								(size 1.27 1.27)
							)
						)
					)
					(number "H21"
						(effects
							(font
								(size 1.27 1.27)
							)
						)
					)
				)
				(pin bidirectional line
					(at 54.61 -39.37 180)
					(length 5.08)
					(name "IO_L7N_T1_17"
						(effects
							(font
								(size 1.27 1.27)
							)
						)
					)
					(number "H22"
						(effects
							(font
								(size 1.27 1.27)
							)
						)
					)
				)
				(pin bidirectional line
					(at 54.61 -41.91 180)
					(length 5.08)
					(name "IO_L8P_T1_17"
						(effects
							(font
								(size 1.27 1.27)
							)
						)
					)
					(number "D21"
						(effects
							(font
								(size 1.27 1.27)
							)
						)
					)
				)
				(pin bidirectional line
					(at 54.61 -44.45 180)
					(length 5.08)
					(name "IO_L8N_T1_17"
						(effects
							(font
								(size 1.27 1.27)
							)
						)
					)
					(number "C21"
						(effects
							(font
								(size 1.27 1.27)
							)
						)
					)
				)
				(pin bidirectional line
					(at 54.61 -46.99 180)
					(length 5.08)
					(name "IO_L9P_T1_DQS_17"
						(effects
							(font
								(size 1.27 1.27)
							)
						)
					)
					(number "G22"
						(effects
							(font
								(size 1.27 1.27)
							)
						)
					)
				)
				(pin bidirectional line
					(at 54.61 -49.53 180)
					(length 5.08)
					(name "IO_L9N_T1_DQS_17"
						(effects
							(font
								(size 1.27 1.27)
							)
						)
					)
					(number "F22"
						(effects
							(font
								(size 1.27 1.27)
							)
						)
					)
				)
				(pin bidirectional line
					(at 54.61 -52.07 180)
					(length 5.08)
					(name "IO_L10P_T1_17"
						(effects
							(font
								(size 1.27 1.27)
							)
						)
					)
					(number "D22"
						(effects
							(font
								(size 1.27 1.27)
							)
						)
					)
				)
				(pin bidirectional line
					(at 54.61 -54.61 180)
					(length 5.08)
					(name "IO_L10N_T1_17"
						(effects
							(font
								(size 1.27 1.27)
							)
						)
					)
					(number "C22"
						(effects
							(font
								(size 1.27 1.27)
							)
						)
					)
				)
				(pin bidirectional line
					(at 54.61 -57.15 180)
					(length 5.08)
					(name "IO_L11P_T1_SRCC_17"
						(effects
							(font
								(size 1.27 1.27)
							)
						)
					)
					(number "F21"
						(effects
							(font
								(size 1.27 1.27)
							)
						)
					)
				)
				(pin bidirectional line
					(at 54.61 -59.69 180)
					(length 5.08)
					(name "IO_L11N_T1_SRCC_17"
						(effects
							(font
								(size 1.27 1.27)
							)
						)
					)
					(number "E21"
						(effects
							(font
								(size 1.27 1.27)
							)
						)
					)
				)
				(pin bidirectional line
					(at 54.61 -62.23 180)
					(length 5.08)
					(name "IO_L12P_T1_MRCC_17"
						(effects
							(font
								(size 1.27 1.27)
							)
						)
					)
					(number "F20"
						(effects
							(font
								(size 1.27 1.27)
							)
						)
					)
				)
				(pin bidirectional line
					(at 54.61 -64.77 180)
					(length 5.08)
					(name "IO_L12N_T1_MRCC_17"
						(effects
							(font
								(size 1.27 1.27)
							)
						)
					)
					(number "E20"
						(effects
							(font
								(size 1.27 1.27)
							)
						)
					)
				)
				(pin bidirectional line
					(at 54.61 -67.31 180)
					(length 5.08)
					(name "IO_L13P_T2_MRCC_17"
						(effects
							(font
								(size 1.27 1.27)
							)
						)
					)
					(number "D17"
						(effects
							(font
								(size 1.27 1.27)
							)
						)
					)
				)
				(pin bidirectional line
					(at 54.61 -69.85 180)
					(length 5.08)
					(name "IO_L13N_T2_MRCC_17"
						(effects
							(font
								(size 1.27 1.27)
							)
						)
					)
					(number "D18"
						(effects
							(font
								(size 1.27 1.27)
							)
						)
					)
				)
				(pin bidirectional line
					(at 54.61 -72.39 180)
					(length 5.08)
					(name "IO_L14P_T2_SRCC_17"
						(effects
							(font
								(size 1.27 1.27)
							)
						)
					)
					(number "E19"
						(effects
							(font
								(size 1.27 1.27)
							)
						)
					)
				)
				(pin bidirectional line
					(at 54.61 -74.93 180)
					(length 5.08)
					(name "IO_L14N_T2_SRCC_17"
						(effects
							(font
								(size 1.27 1.27)
							)
						)
					)
					(number "D19"
						(effects
							(font
								(size 1.27 1.27)
							)
						)
					)
				)
				(pin bidirectional line
					(at 54.61 -77.47 180)
					(length 5.08)
					(name "IO_L15P_T2_DQS_17"
						(effects
							(font
								(size 1.27 1.27)
							)
						)
					)
					(number "D16"
						(effects
							(font
								(size 1.27 1.27)
							)
						)
					)
				)
				(pin bidirectional line
					(at 54.61 -80.01 180)
					(length 5.08)
					(name "IO_L15N_T2_DQS_17"
						(effects
							(font
								(size 1.27 1.27)
							)
						)
					)
					(number "C16"
						(effects
							(font
								(size 1.27 1.27)
							)
						)
					)
				)
				(pin bidirectional line
					(at 54.61 -82.55 180)
					(length 5.08)
					(name "IO_L16P_T2_17"
						(effects
							(font
								(size 1.27 1.27)
							)
						)
					)
					(number "G18"
						(effects
							(font
								(size 1.27 1.27)
							)
						)
					)
				)
				(pin bidirectional line
					(at 54.61 -85.09 180)
					(length 5.08)
					(name "IO_L16N_T2_17"
						(effects
							(font
								(size 1.27 1.27)
							)
						)
					)
					(number "F18"
						(effects
							(font
								(size 1.27 1.27)
							)
						)
					)
				)
				(pin bidirectional line
					(at 54.61 -87.63 180)
					(length 5.08)
					(name "IO_L17P_T2_17"
						(effects
							(font
								(size 1.27 1.27)
							)
						)
					)
					(number "C17"
						(effects
							(font
								(size 1.27 1.27)
							)
						)
					)
				)
				(pin bidirectional line
					(at 54.61 -90.17 180)
					(length 5.08)
					(name "IO_L17N_T2_17"
						(effects
							(font
								(size 1.27 1.27)
							)
						)
					)
					(number "B17"
						(effects
							(font
								(size 1.27 1.27)
							)
						)
					)
				)
				(pin bidirectional line
					(at 54.61 -92.71 180)
					(length 5.08)
					(name "IO_L18P_T2_17"
						(effects
							(font
								(size 1.27 1.27)
							)
						)
					)
					(number "G17"
						(effects
							(font
								(size 1.27 1.27)
							)
						)
					)
				)
				(pin bidirectional line
					(at 54.61 -95.25 180)
					(length 5.08)
					(name "IO_L18N_T2_17"
						(effects
							(font
								(size 1.27 1.27)
							)
						)
					)
					(number "F17"
						(effects
							(font
								(size 1.27 1.27)
							)
						)
					)
				)
				(pin bidirectional line
					(at 54.61 -97.79 180)
					(length 5.08)
					(name "IO_L19P_T3_17"
						(effects
							(font
								(size 1.27 1.27)
							)
						)
					)
					(number "C20"
						(effects
							(font
								(size 1.27 1.27)
							)
						)
					)
				)
				(pin bidirectional line
					(at 54.61 -100.33 180)
					(length 5.08)
					(name "IO_L19N_T3_VREF_17"
						(effects
							(font
								(size 1.27 1.27)
							)
						)
					)
					(number "B20"
						(effects
							(font
								(size 1.27 1.27)
							)
						)
					)
				)
				(pin bidirectional line
					(at 54.61 -102.87 180)
					(length 5.08)
					(name "IO_L20P_T3_17"
						(effects
							(font
								(size 1.27 1.27)
							)
						)
					)
					(number "A16"
						(effects
							(font
								(size 1.27 1.27)
							)
						)
					)
				)
				(pin bidirectional line
					(at 54.61 -105.41 180)
					(length 5.08)
					(name "IO_L20N_T3_17"
						(effects
							(font
								(size 1.27 1.27)
							)
						)
					)
					(number "A17"
						(effects
							(font
								(size 1.27 1.27)
							)
						)
					)
				)
				(pin bidirectional line
					(at 54.61 -107.95 180)
					(length 5.08)
					(name "IO_L21P_T3_DQS_17"
						(effects
							(font
								(size 1.27 1.27)
							)
						)
					)
					(number "A20"
						(effects
							(font
								(size 1.27 1.27)
							)
						)
					)
				)
				(pin bidirectional line
					(at 54.61 -110.49 180)
					(length 5.08)
					(name "IO_L21N_T3_DQS_17"
						(effects
							(font
								(size 1.27 1.27)
							)
						)
					)
					(number "A21"
						(effects
							(font
								(size 1.27 1.27)
							)
						)
					)
				)
				(pin bidirectional line
					(at 54.61 -113.03 180)
					(length 5.08)
					(name "IO_L22P_T3_17"
						(effects
							(font
								(size 1.27 1.27)
							)
						)
					)
					(number "B18"
						(effects
							(font
								(size 1.27 1.27)
							)
						)
					)
				)
				(pin bidirectional line
					(at 54.61 -115.57 180)
					(length 5.08)
					(name "IO_L22N_T3_17"
						(effects
							(font
								(size 1.27 1.27)
							)
						)
					)
					(number "A18"
						(effects
							(font
								(size 1.27 1.27)
							)
						)
					)
				)
				(pin bidirectional line
					(at 54.61 -118.11 180)
					(length 5.08)
					(name "IO_L23P_T3_17"
						(effects
							(font
								(size 1.27 1.27)
							)
						)
					)
					(number "B22"
						(effects
							(font
								(size 1.27 1.27)
							)
						)
					)
				)
				(pin bidirectional line
					(at 54.61 -120.65 180)
					(length 5.08)
					(name "IO_L23N_T3_17"
						(effects
							(font
								(size 1.27 1.27)
							)
						)
					)
					(number "A22"
						(effects
							(font
								(size 1.27 1.27)
							)
						)
					)
				)
				(pin bidirectional line
					(at 54.61 -123.19 180)
					(length 5.08)
					(name "IO_L24P_T3_17"
						(effects
							(font
								(size 1.27 1.27)
							)
						)
					)
					(number "C19"
						(effects
							(font
								(size 1.27 1.27)
							)
						)
					)
				)
				(pin bidirectional line
					(at 54.61 -125.73 180)
					(length 5.08)
					(name "IO_L24N_T3_17"
						(effects
							(font
								(size 1.27 1.27)
							)
						)
					)
					(number "B19"
						(effects
							(font
								(size 1.27 1.27)
							)
						)
					)
				)
				(pin bidirectional line
					(at 54.61 -128.27 180)
					(length 5.08)
					(name "IO_25_17"
						(effects
							(font
								(size 1.27 1.27)
							)
						)
					)
					(number "E18"
						(effects
							(font
								(size 1.27 1.27)
							)
						)
					)
				)
			)
			(symbol "XC7K410T-2FFG900I_4_1"
				(rectangle
					(start 5.08 5.08)
					(end 48.26 -130.81)
					(stroke
						(width 0.254)
						(type default)
					)
					(fill
						(type background)
					)
				)
				(text "BANK 18"
					(at 17.78 2.54 0)
					(effects
						(font
							(size 1.27 1.27)
							(thickness 0.15)
						)
						(justify left bottom)
					)
				)
				(text "BANK 32"
					(at 29.21 2.54 0)
					(effects
						(font
							(size 1.27 1.27)
							(thickness 0.15)
						)
						(justify left bottom)
					)
				)
				(pin bidirectional line
					(at 0 0 0)
					(length 5.08)
					(name "VCCO_18"
						(effects
							(font
								(size 1.27 1.27)
							)
						)
					)
					(number "C13"
						(effects
							(font
								(size 1.27 1.27)
							)
						)
					)
				)
				(pin passive line
					(at 0 0 0)
					(length 5.08)
					(hide yes)
					(name "VCCO_18"
						(effects
							(font
								(size 1.27 1.27)
							)
						)
					)
					(number "D10"
						(effects
							(font
								(size 1.27 1.27)
							)
						)
					)
				)
				(pin passive line
					(at 0 0 0)
					(length 5.08)
					(hide yes)
					(name "VCCO_18"
						(effects
							(font
								(size 1.27 1.27)
							)
						)
					)
					(number "F14"
						(effects
							(font
								(size 1.27 1.27)
							)
						)
					)
				)
				(pin passive line
					(at 0 0 0)
					(length 5.08)
					(hide yes)
					(name "VCCO_18"
						(effects
							(font
								(size 1.27 1.27)
							)
						)
					)
					(number "G11"
						(effects
							(font
								(size 1.27 1.27)
							)
						)
					)
				)
				(pin passive line
					(at 0 0 0)
					(length 5.08)
					(hide yes)
					(name "VCCO_18"
						(effects
							(font
								(size 1.27 1.27)
							)
						)
					)
					(number "J15"
						(effects
							(font
								(size 1.27 1.27)
							)
						)
					)
				)
				(pin passive line
					(at 0 0 0)
					(length 5.08)
					(hide yes)
					(name "VCCO_18"
						(effects
							(font
								(size 1.27 1.27)
							)
						)
					)
					(number "K12"
						(effects
							(font
								(size 1.27 1.27)
							)
						)
					)
				)
				(pin bidirectional line
					(at 0 -3.81 0)
					(length 5.08)
					(name "IO_0_18"
						(effects
							(font
								(size 1.27 1.27)
							)
						)
					)
					(number "G12"
						(effects
							(font
								(size 1.27 1.27)
							)
						)
					)
				)
				(pin bidirectional line
					(at 0 -6.35 0)
					(length 5.08)
					(name "IO_L1P_T0_18"
						(effects
							(font
								(size 1.27 1.27)
							)
						)
					)
					(number "L16"
						(effects
							(font
								(size 1.27 1.27)
							)
						)
					)
				)
				(pin bidirectional line
					(at 0 -8.89 0)
					(length 5.08)
					(name "IO_L1N_T0_18"
						(effects
							(font
								(size 1.27 1.27)
							)
						)
					)
					(number "K16"
						(effects
							(font
								(size 1.27 1.27)
							)
						)
					)
				)
				(pin bidirectional line
					(at 0 -11.43 0)
					(length 5.08)
					(name "IO_L2P_T0_18"
						(effects
							(font
								(size 1.27 1.27)
							)
						)
					)
					(number "L15"
						(effects
							(font
								(size 1.27 1.27)
							)
						)
					)
				)
				(pin bidirectional line
					(at 0 -13.97 0)
					(length 5.08)
					(name "IO_L2N_T0_18"
						(effects
							(font
								(size 1.27 1.27)
							)
						)
					)
					(number "K15"
						(effects
							(font
								(size 1.27 1.27)
							)
						)
					)
				)
				(pin bidirectional line
					(at 0 -16.51 0)
					(length 5.08)
					(name "IO_L3P_T0_DQS_18"
						(effects
							(font
								(size 1.27 1.27)
							)
						)
					)
					(number "L12"
						(effects
							(font
								(size 1.27 1.27)
							)
						)
					)
				)
				(pin bidirectional line
					(at 0 -19.05 0)
					(length 5.08)
					(name "IO_L3N_T0_DQS_18"
						(effects
							(font
								(size 1.27 1.27)
							)
						)
					)
					(number "L13"
						(effects
							(font
								(size 1.27 1.27)
							)
						)
					)
				)
				(pin bidirectional line
					(at 0 -21.59 0)
					(length 5.08)
					(name "IO_L4P_T0_18"
						(effects
							(font
								(size 1.27 1.27)
							)
						)
					)
					(number "K13"
						(effects
							(font
								(size 1.27 1.27)
							)
						)
					)
				)
				(pin bidirectional line
					(at 0 -24.13 0)
					(length 5.08)
					(name "IO_L4N_T0_18"
						(effects
							(font
								(size 1.27 1.27)
							)
						)
					)
					(number "J13"
						(effects
							(font
								(size 1.27 1.27)
							)
						)
					)
				)
				(pin bidirectional line
					(at 0 -26.67 0)
					(length 5.08)
					(name "IO_L5P_T0_18"
						(effects
							(font
								(size 1.27 1.27)
							)
						)
					)
					(number "K14"
						(effects
							(font
								(size 1.27 1.27)
							)
						)
					)
				)
				(pin bidirectional line
					(at 0 -29.21 0)
					(length 5.08)
					(name "IO_L5N_T0_18"
						(effects
							(font
								(size 1.27 1.27)
							)
						)
					)
					(number "J14"
						(effects
							(font
								(size 1.27 1.27)
							)
						)
					)
				)
				(pin bidirectional line
					(at 0 -31.75 0)
					(length 5.08)
					(name "IO_L6P_T0_18"
						(effects
							(font
								(size 1.27 1.27)
							)
						)
					)
					(number "L11"
						(effects
							(font
								(size 1.27 1.27)
							)
						)
					)
				)
				(pin bidirectional line
					(at 0 -34.29 0)
					(length 5.08)
					(name "IO_L6N_T0_VREF_18"
						(effects
							(font
								(size 1.27 1.27)
							)
						)
					)
					(number "K11"
						(effects
							(font
								(size 1.27 1.27)
							)
						)
					)
				)
				(pin bidirectional line
					(at 0 -36.83 0)
					(length 5.08)
					(name "IO_L7P_T1_18"
						(effects
							(font
								(size 1.27 1.27)
							)
						)
					)
					(number "H15"
						(effects
							(font
								(size 1.27 1.27)
							)
						)
					)
				)
				(pin bidirectional line
					(at 0 -39.37 0)
					(length 5.08)
					(name "IO_L7N_T1_18"
						(effects
							(font
								(size 1.27 1.27)
							)
						)
					)
					(number "G15"
						(effects
							(font
								(size 1.27 1.27)
							)
						)
					)
				)
				(pin bidirectional line
					(at 0 -41.91 0)
					(length 5.08)
					(name "IO_L8P_T1_18"
						(effects
							(font
								(size 1.27 1.27)
							)
						)
					)
					(number "J11"
						(effects
							(font
								(size 1.27 1.27)
							)
						)
					)
				)
				(pin bidirectional line
					(at 0 -44.45 0)
					(length 5.08)
					(name "IO_L8N_T1_18"
						(effects
							(font
								(size 1.27 1.27)
							)
						)
					)
					(number "J12"
						(effects
							(font
								(size 1.27 1.27)
							)
						)
					)
				)
				(pin bidirectional line
					(at 0 -46.99 0)
					(length 5.08)
					(name "IO_L9P_T1_DQS_18"
						(effects
							(font
								(size 1.27 1.27)
							)
						)
					)
					(number "J16"
						(effects
							(font
								(size 1.27 1.27)
							)
						)
					)
				)
				(pin bidirectional line
					(at 0 -49.53 0)
					(length 5.08)
					(name "IO_L9N_T1_DQS_18"
						(effects
							(font
								(size 1.27 1.27)
							)
						)
					)
					(number "H16"
						(effects
							(font
								(size 1.27 1.27)
							)
						)
					)
				)
				(pin bidirectional line
					(at 0 -52.07 0)
					(length 5.08)
					(name "IO_L10P_T1_18"
						(effects
							(font
								(size 1.27 1.27)
							)
						)
					)
					(number "H11"
						(effects
							(font
								(size 1.27 1.27)
							)
						)
					)
				)
				(pin bidirectional line
					(at 0 -54.61 0)
					(length 5.08)
					(name "IO_L10N_T1_18"
						(effects
							(font
								(size 1.27 1.27)
							)
						)
					)
					(number "H12"
						(effects
							(font
								(size 1.27 1.27)
							)
						)
					)
				)
				(pin bidirectional line
					(at 0 -57.15 0)
					(length 5.08)
					(name "IO_L11P_T1_SRCC_18"
						(effects
							(font
								(size 1.27 1.27)
							)
						)
					)
					(number "H14"
						(effects
							(font
								(size 1.27 1.27)
							)
						)
					)
				)
				(pin bidirectional line
					(at 0 -59.69 0)
					(length 5.08)
					(name "IO_L11N_T1_SRCC_18"
						(effects
							(font
								(size 1.27 1.27)
							)
						)
					)
					(number "G14"
						(effects
							(font
								(size 1.27 1.27)
							)
						)
					)
				)
				(pin bidirectional line
					(at 0 -62.23 0)
					(length 5.08)
					(name "IO_L12P_T1_MRCC_18"
						(effects
							(font
								(size 1.27 1.27)
							)
						)
					)
					(number "G13"
						(effects
							(font
								(size 1.27 1.27)
							)
						)
					)
				)
				(pin bidirectional line
					(at 0 -64.77 0)
					(length 5.08)
					(name "IO_L12N_T1_MRCC_18"
						(effects
							(font
								(size 1.27 1.27)
							)
						)
					)
					(number "F13"
						(effects
							(font
								(size 1.27 1.27)
							)
						)
					)
				)
				(pin bidirectional line
					(at 0 -67.31 0)
					(length 5.08)
					(name "IO_L13P_T2_MRCC_18"
						(effects
							(font
								(size 1.27 1.27)
							)
						)
					)
					(number "D12"
						(effects
							(font
								(size 1.27 1.27)
							)
						)
					)
				)
				(pin bidirectional line
					(at 0 -69.85 0)
					(length 5.08)
					(name "IO_L13N_T2_MRCC_18"
						(effects
							(font
								(size 1.27 1.27)
							)
						)
					)
					(number "D13"
						(effects
							(font
								(size 1.27 1.27)
							)
						)
					)
				)
				(pin bidirectional line
					(at 0 -72.39 0)
					(length 5.08)
					(name "IO_L14P_T2_SRCC_18"
						(effects
							(font
								(size 1.27 1.27)
							)
						)
					)
					(number "F12"
						(effects
							(font
								(size 1.27 1.27)
							)
						)
					)
				)
				(pin bidirectional line
					(at 0 -74.93 0)
					(length 5.08)
					(name "IO_L14N_T2_SRCC_18"
						(effects
							(font
								(size 1.27 1.27)
							)
						)
					)
					(number "E13"
						(effects
							(font
								(size 1.27 1.27)
							)
						)
					)
				)
				(pin bidirectional line
					(at 0 -77.47 0)
					(length 5.08)
					(name "IO_L15P_T2_DQS_18"
						(effects
							(font
								(size 1.27 1.27)
							)
						)
					)
					(number "C12"
						(effects
							(font
								(size 1.27 1.27)
							)
						)
					)
				)
				(pin bidirectional line
					(at 0 -80.01 0)
					(length 5.08)
					(name "IO_L15N_T2_DQS_18"
						(effects
							(font
								(size 1.27 1.27)
							)
						)
					)
					(number "B12"
						(effects
							(font
								(size 1.27 1.27)
							)
						)
					)
				)
				(pin bidirectional line
					(at 0 -82.55 0)
					(length 5.08)
					(name "IO_L16P_T2_18"
						(effects
							(font
								(size 1.27 1.27)
							)
						)
					)
					(number "F11"
						(effects
							(font
								(size 1.27 1.27)
							)
						)
					)
				)
				(pin bidirectional line
					(at 0 -85.09 0)
					(length 5.08)
					(name "IO_L16N_T2_18"
						(effects
							(font
								(size 1.27 1.27)
							)
						)
					)
					(number "E11"
						(effects
							(font
								(size 1.27 1.27)
							)
						)
					)
				)
				(pin bidirectional line
					(at 0 -87.63 0)
					(length 5.08)
					(name "IO_L17P_T2_18"
						(effects
							(font
								(size 1.27 1.27)
							)
						)
					)
					(number "A11"
						(effects
							(font
								(size 1.27 1.27)
							)
						)
					)
				)
				(pin bidirectional line
					(at 0 -90.17 0)
					(length 5.08)
					(name "IO_L17N_T2_18"
						(effects
							(font
								(size 1.27 1.27)
							)
						)
					)
					(number "A12"
						(effects
							(font
								(size 1.27 1.27)
							)
						)
					)
				)
				(pin bidirectional line
					(at 0 -92.71 0)
					(length 5.08)
					(name "IO_L18P_T2_18"
						(effects
							(font
								(size 1.27 1.27)
							)
						)
					)
					(number "D11"
						(effects
							(font
								(size 1.27 1.27)
							)
						)
					)
				)
				(pin bidirectional line
					(at 0 -95.25 0)
					(length 5.08)
					(name "IO_L18N_T2_18"
						(effects
							(font
								(size 1.27 1.27)
							)
						)
					)
					(number "C11"
						(effects
							(font
								(size 1.27 1.27)
							)
						)
					)
				)
				(pin bidirectional line
					(at 0 -97.79 0)
					(length 5.08)
					(name "IO_L19P_T3_18"
						(effects
							(font
								(size 1.27 1.27)
							)
						)
					)
					(number "F15"
						(effects
							(font
								(size 1.27 1.27)
							)
						)
					)
				)
				(pin bidirectional line
					(at 0 -100.33 0)
					(length 5.08)
					(name "IO_L19N_T3_VREF_18"
						(effects
							(font
								(size 1.27 1.27)
							)
						)
					)
					(number "E16"
						(effects
							(font
								(size 1.27 1.27)
							)
						)
					)
				)
				(pin bidirectional line
					(at 0 -102.87 0)
					(length 5.08)
					(name "IO_L20P_T3_18"
						(effects
							(font
								(size 1.27 1.27)
							)
						)
					)
					(number "E14"
						(effects
							(font
								(size 1.27 1.27)
							)
						)
					)
				)
				(pin bidirectional line
					(at 0 -105.41 0)
					(length 5.08)
					(name "IO_L20N_T3_18"
						(effects
							(font
								(size 1.27 1.27)
							)
						)
					)
					(number "E15"
						(effects
							(font
								(size 1.27 1.27)
							)
						)
					)
				)
				(pin bidirectional line
					(at 0 -107.95 0)
					(length 5.08)
					(name "IO_L21P_T3_DQS_18"
						(effects
							(font
								(size 1.27 1.27)
							)
						)
					)
					(number "D14"
						(effects
							(font
								(size 1.27 1.27)
							)
						)
					)
				)
				(pin bidirectional line
					(at 0 -110.49 0)
					(length 5.08)
					(name "IO_L21N_T3_DQS_18"
						(effects
							(font
								(size 1.27 1.27)
							)
						)
					)
					(number "C14"
						(effects
							(font
								(size 1.27 1.27)
							)
						)
					)
				)
				(pin bidirectional line
					(at 0 -113.03 0)
					(length 5.08)
					(name "IO_L22P_T3_18"
						(effects
							(font
								(size 1.27 1.27)
							)
						)
					)
					(number "B13"
						(effects
							(font
								(size 1.27 1.27)
							)
						)
					)
				)
				(pin bidirectional line
					(at 0 -115.57 0)
					(length 5.08)
					(name "IO_L22N_T3_18"
						(effects
							(font
								(size 1.27 1.27)
							)
						)
					)
					(number "A13"
						(effects
							(font
								(size 1.27 1.27)
							)
						)
					)
				)
				(pin bidirectional line
					(at 0 -118.11 0)
					(length 5.08)
					(name "IO_L23P_T3_18"
						(effects
							(font
								(size 1.27 1.27)
							)
						)
					)
					(number "C15"
						(effects
							(font
								(size 1.27 1.27)
							)
						)
					)
				)
				(pin bidirectional line
					(at 0 -120.65 0)
					(length 5.08)
					(name "IO_L23N_T3_18"
						(effects
							(font
								(size 1.27 1.27)
							)
						)
					)
					(number "B15"
						(effects
							(font
								(size 1.27 1.27)
							)
						)
					)
				)
				(pin bidirectional line
					(at 0 -123.19 0)
					(length 5.08)
					(name "IO_L24P_T3_18"
						(effects
							(font
								(size 1.27 1.27)
							)
						)
					)
					(number "B14"
						(effects
							(font
								(size 1.27 1.27)
							)
						)
					)
				)
				(pin bidirectional line
					(at 0 -125.73 0)
					(length 5.08)
					(name "IO_L24N_T3_18"
						(effects
							(font
								(size 1.27 1.27)
							)
						)
					)
					(number "A15"
						(effects
							(font
								(size 1.27 1.27)
							)
						)
					)
				)
				(pin bidirectional line
					(at 0 -128.27 0)
					(length 5.08)
					(name "IO_25_18"
						(effects
							(font
								(size 1.27 1.27)
							)
						)
					)
					(number "F16"
						(effects
							(font
								(size 1.27 1.27)
							)
						)
					)
				)
				(pin bidirectional line
					(at 53.34 0 180)
					(length 5.08)
					(name "VCCO_32"
						(effects
							(font
								(size 1.27 1.27)
							)
						)
					)
					(number "AA19"
						(effects
							(font
								(size 1.27 1.27)
							)
						)
					)
				)
				(pin passive line
					(at 53.34 0 180)
					(length 5.08)
					(hide yes)
					(name "VCCO_32"
						(effects
							(font
								(size 1.27 1.27)
							)
						)
					)
					(number "AB16"
						(effects
							(font
								(size 1.27 1.27)
							)
						)
					)
				)
				(pin passive line
					(at 53.34 0 180)
					(length 5.08)
					(hide yes)
					(name "VCCO_32"
						(effects
							(font
								(size 1.27 1.27)
							)
						)
					)
					(number "AE17"
						(effects
							(font
								(size 1.27 1.27)
							)
						)
					)
				)
				(pin passive line
					(at 53.34 0 180)
					(length 5.08)
					(hide yes)
					(name "VCCO_32"
						(effects
							(font
								(size 1.27 1.27)
							)
						)
					)
					(number "AF14"
						(effects
							(font
								(size 1.27 1.27)
							)
						)
					)
				)
				(pin passive line
					(at 53.34 0 180)
					(length 5.08)
					(hide yes)
					(name "VCCO_32"
						(effects
							(font
								(size 1.27 1.27)
							)
						)
					)
					(number "AH18"
						(effects
							(font
								(size 1.27 1.27)
							)
						)
					)
				)
				(pin passive line
					(at 53.34 0 180)
					(length 5.08)
					(hide yes)
					(name "VCCO_32"
						(effects
							(font
								(size 1.27 1.27)
							)
						)
					)
					(number "AJ15"
						(effects
							(font
								(size 1.27 1.27)
							)
						)
					)
				)
				(pin bidirectional line
					(at 53.34 -3.81 180)
					(length 5.08)
					(name "IO_0_VRN_32"
						(effects
							(font
								(size 1.27 1.27)
							)
						)
					)
					(number "Y14"
						(effects
							(font
								(size 1.27 1.27)
							)
						)
					)
				)
				(pin bidirectional line
					(at 53.34 -6.35 180)
					(length 5.08)
					(name "IO_L1P_T0_32"
						(effects
							(font
								(size 1.27 1.27)
							)
						)
					)
					(number "AK16"
						(effects
							(font
								(size 1.27 1.27)
							)
						)
					)
				)
				(pin bidirectional line
					(at 53.34 -8.89 180)
					(length 5.08)
					(name "IO_L1N_T0_32"
						(effects
							(font
								(size 1.27 1.27)
							)
						)
					)
					(number "AK15"
						(effects
							(font
								(size 1.27 1.27)
							)
						)
					)
				)
				(pin bidirectional line
					(at 53.34 -11.43 180)
					(length 5.08)
					(name "IO_L2P_T0_32"
						(effects
							(font
								(size 1.27 1.27)
							)
						)
					)
					(number "AG15"
						(effects
							(font
								(size 1.27 1.27)
							)
						)
					)
				)
				(pin bidirectional line
					(at 53.34 -13.97 180)
					(length 5.08)
					(name "IO_L2N_T0_32"
						(effects
							(font
								(size 1.27 1.27)
							)
						)
					)
					(number "AH15"
						(effects
							(font
								(size 1.27 1.27)
							)
						)
					)
				)
				(pin bidirectional line
					(at 53.34 -16.51 180)
					(length 5.08)
					(name "IO_L3P_T0_DQS_32"
						(effects
							(font
								(size 1.27 1.27)
							)
						)
					)
					(number "AH16"
						(effects
							(font
								(size 1.27 1.27)
							)
						)
					)
				)
				(pin bidirectional line
					(at 53.34 -19.05 180)
					(length 5.08)
					(name "IO_L3N_T0_DQS_32"
						(effects
							(font
								(size 1.27 1.27)
							)
						)
					)
					(number "AJ16"
						(effects
							(font
								(size 1.27 1.27)
							)
						)
					)
				)
				(pin bidirectional line
					(at 53.34 -21.59 180)
					(length 5.08)
					(name "IO_L4P_T0_32"
						(effects
							(font
								(size 1.27 1.27)
							)
						)
					)
					(number "AF15"
						(effects
							(font
								(size 1.27 1.27)
							)
						)
					)
				)
				(pin bidirectional line
					(at 53.34 -24.13 180)
					(length 5.08)
					(name "IO_L4N_T0_32"
						(effects
							(font
								(size 1.27 1.27)
							)
						)
					)
					(number "AG14"
						(effects
							(font
								(size 1.27 1.27)
							)
						)
					)
				)
				(pin bidirectional line
					(at 53.34 -26.67 180)
					(length 5.08)
					(name "IO_L5P_T0_32"
						(effects
							(font
								(size 1.27 1.27)
							)
						)
					)
					(number "AH17"
						(effects
							(font
								(size 1.27 1.27)
							)
						)
					)
				)
				(pin bidirectional line
					(at 53.34 -29.21 180)
					(length 5.08)
					(name "IO_L5N_T0_32"
						(effects
							(font
								(size 1.27 1.27)
							)
						)
					)
					(number "AJ17"
						(effects
							(font
								(size 1.27 1.27)
							)
						)
					)
				)
				(pin bidirectional line
					(at 53.34 -31.75 180)
					(length 5.08)
					(name "IO_L6P_T0_32"
						(effects
							(font
								(size 1.27 1.27)
							)
						)
					)
					(number "AE16"
						(effects
							(font
								(size 1.27 1.27)
							)
						)
					)
				)
				(pin bidirectional line
					(at 53.34 -34.29 180)
					(length 5.08)
					(name "IO_L6N_T0_VREF_32"
						(effects
							(font
								(size 1.27 1.27)
							)
						)
					)
					(number "AF16"
						(effects
							(font
								(size 1.27 1.27)
							)
						)
					)
				)
				(pin bidirectional line
					(at 53.34 -36.83 180)
					(length 5.08)
					(name "IO_L7P_T1_32"
						(effects
							(font
								(size 1.27 1.27)
							)
						)
					)
					(number "AJ19"
						(effects
							(font
								(size 1.27 1.27)
							)
						)
					)
				)
				(pin bidirectional line
					(at 53.34 -39.37 180)
					(length 5.08)
					(name "IO_L7N_T1_32"
						(effects
							(font
								(size 1.27 1.27)
							)
						)
					)
					(number "AK19"
						(effects
							(font
								(size 1.27 1.27)
							)
						)
					)
				)
				(pin bidirectional line
					(at 53.34 -41.91 180)
					(length 5.08)
					(name "IO_L8P_T1_32"
						(effects
							(font
								(size 1.27 1.27)
							)
						)
					)
					(number "AG19"
						(effects
							(font
								(size 1.27 1.27)
							)
						)
					)
				)
				(pin bidirectional line
					(at 53.34 -44.45 180)
					(length 5.08)
					(name "IO_L8N_T1_32"
						(effects
							(font
								(size 1.27 1.27)
							)
						)
					)
					(number "AH19"
						(effects
							(font
								(size 1.27 1.27)
							)
						)
					)
				)
				(pin bidirectional line
					(at 53.34 -46.99 180)
					(length 5.08)
					(name "IO_L9P_T1_DQS_32"
						(effects
							(font
								(size 1.27 1.27)
							)
						)
					)
					(number "AJ18"
						(effects
							(font
								(size 1.27 1.27)
							)
						)
					)
				)
				(pin bidirectional line
					(at 53.34 -49.53 180)
					(length 5.08)
					(name "IO_L9N_T1_DQS_32"
						(effects
							(font
								(size 1.27 1.27)
							)
						)
					)
					(number "AK18"
						(effects
							(font
								(size 1.27 1.27)
							)
						)
					)
				)
				(pin bidirectional line
					(at 53.34 -52.07 180)
					(length 5.08)
					(name "IO_L10P_T1_32"
						(effects
							(font
								(size 1.27 1.27)
							)
						)
					)
					(number "AD19"
						(effects
							(font
								(size 1.27 1.27)
							)
						)
					)
				)
				(pin bidirectional line
					(at 53.34 -54.61 180)
					(length 5.08)
					(name "IO_L10N_T1_32"
						(effects
							(font
								(size 1.27 1.27)
							)
						)
					)
					(number "AE19"
						(effects
							(font
								(size 1.27 1.27)
							)
						)
					)
				)
				(pin bidirectional line
					(at 53.34 -57.15 180)
					(length 5.08)
					(name "IO_L11P_T1_SRCC_32"
						(effects
							(font
								(size 1.27 1.27)
							)
						)
					)
					(number "AF18"
						(effects
							(font
								(size 1.27 1.27)
							)
						)
					)
				)
				(pin bidirectional line
					(at 53.34 -59.69 180)
					(length 5.08)
					(name "IO_L11N_T1_SRCC_32"
						(effects
							(font
								(size 1.27 1.27)
							)
						)
					)
					(number "AG18"
						(effects
							(font
								(size 1.27 1.27)
							)
						)
					)
				)
				(pin bidirectional line
					(at 53.34 -62.23 180)
					(length 5.08)
					(name "IO_L12P_T1_MRCC_32"
						(effects
							(font
								(size 1.27 1.27)
							)
						)
					)
					(number "AF17"
						(effects
							(font
								(size 1.27 1.27)
							)
						)
					)
				)
				(pin bidirectional line
					(at 53.34 -64.77 180)
					(length 5.08)
					(name "IO_L12N_T1_MRCC_32"
						(effects
							(font
								(size 1.27 1.27)
							)
						)
					)
					(number "AG17"
						(effects
							(font
								(size 1.27 1.27)
							)
						)
					)
				)
				(pin bidirectional line
					(at 53.34 -67.31 180)
					(length 5.08)
					(name "IO_L13P_T2_MRCC_32"
						(effects
							(font
								(size 1.27 1.27)
							)
						)
					)
					(number "AD18"
						(effects
							(font
								(size 1.27 1.27)
							)
						)
					)
				)
				(pin bidirectional line
					(at 53.34 -69.85 180)
					(length 5.08)
					(name "IO_L13N_T2_MRCC_32"
						(effects
							(font
								(size 1.27 1.27)
							)
						)
					)
					(number "AE18"
						(effects
							(font
								(size 1.27 1.27)
							)
						)
					)
				)
				(pin bidirectional line
					(at 53.34 -72.39 180)
					(length 5.08)
					(name "IO_L14P_T2_SRCC_32"
						(effects
							(font
								(size 1.27 1.27)
							)
						)
					)
					(number "AD17"
						(effects
							(font
								(size 1.27 1.27)
							)
						)
					)
				)
				(pin bidirectional line
					(at 53.34 -74.93 180)
					(length 5.08)
					(name "IO_L14N_T2_SRCC_32"
						(effects
							(font
								(size 1.27 1.27)
							)
						)
					)
					(number "AD16"
						(effects
							(font
								(size 1.27 1.27)
							)
						)
					)
				)
				(pin bidirectional line
					(at 53.34 -77.47 180)
					(length 5.08)
					(name "IO_L15P_T2_DQS_32"
						(effects
							(font
								(size 1.27 1.27)
							)
						)
					)
					(number "Y19"
						(effects
							(font
								(size 1.27 1.27)
							)
						)
					)
				)
				(pin bidirectional line
					(at 53.34 -80.01 180)
					(length 5.08)
					(name "IO_L15N_T2_DQS_32"
						(effects
							(font
								(size 1.27 1.27)
							)
						)
					)
					(number "Y18"
						(effects
							(font
								(size 1.27 1.27)
							)
						)
					)
				)
				(pin bidirectional line
					(at 53.34 -82.55 180)
					(length 5.08)
					(name "IO_L16P_T2_32"
						(effects
							(font
								(size 1.27 1.27)
							)
						)
					)
					(number "AA18"
						(effects
							(font
								(size 1.27 1.27)
							)
						)
					)
				)
				(pin bidirectional line
					(at 53.34 -85.09 180)
					(length 5.08)
					(name "IO_L16N_T2_32"
						(effects
							(font
								(size 1.27 1.27)
							)
						)
					)
					(number "AB18"
						(effects
							(font
								(size 1.27 1.27)
							)
						)
					)
				)
				(pin bidirectional line
					(at 53.34 -87.63 180)
					(length 5.08)
					(name "IO_L17P_T2_32"
						(effects
							(font
								(size 1.27 1.27)
							)
						)
					)
					(number "AB19"
						(effects
							(font
								(size 1.27 1.27)
							)
						)
					)
				)
				(pin bidirectional line
					(at 53.34 -90.17 180)
					(length 5.08)
					(name "IO_L17N_T2_32"
						(effects
							(font
								(size 1.27 1.27)
							)
						)
					)
					(number "AC19"
						(effects
							(font
								(size 1.27 1.27)
							)
						)
					)
				)
				(pin bidirectional line
					(at 53.34 -92.71 180)
					(length 5.08)
					(name "IO_L18P_T2_32"
						(effects
							(font
								(size 1.27 1.27)
							)
						)
					)
					(number "AB17"
						(effects
							(font
								(size 1.27 1.27)
							)
						)
					)
				)
				(pin bidirectional line
					(at 53.34 -95.25 180)
					(length 5.08)
					(name "IO_L18N_T2_32"
						(effects
							(font
								(size 1.27 1.27)
							)
						)
					)
					(number "AC17"
						(effects
							(font
								(size 1.27 1.27)
							)
						)
					)
				)
				(pin bidirectional line
					(at 53.34 -97.79 180)
					(length 5.08)
					(name "IO_L19P_T3_32"
						(effects
							(font
								(size 1.27 1.27)
							)
						)
					)
					(number "AE15"
						(effects
							(font
								(size 1.27 1.27)
							)
						)
					)
				)
				(pin bidirectional line
					(at 53.34 -100.33 180)
					(length 5.08)
					(name "IO_L19N_T3_VREF_32"
						(effects
							(font
								(size 1.27 1.27)
							)
						)
					)
					(number "AE14"
						(effects
							(font
								(size 1.27 1.27)
							)
						)
					)
				)
				(pin bidirectional line
					(at 53.34 -102.87 180)
					(length 5.08)
					(name "IO_L20P_T3_32"
						(effects
							(font
								(size 1.27 1.27)
							)
						)
					)
					(number "AA15"
						(effects
							(font
								(size 1.27 1.27)
							)
						)
					)
				)
				(pin bidirectional line
					(at 53.34 -105.41 180)
					(length 5.08)
					(name "IO_L20N_T3_32"
						(effects
							(font
								(size 1.27 1.27)
							)
						)
					)
					(number "AB15"
						(effects
							(font
								(size 1.27 1.27)
							)
						)
					)
				)
				(pin bidirectional line
					(at 53.34 -107.95 180)
					(length 5.08)
					(name "IO_L21P_T3_DQS_32"
						(effects
							(font
								(size 1.27 1.27)
							)
						)
					)
					(number "AC16"
						(effects
							(font
								(size 1.27 1.27)
							)
						)
					)
				)
				(pin bidirectional line
					(at 53.34 -110.49 180)
					(length 5.08)
					(name "IO_L21N_T3_DQS_32"
						(effects
							(font
								(size 1.27 1.27)
							)
						)
					)
					(number "AC15"
						(effects
							(font
								(size 1.27 1.27)
							)
						)
					)
				)
				(pin bidirectional line
					(at 53.34 -113.03 180)
					(length 5.08)
					(name "IO_L22P_T3_32"
						(effects
							(font
								(size 1.27 1.27)
							)
						)
					)
					(number "AC14"
						(effects
							(font
								(size 1.27 1.27)
							)
						)
					)
				)
				(pin bidirectional line
					(at 53.34 -115.57 180)
					(length 5.08)
					(name "IO_L22N_T3_32"
						(effects
							(font
								(size 1.27 1.27)
							)
						)
					)
					(number "AD14"
						(effects
							(font
								(size 1.27 1.27)
							)
						)
					)
				)
				(pin bidirectional line
					(at 53.34 -118.11 180)
					(length 5.08)
					(name "IO_L23P_T3_32"
						(effects
							(font
								(size 1.27 1.27)
							)
						)
					)
					(number "AA17"
						(effects
							(font
								(size 1.27 1.27)
							)
						)
					)
				)
				(pin bidirectional line
					(at 53.34 -120.65 180)
					(length 5.08)
					(name "IO_L23N_T3_32"
						(effects
							(font
								(size 1.27 1.27)
							)
						)
					)
					(number "AA16"
						(effects
							(font
								(size 1.27 1.27)
							)
						)
					)
				)
				(pin bidirectional line
					(at 53.34 -123.19 180)
					(length 5.08)
					(name "IO_L24P_T3_32"
						(effects
							(font
								(size 1.27 1.27)
							)
						)
					)
					(number "Y16"
						(effects
							(font
								(size 1.27 1.27)
							)
						)
					)
				)
				(pin bidirectional line
					(at 53.34 -125.73 180)
					(length 5.08)
					(name "IO_L24N_T3_32"
						(effects
							(font
								(size 1.27 1.27)
							)
						)
					)
					(number "Y15"
						(effects
							(font
								(size 1.27 1.27)
							)
						)
					)
				)
				(pin bidirectional line
					(at 53.34 -128.27 180)
					(length 5.08)
					(name "IO_25_VRP_32"
						(effects
							(font
								(size 1.27 1.27)
							)
						)
					)
					(number "AB14"
						(effects
							(font
								(size 1.27 1.27)
							)
						)
					)
				)
			)
			(symbol "XC7K410T-2FFG900I_5_1"
				(rectangle
					(start 5.08 5.08)
					(end 49.53 -130.81)
					(stroke
						(width 0.254)
						(type default)
					)
					(fill
						(type background)
					)
				)
				(text "BANK 33"
					(at 17.78 2.54 0)
					(effects
						(font
							(size 1.27 1.27)
							(thickness 0.15)
						)
						(justify left bottom)
					)
				)
				(text "BANK 34"
					(at 30.48 2.54 0)
					(effects
						(font
							(size 1.27 1.27)
							(thickness 0.15)
						)
						(justify left bottom)
					)
				)
				(pin bidirectional line
					(at 0 0 0)
					(length 5.08)
					(name "VCCO_33"
						(effects
							(font
								(size 1.27 1.27)
							)
						)
					)
					(number "AA9"
						(effects
							(font
								(size 1.27 1.27)
							)
						)
					)
				)
				(pin passive line
					(at 0 0 0)
					(length 5.08)
					(hide yes)
					(name "VCCO_33"
						(effects
							(font
								(size 1.27 1.27)
							)
						)
					)
					(number "AC13"
						(effects
							(font
								(size 1.27 1.27)
							)
						)
					)
				)
				(pin passive line
					(at 0 0 0)
					(length 5.08)
					(hide yes)
					(name "VCCO_33"
						(effects
							(font
								(size 1.27 1.27)
							)
						)
					)
					(number "AD10"
						(effects
							(font
								(size 1.27 1.27)
							)
						)
					)
				)
				(pin passive line
					(at 0 0 0)
					(length 5.08)
					(hide yes)
					(name "VCCO_33"
						(effects
							(font
								(size 1.27 1.27)
							)
						)
					)
					(number "AG11"
						(effects
							(font
								(size 1.27 1.27)
							)
						)
					)
				)
				(pin passive line
					(at 0 0 0)
					(length 5.08)
					(hide yes)
					(name "VCCO_33"
						(effects
							(font
								(size 1.27 1.27)
							)
						)
					)
					(number "AK12"
						(effects
							(font
								(size 1.27 1.27)
							)
						)
					)
				)
				(pin passive line
					(at 0 0 0)
					(length 5.08)
					(hide yes)
					(name "VCCO_33"
						(effects
							(font
								(size 1.27 1.27)
							)
						)
					)
					(number "Y12"
						(effects
							(font
								(size 1.27 1.27)
							)
						)
					)
				)
				(pin bidirectional line
					(at 0 -3.81 0)
					(length 5.08)
					(name "IO_0_VRN_33"
						(effects
							(font
								(size 1.27 1.27)
							)
						)
					)
					(number "Y13"
						(effects
							(font
								(size 1.27 1.27)
							)
						)
					)
				)
				(pin bidirectional line
					(at 0 -6.35 0)
					(length 5.08)
					(name "IO_L1P_T0_33"
						(effects
							(font
								(size 1.27 1.27)
							)
						)
					)
					(number "AA12"
						(effects
							(font
								(size 1.27 1.27)
							)
						)
					)
				)
				(pin bidirectional line
					(at 0 -8.89 0)
					(length 5.08)
					(name "IO_L1N_T0_33"
						(effects
							(font
								(size 1.27 1.27)
							)
						)
					)
					(number "AB12"
						(effects
							(font
								(size 1.27 1.27)
							)
						)
					)
				)
				(pin bidirectional line
					(at 0 -11.43 0)
					(length 5.08)
					(name "IO_L2P_T0_33"
						(effects
							(font
								(size 1.27 1.27)
							)
						)
					)
					(number "AA8"
						(effects
							(font
								(size 1.27 1.27)
							)
						)
					)
				)
				(pin bidirectional line
					(at 0 -13.97 0)
					(length 5.08)
					(name "IO_L2N_T0_33"
						(effects
							(font
								(size 1.27 1.27)
							)
						)
					)
					(number "AB8"
						(effects
							(font
								(size 1.27 1.27)
							)
						)
					)
				)
				(pin bidirectional line
					(at 0 -16.51 0)
					(length 5.08)
					(name "IO_L3P_T0_DQS_33"
						(effects
							(font
								(size 1.27 1.27)
							)
						)
					)
					(number "AB9"
						(effects
							(font
								(size 1.27 1.27)
							)
						)
					)
				)
				(pin bidirectional line
					(at 0 -19.05 0)
					(length 5.08)
					(name "IO_L3N_T0_DQS_33"
						(effects
							(font
								(size 1.27 1.27)
							)
						)
					)
					(number "AC9"
						(effects
							(font
								(size 1.27 1.27)
							)
						)
					)
				)
				(pin bidirectional line
					(at 0 -21.59 0)
					(length 5.08)
					(name "IO_L4P_T0_33"
						(effects
							(font
								(size 1.27 1.27)
							)
						)
					)
					(number "Y11"
						(effects
							(font
								(size 1.27 1.27)
							)
						)
					)
				)
				(pin bidirectional line
					(at 0 -24.13 0)
					(length 5.08)
					(name "IO_L4N_T0_33"
						(effects
							(font
								(size 1.27 1.27)
							)
						)
					)
					(number "Y10"
						(effects
							(font
								(size 1.27 1.27)
							)
						)
					)
				)
				(pin bidirectional line
					(at 0 -26.67 0)
					(length 5.08)
					(name "IO_L5P_T0_33"
						(effects
							(font
								(size 1.27 1.27)
							)
						)
					)
					(number "AA11"
						(effects
							(font
								(size 1.27 1.27)
							)
						)
					)
				)
				(pin bidirectional line
					(at 0 -29.21 0)
					(length 5.08)
					(name "IO_L5N_T0_33"
						(effects
							(font
								(size 1.27 1.27)
							)
						)
					)
					(number "AA10"
						(effects
							(font
								(size 1.27 1.27)
							)
						)
					)
				)
				(pin bidirectional line
					(at 0 -31.75 0)
					(length 5.08)
					(name "IO_L6P_T0_33"
						(effects
							(font
								(size 1.27 1.27)
							)
						)
					)
					(number "AA13"
						(effects
							(font
								(size 1.27 1.27)
							)
						)
					)
				)
				(pin bidirectional line
					(at 0 -34.29 0)
					(length 5.08)
					(name "IO_L6N_T0_VREF_33"
						(effects
							(font
								(size 1.27 1.27)
							)
						)
					)
					(number "AB13"
						(effects
							(font
								(size 1.27 1.27)
							)
						)
					)
				)
				(pin bidirectional line
					(at 0 -36.83 0)
					(length 5.08)
					(name "IO_L7P_T1_33"
						(effects
							(font
								(size 1.27 1.27)
							)
						)
					)
					(number "AB10"
						(effects
							(font
								(size 1.27 1.27)
							)
						)
					)
				)
				(pin bidirectional line
					(at 0 -39.37 0)
					(length 5.08)
					(name "IO_L7N_T1_33"
						(effects
							(font
								(size 1.27 1.27)
							)
						)
					)
					(number "AC10"
						(effects
							(font
								(size 1.27 1.27)
							)
						)
					)
				)
				(pin bidirectional line
					(at 0 -41.91 0)
					(length 5.08)
					(name "IO_L8P_T1_33"
						(effects
							(font
								(size 1.27 1.27)
							)
						)
					)
					(number "AD8"
						(effects
							(font
								(size 1.27 1.27)
							)
						)
					)
				)
				(pin bidirectional line
					(at 0 -44.45 0)
					(length 5.08)
					(name "IO_L8N_T1_33"
						(effects
							(font
								(size 1.27 1.27)
							)
						)
					)
					(number "AE8"
						(effects
							(font
								(size 1.27 1.27)
							)
						)
					)
				)
				(pin bidirectional line
					(at 0 -46.99 0)
					(length 5.08)
					(name "IO_L9P_T1_DQS_33"
						(effects
							(font
								(size 1.27 1.27)
							)
						)
					)
					(number "AC12"
						(effects
							(font
								(size 1.27 1.27)
							)
						)
					)
				)
				(pin bidirectional line
					(at 0 -49.53 0)
					(length 5.08)
					(name "IO_L9N_T1_DQS_33"
						(effects
							(font
								(size 1.27 1.27)
							)
						)
					)
					(number "AC11"
						(effects
							(font
								(size 1.27 1.27)
							)
						)
					)
				)
				(pin bidirectional line
					(at 0 -52.07 0)
					(length 5.08)
					(name "IO_L10P_T1_33"
						(effects
							(font
								(size 1.27 1.27)
							)
						)
					)
					(number "AD9"
						(effects
							(font
								(size 1.27 1.27)
							)
						)
					)
				)
				(pin bidirectional line
					(at 0 -54.61 0)
					(length 5.08)
					(name "IO_L10N_T1_33"
						(effects
							(font
								(size 1.27 1.27)
							)
						)
					)
					(number "AE9"
						(effects
							(font
								(size 1.27 1.27)
							)
						)
					)
				)
				(pin bidirectional line
					(at 0 -57.15 0)
					(length 5.08)
					(name "IO_L11P_T1_SRCC_33"
						(effects
							(font
								(size 1.27 1.27)
							)
						)
					)
					(number "AE11"
						(effects
							(font
								(size 1.27 1.27)
							)
						)
					)
				)
				(pin bidirectional line
					(at 0 -59.69 0)
					(length 5.08)
					(name "IO_L11N_T1_SRCC_33"
						(effects
							(font
								(size 1.27 1.27)
							)
						)
					)
					(number "AF11"
						(effects
							(font
								(size 1.27 1.27)
							)
						)
					)
				)
				(pin bidirectional line
					(at 0 -62.23 0)
					(length 5.08)
					(name "IO_L12P_T1_MRCC_33"
						(effects
							(font
								(size 1.27 1.27)
							)
						)
					)
					(number "AD12"
						(effects
							(font
								(size 1.27 1.27)
							)
						)
					)
				)
				(pin bidirectional line
					(at 0 -64.77 0)
					(length 5.08)
					(name "IO_L12N_T1_MRCC_33"
						(effects
							(font
								(size 1.27 1.27)
							)
						)
					)
					(number "AD11"
						(effects
							(font
								(size 1.27 1.27)
							)
						)
					)
				)
				(pin bidirectional line
					(at 0 -67.31 0)
					(length 5.08)
					(name "IO_L13P_T2_MRCC_33"
						(effects
							(font
								(size 1.27 1.27)
							)
						)
					)
					(number "AG10"
						(effects
							(font
								(size 1.27 1.27)
							)
						)
					)
				)
				(pin bidirectional line
					(at 0 -69.85 0)
					(length 5.08)
					(name "IO_L13N_T2_MRCC_33"
						(effects
							(font
								(size 1.27 1.27)
							)
						)
					)
					(number "AH10"
						(effects
							(font
								(size 1.27 1.27)
							)
						)
					)
				)
				(pin bidirectional line
					(at 0 -72.39 0)
					(length 5.08)
					(name "IO_L14P_T2_SRCC_33"
						(effects
							(font
								(size 1.27 1.27)
							)
						)
					)
					(number "AE10"
						(effects
							(font
								(size 1.27 1.27)
							)
						)
					)
				)
				(pin bidirectional line
					(at 0 -74.93 0)
					(length 5.08)
					(name "IO_L14N_T2_SRCC_33"
						(effects
							(font
								(size 1.27 1.27)
							)
						)
					)
					(number "AF10"
						(effects
							(font
								(size 1.27 1.27)
							)
						)
					)
				)
				(pin bidirectional line
					(at 0 -77.47 0)
					(length 5.08)
					(name "IO_L15P_T2_DQS_33"
						(effects
							(font
								(size 1.27 1.27)
							)
						)
					)
					(number "AJ9"
						(effects
							(font
								(size 1.27 1.27)
							)
						)
					)
				)
				(pin bidirectional line
					(at 0 -80.01 0)
					(length 5.08)
					(name "IO_L15N_T2_DQS_33"
						(effects
							(font
								(size 1.27 1.27)
							)
						)
					)
					(number "AK9"
						(effects
							(font
								(size 1.27 1.27)
							)
						)
					)
				)
				(pin bidirectional line
					(at 0 -82.55 0)
					(length 5.08)
					(name "IO_L16P_T2_33"
						(effects
							(font
								(size 1.27 1.27)
							)
						)
					)
					(number "AG9"
						(effects
							(font
								(size 1.27 1.27)
							)
						)
					)
				)
				(pin bidirectional line
					(at 0 -85.09 0)
					(length 5.08)
					(name "IO_L16N_T2_33"
						(effects
							(font
								(size 1.27 1.27)
							)
						)
					)
					(number "AH9"
						(effects
							(font
								(size 1.27 1.27)
							)
						)
					)
				)
				(pin bidirectional line
					(at 0 -87.63 0)
					(length 5.08)
					(name "IO_L17P_T2_33"
						(effects
							(font
								(size 1.27 1.27)
							)
						)
					)
					(number "AK11"
						(effects
							(font
								(size 1.27 1.27)
							)
						)
					)
				)
				(pin bidirectional line
					(at 0 -90.17 0)
					(length 5.08)
					(name "IO_L17N_T2_33"
						(effects
							(font
								(size 1.27 1.27)
							)
						)
					)
					(number "AK10"
						(effects
							(font
								(size 1.27 1.27)
							)
						)
					)
				)
				(pin bidirectional line
					(at 0 -92.71 0)
					(length 5.08)
					(name "IO_L18P_T2_33"
						(effects
							(font
								(size 1.27 1.27)
							)
						)
					)
					(number "AH11"
						(effects
							(font
								(size 1.27 1.27)
							)
						)
					)
				)
				(pin bidirectional line
					(at 0 -95.25 0)
					(length 5.08)
					(name "IO_L18N_T2_33"
						(effects
							(font
								(size 1.27 1.27)
							)
						)
					)
					(number "AJ11"
						(effects
							(font
								(size 1.27 1.27)
							)
						)
					)
				)
				(pin bidirectional line
					(at 0 -97.79 0)
					(length 5.08)
					(name "IO_L19P_T3_33"
						(effects
							(font
								(size 1.27 1.27)
							)
						)
					)
					(number "AE13"
						(effects
							(font
								(size 1.27 1.27)
							)
						)
					)
				)
				(pin bidirectional line
					(at 0 -100.33 0)
					(length 5.08)
					(name "IO_L19N_T3_VREF_33"
						(effects
							(font
								(size 1.27 1.27)
							)
						)
					)
					(number "AF13"
						(effects
							(font
								(size 1.27 1.27)
							)
						)
					)
				)
				(pin bidirectional line
					(at 0 -102.87 0)
					(length 5.08)
					(name "IO_L20P_T3_33"
						(effects
							(font
								(size 1.27 1.27)
							)
						)
					)
					(number "AK14"
						(effects
							(font
								(size 1.27 1.27)
							)
						)
					)
				)
				(pin bidirectional line
					(at 0 -105.41 0)
					(length 5.08)
					(name "IO_L20N_T3_33"
						(effects
							(font
								(size 1.27 1.27)
							)
						)
					)
					(number "AK13"
						(effects
							(font
								(size 1.27 1.27)
							)
						)
					)
				)
				(pin bidirectional line
					(at 0 -107.95 0)
					(length 5.08)
					(name "IO_L21P_T3_DQS_33"
						(effects
							(font
								(size 1.27 1.27)
							)
						)
					)
					(number "AH14"
						(effects
							(font
								(size 1.27 1.27)
							)
						)
					)
				)
				(pin bidirectional line
					(at 0 -110.49 0)
					(length 5.08)
					(name "IO_L21N_T3_DQS_33"
						(effects
							(font
								(size 1.27 1.27)
							)
						)
					)
					(number "AJ14"
						(effects
							(font
								(size 1.27 1.27)
							)
						)
					)
				)
				(pin bidirectional line
					(at 0 -113.03 0)
					(length 5.08)
					(name "IO_L22P_T3_33"
						(effects
							(font
								(size 1.27 1.27)
							)
						)
					)
					(number "AJ13"
						(effects
							(font
								(size 1.27 1.27)
							)
						)
					)
				)
				(pin bidirectional line
					(at 0 -115.57 0)
					(length 5.08)
					(name "IO_L22N_T3_33"
						(effects
							(font
								(size 1.27 1.27)
							)
						)
					)
					(number "AJ12"
						(effects
							(font
								(size 1.27 1.27)
							)
						)
					)
				)
				(pin bidirectional line
					(at 0 -118.11 0)
					(length 5.08)
					(name "IO_L23P_T3_33"
						(effects
							(font
								(size 1.27 1.27)
							)
						)
					)
					(number "AF12"
						(effects
							(font
								(size 1.27 1.27)
							)
						)
					)
				)
				(pin bidirectional line
					(at 0 -120.65 0)
					(length 5.08)
					(name "IO_L23N_T3_33"
						(effects
							(font
								(size 1.27 1.27)
							)
						)
					)
					(number "AG12"
						(effects
							(font
								(size 1.27 1.27)
							)
						)
					)
				)
				(pin bidirectional line
					(at 0 -123.19 0)
					(length 5.08)
					(name "IO_L24P_T3_33"
						(effects
							(font
								(size 1.27 1.27)
							)
						)
					)
					(number "AG13"
						(effects
							(font
								(size 1.27 1.27)
							)
						)
					)
				)
				(pin bidirectional line
					(at 0 -125.73 0)
					(length 5.08)
					(name "IO_L24N_T3_33"
						(effects
							(font
								(size 1.27 1.27)
							)
						)
					)
					(number "AH12"
						(effects
							(font
								(size 1.27 1.27)
							)
						)
					)
				)
				(pin bidirectional line
					(at 0 -128.27 0)
					(length 5.08)
					(name "IO_25_VRP_33"
						(effects
							(font
								(size 1.27 1.27)
							)
						)
					)
					(number "AD13"
						(effects
							(font
								(size 1.27 1.27)
							)
						)
					)
				)
				(pin bidirectional line
					(at 54.61 0 180)
					(length 5.08)
					(name "VCCO_34"
						(effects
							(font
								(size 1.27 1.27)
							)
						)
					)
					(number "AC3"
						(effects
							(font
								(size 1.27 1.27)
							)
						)
					)
				)
				(pin passive line
					(at 54.61 0 180)
					(length 5.08)
					(hide yes)
					(name "VCCO_34"
						(effects
							(font
								(size 1.27 1.27)
							)
						)
					)
					(number "AE7"
						(effects
							(font
								(size 1.27 1.27)
							)
						)
					)
				)
				(pin passive line
					(at 54.61 0 180)
					(length 5.08)
					(hide yes)
					(name "VCCO_34"
						(effects
							(font
								(size 1.27 1.27)
							)
						)
					)
					(number "AF4"
						(effects
							(font
								(size 1.27 1.27)
							)
						)
					)
				)
				(pin passive line
					(at 54.61 0 180)
					(length 5.08)
					(hide yes)
					(name "VCCO_34"
						(effects
							(font
								(size 1.27 1.27)
							)
						)
					)
					(number "AG1"
						(effects
							(font
								(size 1.27 1.27)
							)
						)
					)
				)
				(pin passive line
					(at 54.61 0 180)
					(length 5.08)
					(hide yes)
					(name "VCCO_34"
						(effects
							(font
								(size 1.27 1.27)
							)
						)
					)
					(number "AH8"
						(effects
							(font
								(size 1.27 1.27)
							)
						)
					)
				)
				(pin passive line
					(at 54.61 0 180)
					(length 5.08)
					(hide yes)
					(name "VCCO_34"
						(effects
							(font
								(size 1.27 1.27)
							)
						)
					)
					(number "AJ5"
						(effects
							(font
								(size 1.27 1.27)
							)
						)
					)
				)
				(pin passive line
					(at 54.61 0 180)
					(length 5.08)
					(hide yes)
					(name "VCCO_34"
						(effects
							(font
								(size 1.27 1.27)
							)
						)
					)
					(number "AK2"
						(effects
							(font
								(size 1.27 1.27)
							)
						)
					)
				)
				(pin bidirectional line
					(at 54.61 -3.81 180)
					(length 5.08)
					(name "IO_0_VRN_34"
						(effects
							(font
								(size 1.27 1.27)
							)
						)
					)
					(number "AC6"
						(effects
							(font
								(size 1.27 1.27)
							)
						)
					)
				)
				(pin bidirectional line
					(at 54.61 -6.35 180)
					(length 5.08)
					(name "IO_L1P_T0_34"
						(effects
							(font
								(size 1.27 1.27)
							)
						)
					)
					(number "AD4"
						(effects
							(font
								(size 1.27 1.27)
							)
						)
					)
				)
				(pin bidirectional line
					(at 54.61 -8.89 180)
					(length 5.08)
					(name "IO_L1N_T0_34"
						(effects
							(font
								(size 1.27 1.27)
							)
						)
					)
					(number "AD3"
						(effects
							(font
								(size 1.27 1.27)
							)
						)
					)
				)
				(pin bidirectional line
					(at 54.61 -11.43 180)
					(length 5.08)
					(name "IO_L2P_T0_34"
						(effects
							(font
								(size 1.27 1.27)
							)
						)
					)
					(number "AC2"
						(effects
							(font
								(size 1.27 1.27)
							)
						)
					)
				)
				(pin bidirectional line
					(at 54.61 -13.97 180)
					(length 5.08)
					(name "IO_L2N_T0_34"
						(effects
							(font
								(size 1.27 1.27)
							)
						)
					)
					(number "AC1"
						(effects
							(font
								(size 1.27 1.27)
							)
						)
					)
				)
				(pin bidirectional line
					(at 54.61 -16.51 180)
					(length 5.08)
					(name "IO_L3P_T0_DQS_34"
						(effects
							(font
								(size 1.27 1.27)
							)
						)
					)
					(number "AD2"
						(effects
							(font
								(size 1.27 1.27)
							)
						)
					)
				)
				(pin bidirectional line
					(at 54.61 -19.05 180)
					(length 5.08)
					(name "IO_L3N_T0_DQS_34"
						(effects
							(font
								(size 1.27 1.27)
							)
						)
					)
					(number "AD1"
						(effects
							(font
								(size 1.27 1.27)
							)
						)
					)
				)
				(pin bidirectional line
					(at 54.61 -21.59 180)
					(length 5.08)
					(name "IO_L4P_T0_34"
						(effects
							(font
								(size 1.27 1.27)
							)
						)
					)
					(number "AC5"
						(effects
							(font
								(size 1.27 1.27)
							)
						)
					)
				)
				(pin bidirectional line
					(at 54.61 -24.13 180)
					(length 5.08)
					(name "IO_L4N_T0_34"
						(effects
							(font
								(size 1.27 1.27)
							)
						)
					)
					(number "AC4"
						(effects
							(font
								(size 1.27 1.27)
							)
						)
					)
				)
				(pin bidirectional line
					(at 54.61 -26.67 180)
					(length 5.08)
					(name "IO_L5P_T0_34"
						(effects
							(font
								(size 1.27 1.27)
							)
						)
					)
					(number "AD6"
						(effects
							(font
								(size 1.27 1.27)
							)
						)
					)
				)
				(pin bidirectional line
					(at 54.61 -29.21 180)
					(length 5.08)
					(name "IO_L5N_T0_34"
						(effects
							(font
								(size 1.27 1.27)
							)
						)
					)
					(number "AE6"
						(effects
							(font
								(size 1.27 1.27)
							)
						)
					)
				)
				(pin bidirectional line
					(at 54.61 -31.75 180)
					(length 5.08)
					(name "IO_L6P_T0_34"
						(effects
							(font
								(size 1.27 1.27)
							)
						)
					)
					(number "AC7"
						(effects
							(font
								(size 1.27 1.27)
							)
						)
					)
				)
				(pin bidirectional line
					(at 54.61 -34.29 180)
					(length 5.08)
					(name "IO_L6N_T0_VREF_34"
						(effects
							(font
								(size 1.27 1.27)
							)
						)
					)
					(number "AD7"
						(effects
							(font
								(size 1.27 1.27)
							)
						)
					)
				)
				(pin bidirectional line
					(at 54.61 -36.83 180)
					(length 5.08)
					(name "IO_L7P_T1_34"
						(effects
							(font
								(size 1.27 1.27)
							)
						)
					)
					(number "AF3"
						(effects
							(font
								(size 1.27 1.27)
							)
						)
					)
				)
				(pin bidirectional line
					(at 54.61 -39.37 180)
					(length 5.08)
					(name "IO_L7N_T1_34"
						(effects
							(font
								(size 1.27 1.27)
							)
						)
					)
					(number "AF2"
						(effects
							(font
								(size 1.27 1.27)
							)
						)
					)
				)
				(pin bidirectional line
					(at 54.61 -41.91 180)
					(length 5.08)
					(name "IO_L8P_T1_34"
						(effects
							(font
								(size 1.27 1.27)
							)
						)
					)
					(number "AE1"
						(effects
							(font
								(size 1.27 1.27)
							)
						)
					)
				)
				(pin bidirectional line
					(at 54.61 -44.45 180)
					(length 5.08)
					(name "IO_L8N_T1_34"
						(effects
							(font
								(size 1.27 1.27)
							)
						)
					)
					(number "AF1"
						(effects
							(font
								(size 1.27 1.27)
							)
						)
					)
				)
				(pin bidirectional line
					(at 54.61 -46.99 180)
					(length 5.08)
					(name "IO_L9P_T1_DQS_34"
						(effects
							(font
								(size 1.27 1.27)
							)
						)
					)
					(number "AG4"
						(effects
							(font
								(size 1.27 1.27)
							)
						)
					)
				)
				(pin bidirectional line
					(at 54.61 -49.53 180)
					(length 5.08)
					(name "IO_L9N_T1_DQS_34"
						(effects
							(font
								(size 1.27 1.27)
							)
						)
					)
					(number "AG3"
						(effects
							(font
								(size 1.27 1.27)
							)
						)
					)
				)
				(pin bidirectional line
					(at 54.61 -52.07 180)
					(length 5.08)
					(name "IO_L10P_T1_34"
						(effects
							(font
								(size 1.27 1.27)
							)
						)
					)
					(number "AE4"
						(effects
							(font
								(size 1.27 1.27)
							)
						)
					)
				)
				(pin bidirectional line
					(at 54.61 -54.61 180)
					(length 5.08)
					(name "IO_L10N_T1_34"
						(effects
							(font
								(size 1.27 1.27)
							)
						)
					)
					(number "AE3"
						(effects
							(font
								(size 1.27 1.27)
							)
						)
					)
				)
				(pin bidirectional line
					(at 54.61 -57.15 180)
					(length 5.08)
					(name "IO_L11P_T1_SRCC_34"
						(effects
							(font
								(size 1.27 1.27)
							)
						)
					)
					(number "AE5"
						(effects
							(font
								(size 1.27 1.27)
							)
						)
					)
				)
				(pin bidirectional line
					(at 54.61 -59.69 180)
					(length 5.08)
					(name "IO_L11N_T1_SRCC_34"
						(effects
							(font
								(size 1.27 1.27)
							)
						)
					)
					(number "AF5"
						(effects
							(font
								(size 1.27 1.27)
							)
						)
					)
				)
				(pin bidirectional line
					(at 54.61 -62.23 180)
					(length 5.08)
					(name "IO_L12P_T1_MRCC_34"
						(effects
							(font
								(size 1.27 1.27)
							)
						)
					)
					(number "AF6"
						(effects
							(font
								(size 1.27 1.27)
							)
						)
					)
				)
				(pin bidirectional line
					(at 54.61 -64.77 180)
					(length 5.08)
					(name "IO_L12N_T1_MRCC_34"
						(effects
							(font
								(size 1.27 1.27)
							)
						)
					)
					(number "AG5"
						(effects
							(font
								(size 1.27 1.27)
							)
						)
					)
				)
				(pin bidirectional line
					(at 54.61 -67.31 180)
					(length 5.08)
					(name "IO_L13P_T2_MRCC_34"
						(effects
							(font
								(size 1.27 1.27)
							)
						)
					)
					(number "AH4"
						(effects
							(font
								(size 1.27 1.27)
							)
						)
					)
				)
				(pin bidirectional line
					(at 54.61 -69.85 180)
					(length 5.08)
					(name "IO_L13N_T2_MRCC_34"
						(effects
							(font
								(size 1.27 1.27)
							)
						)
					)
					(number "AJ4"
						(effects
							(font
								(size 1.27 1.27)
							)
						)
					)
				)
				(pin bidirectional line
					(at 54.61 -72.39 180)
					(length 5.08)
					(name "IO_L14P_T2_SRCC_34"
						(effects
							(font
								(size 1.27 1.27)
							)
						)
					)
					(number "AH6"
						(effects
							(font
								(size 1.27 1.27)
							)
						)
					)
				)
				(pin bidirectional line
					(at 54.61 -74.93 180)
					(length 5.08)
					(name "IO_L14N_T2_SRCC_34"
						(effects
							(font
								(size 1.27 1.27)
							)
						)
					)
					(number "AH5"
						(effects
							(font
								(size 1.27 1.27)
							)
						)
					)
				)
				(pin bidirectional line
					(at 54.61 -77.47 180)
					(length 5.08)
					(name "IO_L15P_T2_DQS_34"
						(effects
							(font
								(size 1.27 1.27)
							)
						)
					)
					(number "AG2"
						(effects
							(font
								(size 1.27 1.27)
							)
						)
					)
				)
				(pin bidirectional line
					(at 54.61 -80.01 180)
					(length 5.08)
					(name "IO_L15N_T2_DQS_34"
						(effects
							(font
								(size 1.27 1.27)
							)
						)
					)
					(number "AH1"
						(effects
							(font
								(size 1.27 1.27)
							)
						)
					)
				)
				(pin bidirectional line
					(at 54.61 -82.55 180)
					(length 5.08)
					(name "IO_L16P_T2_34"
						(effects
							(font
								(size 1.27 1.27)
							)
						)
					)
					(number "AH2"
						(effects
							(font
								(size 1.27 1.27)
							)
						)
					)
				)
				(pin bidirectional line
					(at 54.61 -85.09 180)
					(length 5.08)
					(name "IO_L16N_T2_34"
						(effects
							(font
								(size 1.27 1.27)
							)
						)
					)
					(number "AJ2"
						(effects
							(font
								(size 1.27 1.27)
							)
						)
					)
				)
				(pin bidirectional line
					(at 54.61 -87.63 180)
					(length 5.08)
					(name "IO_L17P_T2_34"
						(effects
							(font
								(size 1.27 1.27)
							)
						)
					)
					(number "AJ1"
						(effects
							(font
								(size 1.27 1.27)
							)
						)
					)
				)
				(pin bidirectional line
					(at 54.61 -90.17 180)
					(length 5.08)
					(name "IO_L17N_T2_34"
						(effects
							(font
								(size 1.27 1.27)
							)
						)
					)
					(number "AK1"
						(effects
							(font
								(size 1.27 1.27)
							)
						)
					)
				)
				(pin bidirectional line
					(at 54.61 -92.71 180)
					(length 5.08)
					(name "IO_L18P_T2_34"
						(effects
							(font
								(size 1.27 1.27)
							)
						)
					)
					(number "AJ3"
						(effects
							(font
								(size 1.27 1.27)
							)
						)
					)
				)
				(pin bidirectional line
					(at 54.61 -95.25 180)
					(length 5.08)
					(name "IO_L18N_T2_34"
						(effects
							(font
								(size 1.27 1.27)
							)
						)
					)
					(number "AK3"
						(effects
							(font
								(size 1.27 1.27)
							)
						)
					)
				)
				(pin bidirectional line
					(at 54.61 -97.79 180)
					(length 5.08)
					(name "IO_L19P_T3_34"
						(effects
							(font
								(size 1.27 1.27)
							)
						)
					)
					(number "AF8"
						(effects
							(font
								(size 1.27 1.27)
							)
						)
					)
				)
				(pin bidirectional line
					(at 54.61 -100.33 180)
					(length 5.08)
					(name "IO_L19N_T3_VREF_34"
						(effects
							(font
								(size 1.27 1.27)
							)
						)
					)
					(number "AG8"
						(effects
							(font
								(size 1.27 1.27)
							)
						)
					)
				)
				(pin bidirectional line
					(at 54.61 -102.87 180)
					(length 5.08)
					(name "IO_L20P_T3_34"
						(effects
							(font
								(size 1.27 1.27)
							)
						)
					)
					(number "AF7"
						(effects
							(font
								(size 1.27 1.27)
							)
						)
					)
				)
				(pin bidirectional line
					(at 54.61 -105.41 180)
					(length 5.08)
					(name "IO_L20N_T3_34"
						(effects
							(font
								(size 1.27 1.27)
							)
						)
					)
					(number "AG7"
						(effects
							(font
								(size 1.27 1.27)
							)
						)
					)
				)
				(pin bidirectional line
					(at 54.61 -107.95 180)
					(length 5.08)
					(name "IO_L21P_T3_DQS_34"
						(effects
							(font
								(size 1.27 1.27)
							)
						)
					)
					(number "AH7"
						(effects
							(font
								(size 1.27 1.27)
							)
						)
					)
				)
				(pin bidirectional line
					(at 54.61 -110.49 180)
					(length 5.08)
					(name "IO_L21N_T3_DQS_34"
						(effects
							(font
								(size 1.27 1.27)
							)
						)
					)
					(number "AJ7"
						(effects
							(font
								(size 1.27 1.27)
							)
						)
					)
				)
				(pin bidirectional line
					(at 54.61 -113.03 180)
					(length 5.08)
					(name "IO_L22P_T3_34"
						(effects
							(font
								(size 1.27 1.27)
							)
						)
					)
					(number "AJ6"
						(effects
							(font
								(size 1.27 1.27)
							)
						)
					)
				)
				(pin bidirectional line
					(at 54.61 -115.57 180)
					(length 5.08)
					(name "IO_L22N_T3_34"
						(effects
							(font
								(size 1.27 1.27)
							)
						)
					)
					(number "AK6"
						(effects
							(font
								(size 1.27 1.27)
							)
						)
					)
				)
				(pin bidirectional line
					(at 54.61 -118.11 180)
					(length 5.08)
					(name "IO_L23P_T3_34"
						(effects
							(font
								(size 1.27 1.27)
							)
						)
					)
					(number "AJ8"
						(effects
							(font
								(size 1.27 1.27)
							)
						)
					)
				)
				(pin bidirectional line
					(at 54.61 -120.65 180)
					(length 5.08)
					(name "IO_L23N_T3_34"
						(effects
							(font
								(size 1.27 1.27)
							)
						)
					)
					(number "AK8"
						(effects
							(font
								(size 1.27 1.27)
							)
						)
					)
				)
				(pin bidirectional line
					(at 54.61 -123.19 180)
					(length 5.08)
					(name "IO_L24P_T3_34"
						(effects
							(font
								(size 1.27 1.27)
							)
						)
					)
					(number "AK5"
						(effects
							(font
								(size 1.27 1.27)
							)
						)
					)
				)
				(pin bidirectional line
					(at 54.61 -125.73 180)
					(length 5.08)
					(name "IO_L24N_T3_34"
						(effects
							(font
								(size 1.27 1.27)
							)
						)
					)
					(number "AK4"
						(effects
							(font
								(size 1.27 1.27)
							)
						)
					)
				)
				(pin bidirectional line
					(at 54.61 -128.27 180)
					(length 5.08)
					(name "IO_25_VRP_34"
						(effects
							(font
								(size 1.27 1.27)
							)
						)
					)
					(number "AB7"
						(effects
							(font
								(size 1.27 1.27)
							)
						)
					)
				)
			)
			(symbol "XC7K410T-2FFG900I_6_1"
				(rectangle
					(start 5.08 5.08)
					(end 43.18 -53.34)
					(stroke
						(width 0.254)
						(type default)
					)
					(fill
						(type background)
					)
				)
				(text "GTX 115"
					(at 8.89 2.54 0)
					(effects
						(font
							(size 1.27 1.27)
							(thickness 0.15)
						)
						(justify left bottom)
					)
				)
				(text "GTX 116"
					(at 29.21 2.54 0)
					(effects
						(font
							(size 1.27 1.27)
							(thickness 0.15)
						)
						(justify left bottom)
					)
				)
				(pin bidirectional line
					(at 0 0 0)
					(length 5.08)
					(name "MGTXTXP0_115"
						(effects
							(font
								(size 1.27 1.27)
							)
						)
					)
					(number "Y2"
						(effects
							(font
								(size 1.27 1.27)
							)
						)
					)
				)
				(pin bidirectional line
					(at 0 -2.54 0)
					(length 5.08)
					(name "MGTXTXN0_115"
						(effects
							(font
								(size 1.27 1.27)
							)
						)
					)
					(number "Y1"
						(effects
							(font
								(size 1.27 1.27)
							)
						)
					)
				)
				(pin bidirectional line
					(at 0 -5.08 0)
					(length 5.08)
					(name "MGTXTXP1_115"
						(effects
							(font
								(size 1.27 1.27)
							)
						)
					)
					(number "V2"
						(effects
							(font
								(size 1.27 1.27)
							)
						)
					)
				)
				(pin bidirectional line
					(at 0 -7.62 0)
					(length 5.08)
					(name "MGTXTXN1_115"
						(effects
							(font
								(size 1.27 1.27)
							)
						)
					)
					(number "V1"
						(effects
							(font
								(size 1.27 1.27)
							)
						)
					)
				)
				(pin bidirectional line
					(at 0 -10.16 0)
					(length 5.08)
					(name "MGTXTXP2_115"
						(effects
							(font
								(size 1.27 1.27)
							)
						)
					)
					(number "U4"
						(effects
							(font
								(size 1.27 1.27)
							)
						)
					)
				)
				(pin bidirectional line
					(at 0 -12.7 0)
					(length 5.08)
					(name "MGTXTXN2_115"
						(effects
							(font
								(size 1.27 1.27)
							)
						)
					)
					(number "U3"
						(effects
							(font
								(size 1.27 1.27)
							)
						)
					)
				)
				(pin bidirectional line
					(at 0 -15.24 0)
					(length 5.08)
					(name "MGTXTXP3_115"
						(effects
							(font
								(size 1.27 1.27)
							)
						)
					)
					(number "T2"
						(effects
							(font
								(size 1.27 1.27)
							)
						)
					)
				)
				(pin bidirectional line
					(at 0 -17.78 0)
					(length 5.08)
					(name "MGTXTXN3_115"
						(effects
							(font
								(size 1.27 1.27)
							)
						)
					)
					(number "T1"
						(effects
							(font
								(size 1.27 1.27)
							)
						)
					)
				)
				(pin bidirectional line
					(at 0 -21.59 0)
					(length 5.08)
					(name "MGTXRXP0_115"
						(effects
							(font
								(size 1.27 1.27)
							)
						)
					)
					(number "AA4"
						(effects
							(font
								(size 1.27 1.27)
							)
						)
					)
				)
				(pin bidirectional line
					(at 0 -24.13 0)
					(length 5.08)
					(name "MGTXRXN0_115"
						(effects
							(font
								(size 1.27 1.27)
							)
						)
					)
					(number "AA3"
						(effects
							(font
								(size 1.27 1.27)
							)
						)
					)
				)
				(pin bidirectional line
					(at 0 -26.67 0)
					(length 5.08)
					(name "MGTXRXP1_115"
						(effects
							(font
								(size 1.27 1.27)
							)
						)
					)
					(number "Y6"
						(effects
							(font
								(size 1.27 1.27)
							)
						)
					)
				)
				(pin bidirectional line
					(at 0 -29.21 0)
					(length 5.08)
					(name "MGTXRXN1_115"
						(effects
							(font
								(size 1.27 1.27)
							)
						)
					)
					(number "Y5"
						(effects
							(font
								(size 1.27 1.27)
							)
						)
					)
				)
				(pin bidirectional line
					(at 0 -31.75 0)
					(length 5.08)
					(name "MGTXRXP2_115"
						(effects
							(font
								(size 1.27 1.27)
							)
						)
					)
					(number "W4"
						(effects
							(font
								(size 1.27 1.27)
							)
						)
					)
				)
				(pin bidirectional line
					(at 0 -34.29 0)
					(length 5.08)
					(name "MGTXRXN2_115"
						(effects
							(font
								(size 1.27 1.27)
							)
						)
					)
					(number "W3"
						(effects
							(font
								(size 1.27 1.27)
							)
						)
					)
				)
				(pin bidirectional line
					(at 0 -36.83 0)
					(length 5.08)
					(name "MGTXRXP3_115"
						(effects
							(font
								(size 1.27 1.27)
							)
						)
					)
					(number "V6"
						(effects
							(font
								(size 1.27 1.27)
							)
						)
					)
				)
				(pin bidirectional line
					(at 0 -39.37 0)
					(length 5.08)
					(name "MGTXRXN3_115"
						(effects
							(font
								(size 1.27 1.27)
							)
						)
					)
					(number "V5"
						(effects
							(font
								(size 1.27 1.27)
							)
						)
					)
				)
				(pin bidirectional line
					(at 0 -43.18 0)
					(length 5.08)
					(name "MGTREFCLK0P_115"
						(effects
							(font
								(size 1.27 1.27)
							)
						)
					)
					(number "R8"
						(effects
							(font
								(size 1.27 1.27)
							)
						)
					)
				)
				(pin bidirectional line
					(at 0 -45.72 0)
					(length 5.08)
					(name "MGTREFCLK0N_115"
						(effects
							(font
								(size 1.27 1.27)
							)
						)
					)
					(number "R7"
						(effects
							(font
								(size 1.27 1.27)
							)
						)
					)
				)
				(pin bidirectional line
					(at 0 -48.26 0)
					(length 5.08)
					(name "MGTREFCLK1P_115"
						(effects
							(font
								(size 1.27 1.27)
							)
						)
					)
					(number "U8"
						(effects
							(font
								(size 1.27 1.27)
							)
						)
					)
				)
				(pin bidirectional line
					(at 0 -50.8 0)
					(length 5.08)
					(name "MGTREFCLK1N_115"
						(effects
							(font
								(size 1.27 1.27)
							)
						)
					)
					(number "U7"
						(effects
							(font
								(size 1.27 1.27)
							)
						)
					)
				)
				(pin bidirectional line
					(at 48.26 0 180)
					(length 5.08)
					(name "MGTXTXP0_116"
						(effects
							(font
								(size 1.27 1.27)
							)
						)
					)
					(number "P2"
						(effects
							(font
								(size 1.27 1.27)
							)
						)
					)
				)
				(pin bidirectional line
					(at 48.26 -2.54 180)
					(length 5.08)
					(name "MGTXTXN0_116"
						(effects
							(font
								(size 1.27 1.27)
							)
						)
					)
					(number "P1"
						(effects
							(font
								(size 1.27 1.27)
							)
						)
					)
				)
				(pin bidirectional line
					(at 48.26 -5.08 180)
					(length 5.08)
					(name "MGTXTXP1_116"
						(effects
							(font
								(size 1.27 1.27)
							)
						)
					)
					(number "N4"
						(effects
							(font
								(size 1.27 1.27)
							)
						)
					)
				)
				(pin bidirectional line
					(at 48.26 -7.62 180)
					(length 5.08)
					(name "MGTXTXN1_116"
						(effects
							(font
								(size 1.27 1.27)
							)
						)
					)
					(number "N3"
						(effects
							(font
								(size 1.27 1.27)
							)
						)
					)
				)
				(pin bidirectional line
					(at 48.26 -10.16 180)
					(length 5.08)
					(name "MGTXTXP2_116"
						(effects
							(font
								(size 1.27 1.27)
							)
						)
					)
					(number "M2"
						(effects
							(font
								(size 1.27 1.27)
							)
						)
					)
				)
				(pin bidirectional line
					(at 48.26 -12.7 180)
					(length 5.08)
					(name "MGTXTXN2_116"
						(effects
							(font
								(size 1.27 1.27)
							)
						)
					)
					(number "M1"
						(effects
							(font
								(size 1.27 1.27)
							)
						)
					)
				)
				(pin bidirectional line
					(at 48.26 -15.24 180)
					(length 5.08)
					(name "MGTXTXP3_116"
						(effects
							(font
								(size 1.27 1.27)
							)
						)
					)
					(number "L4"
						(effects
							(font
								(size 1.27 1.27)
							)
						)
					)
				)
				(pin bidirectional line
					(at 48.26 -17.78 180)
					(length 5.08)
					(name "MGTXTXN3_116"
						(effects
							(font
								(size 1.27 1.27)
							)
						)
					)
					(number "L3"
						(effects
							(font
								(size 1.27 1.27)
							)
						)
					)
				)
				(pin bidirectional line
					(at 48.26 -21.59 180)
					(length 5.08)
					(name "MGTXRXP0_116"
						(effects
							(font
								(size 1.27 1.27)
							)
						)
					)
					(number "T6"
						(effects
							(font
								(size 1.27 1.27)
							)
						)
					)
				)
				(pin bidirectional line
					(at 48.26 -24.13 180)
					(length 5.08)
					(name "MGTXRXN0_116"
						(effects
							(font
								(size 1.27 1.27)
							)
						)
					)
					(number "T5"
						(effects
							(font
								(size 1.27 1.27)
							)
						)
					)
				)
				(pin bidirectional line
					(at 48.26 -26.67 180)
					(length 5.08)
					(name "MGTXRXP1_116"
						(effects
							(font
								(size 1.27 1.27)
							)
						)
					)
					(number "R4"
						(effects
							(font
								(size 1.27 1.27)
							)
						)
					)
				)
				(pin bidirectional line
					(at 48.26 -29.21 180)
					(length 5.08)
					(name "MGTXRXN1_116"
						(effects
							(font
								(size 1.27 1.27)
							)
						)
					)
					(number "R3"
						(effects
							(font
								(size 1.27 1.27)
							)
						)
					)
				)
				(pin bidirectional line
					(at 48.26 -31.75 180)
					(length 5.08)
					(name "MGTXRXP2_116"
						(effects
							(font
								(size 1.27 1.27)
							)
						)
					)
					(number "P6"
						(effects
							(font
								(size 1.27 1.27)
							)
						)
					)
				)
				(pin bidirectional line
					(at 48.26 -34.29 180)
					(length 5.08)
					(name "MGTXRXN2_116"
						(effects
							(font
								(size 1.27 1.27)
							)
						)
					)
					(number "P5"
						(effects
							(font
								(size 1.27 1.27)
							)
						)
					)
				)
				(pin bidirectional line
					(at 48.26 -36.83 180)
					(length 5.08)
					(name "MGTXRXP3_116"
						(effects
							(font
								(size 1.27 1.27)
							)
						)
					)
					(number "M6"
						(effects
							(font
								(size 1.27 1.27)
							)
						)
					)
				)
				(pin bidirectional line
					(at 48.26 -39.37 180)
					(length 5.08)
					(name "MGTXRXN3_116"
						(effects
							(font
								(size 1.27 1.27)
							)
						)
					)
					(number "M5"
						(effects
							(font
								(size 1.27 1.27)
							)
						)
					)
				)
				(pin bidirectional line
					(at 48.26 -43.18 180)
					(length 5.08)
					(name "MGTREFCLK0P_116"
						(effects
							(font
								(size 1.27 1.27)
							)
						)
					)
					(number "L8"
						(effects
							(font
								(size 1.27 1.27)
							)
						)
					)
				)
				(pin bidirectional line
					(at 48.26 -45.72 180)
					(length 5.08)
					(name "MGTREFCLK0N_116"
						(effects
							(font
								(size 1.27 1.27)
							)
						)
					)
					(number "L7"
						(effects
							(font
								(size 1.27 1.27)
							)
						)
					)
				)
				(pin bidirectional line
					(at 48.26 -48.26 180)
					(length 5.08)
					(name "MGTREFCLK1P_116"
						(effects
							(font
								(size 1.27 1.27)
							)
						)
					)
					(number "N8"
						(effects
							(font
								(size 1.27 1.27)
							)
						)
					)
				)
				(pin bidirectional line
					(at 48.26 -50.8 180)
					(length 5.08)
					(name "MGTREFCLK1N_116"
						(effects
							(font
								(size 1.27 1.27)
							)
						)
					)
					(number "N7"
						(effects
							(font
								(size 1.27 1.27)
							)
						)
					)
				)
			)
			(symbol "XC7K410T-2FFG900I_7_1"
				(rectangle
					(start 5.08 5.08)
					(end 43.18 -53.34)
					(stroke
						(width 0.254)
						(type default)
					)
					(fill
						(type background)
					)
				)
				(text "GTX 117"
					(at 8.89 2.54 0)
					(effects
						(font
							(size 1.27 1.27)
							(thickness 0.15)
						)
						(justify left bottom)
					)
				)
				(text "GTX 118"
					(at 29.21 2.54 0)
					(effects
						(font
							(size 1.27 1.27)
							(thickness 0.15)
						)
						(justify left bottom)
					)
				)
				(pin bidirectional line
					(at 0 0 0)
					(length 5.08)
					(name "MGTXTXP0_117"
						(effects
							(font
								(size 1.27 1.27)
							)
						)
					)
					(number "K2"
						(effects
							(font
								(size 1.27 1.27)
							)
						)
					)
				)
				(pin bidirectional line
					(at 0 -2.54 0)
					(length 5.08)
					(name "MGTXTXN0_117"
						(effects
							(font
								(size 1.27 1.27)
							)
						)
					)
					(number "K1"
						(effects
							(font
								(size 1.27 1.27)
							)
						)
					)
				)
				(pin bidirectional line
					(at 0 -5.08 0)
					(length 5.08)
					(name "MGTXTXP1_117"
						(effects
							(font
								(size 1.27 1.27)
							)
						)
					)
					(number "J4"
						(effects
							(font
								(size 1.27 1.27)
							)
						)
					)
				)
				(pin bidirectional line
					(at 0 -7.62 0)
					(length 5.08)
					(name "MGTXTXN1_117"
						(effects
							(font
								(size 1.27 1.27)
							)
						)
					)
					(number "J3"
						(effects
							(font
								(size 1.27 1.27)
							)
						)
					)
				)
				(pin bidirectional line
					(at 0 -10.16 0)
					(length 5.08)
					(name "MGTXTXP2_117"
						(effects
							(font
								(size 1.27 1.27)
							)
						)
					)
					(number "H2"
						(effects
							(font
								(size 1.27 1.27)
							)
						)
					)
				)
				(pin bidirectional line
					(at 0 -12.7 0)
					(length 5.08)
					(name "MGTXTXN2_117"
						(effects
							(font
								(size 1.27 1.27)
							)
						)
					)
					(number "H1"
						(effects
							(font
								(size 1.27 1.27)
							)
						)
					)
				)
				(pin bidirectional line
					(at 0 -15.24 0)
					(length 5.08)
					(name "MGTXTXP3_117"
						(effects
							(font
								(size 1.27 1.27)
							)
						)
					)
					(number "F2"
						(effects
							(font
								(size 1.27 1.27)
							)
						)
					)
				)
				(pin bidirectional line
					(at 0 -17.78 0)
					(length 5.08)
					(name "MGTXTXN3_117"
						(effects
							(font
								(size 1.27 1.27)
							)
						)
					)
					(number "F1"
						(effects
							(font
								(size 1.27 1.27)
							)
						)
					)
				)
				(pin bidirectional line
					(at 0 -21.59 0)
					(length 5.08)
					(name "MGTXRXP0_117"
						(effects
							(font
								(size 1.27 1.27)
							)
						)
					)
					(number "K6"
						(effects
							(font
								(size 1.27 1.27)
							)
						)
					)
				)
				(pin bidirectional line
					(at 0 -24.13 0)
					(length 5.08)
					(name "MGTXRXN0_117"
						(effects
							(font
								(size 1.27 1.27)
							)
						)
					)
					(number "K5"
						(effects
							(font
								(size 1.27 1.27)
							)
						)
					)
				)
				(pin bidirectional line
					(at 0 -26.67 0)
					(length 5.08)
					(name "MGTXRXP1_117"
						(effects
							(font
								(size 1.27 1.27)
							)
						)
					)
					(number "H6"
						(effects
							(font
								(size 1.27 1.27)
							)
						)
					)
				)
				(pin bidirectional line
					(at 0 -29.21 0)
					(length 5.08)
					(name "MGTXRXN1_117"
						(effects
							(font
								(size 1.27 1.27)
							)
						)
					)
					(number "H5"
						(effects
							(font
								(size 1.27 1.27)
							)
						)
					)
				)
				(pin bidirectional line
					(at 0 -31.75 0)
					(length 5.08)
					(name "MGTXRXP2_117"
						(effects
							(font
								(size 1.27 1.27)
							)
						)
					)
					(number "G4"
						(effects
							(font
								(size 1.27 1.27)
							)
						)
					)
				)
				(pin bidirectional line
					(at 0 -34.29 0)
					(length 5.08)
					(name "MGTXRXN2_117"
						(effects
							(font
								(size 1.27 1.27)
							)
						)
					)
					(number "G3"
						(effects
							(font
								(size 1.27 1.27)
							)
						)
					)
				)
				(pin bidirectional line
					(at 0 -36.83 0)
					(length 5.08)
					(name "MGTXRXP3_117"
						(effects
							(font
								(size 1.27 1.27)
							)
						)
					)
					(number "F6"
						(effects
							(font
								(size 1.27 1.27)
							)
						)
					)
				)
				(pin bidirectional line
					(at 0 -39.37 0)
					(length 5.08)
					(name "MGTXRXN3_117"
						(effects
							(font
								(size 1.27 1.27)
							)
						)
					)
					(number "F5"
						(effects
							(font
								(size 1.27 1.27)
							)
						)
					)
				)
				(pin bidirectional line
					(at 0 -43.18 0)
					(length 5.08)
					(name "MGTREFCLK0P_117"
						(effects
							(font
								(size 1.27 1.27)
							)
						)
					)
					(number "G8"
						(effects
							(font
								(size 1.27 1.27)
							)
						)
					)
				)
				(pin bidirectional line
					(at 0 -45.72 0)
					(length 5.08)
					(name "MGTREFCLK0N_117"
						(effects
							(font
								(size 1.27 1.27)
							)
						)
					)
					(number "G7"
						(effects
							(font
								(size 1.27 1.27)
							)
						)
					)
				)
				(pin bidirectional line
					(at 0 -48.26 0)
					(length 5.08)
					(name "MGTREFCLK1P_117"
						(effects
							(font
								(size 1.27 1.27)
							)
						)
					)
					(number "J8"
						(effects
							(font
								(size 1.27 1.27)
							)
						)
					)
				)
				(pin bidirectional line
					(at 0 -50.8 0)
					(length 5.08)
					(name "MGTREFCLK1N_117"
						(effects
							(font
								(size 1.27 1.27)
							)
						)
					)
					(number "J7"
						(effects
							(font
								(size 1.27 1.27)
							)
						)
					)
				)
				(pin bidirectional line
					(at 48.26 0 180)
					(length 5.08)
					(name "MGTXTXP0_118"
						(effects
							(font
								(size 1.27 1.27)
							)
						)
					)
					(number "D2"
						(effects
							(font
								(size 1.27 1.27)
							)
						)
					)
				)
				(pin bidirectional line
					(at 48.26 -2.54 180)
					(length 5.08)
					(name "MGTXTXN0_118"
						(effects
							(font
								(size 1.27 1.27)
							)
						)
					)
					(number "D1"
						(effects
							(font
								(size 1.27 1.27)
							)
						)
					)
				)
				(pin bidirectional line
					(at 48.26 -5.08 180)
					(length 5.08)
					(name "MGTXTXP1_118"
						(effects
							(font
								(size 1.27 1.27)
							)
						)
					)
					(number "C4"
						(effects
							(font
								(size 1.27 1.27)
							)
						)
					)
				)
				(pin bidirectional line
					(at 48.26 -7.62 180)
					(length 5.08)
					(name "MGTXTXN1_118"
						(effects
							(font
								(size 1.27 1.27)
							)
						)
					)
					(number "C3"
						(effects
							(font
								(size 1.27 1.27)
							)
						)
					)
				)
				(pin bidirectional line
					(at 48.26 -10.16 180)
					(length 5.08)
					(name "MGTXTXP2_118"
						(effects
							(font
								(size 1.27 1.27)
							)
						)
					)
					(number "B2"
						(effects
							(font
								(size 1.27 1.27)
							)
						)
					)
				)
				(pin bidirectional line
					(at 48.26 -12.7 180)
					(length 5.08)
					(name "MGTXTXN2_118"
						(effects
							(font
								(size 1.27 1.27)
							)
						)
					)
					(number "B1"
						(effects
							(font
								(size 1.27 1.27)
							)
						)
					)
				)
				(pin bidirectional line
					(at 48.26 -15.24 180)
					(length 5.08)
					(name "MGTXTXP3_118"
						(effects
							(font
								(size 1.27 1.27)
							)
						)
					)
					(number "A4"
						(effects
							(font
								(size 1.27 1.27)
							)
						)
					)
				)
				(pin bidirectional line
					(at 48.26 -17.78 180)
					(length 5.08)
					(name "MGTXTXN3_118"
						(effects
							(font
								(size 1.27 1.27)
							)
						)
					)
					(number "A3"
						(effects
							(font
								(size 1.27 1.27)
							)
						)
					)
				)
				(pin bidirectional line
					(at 48.26 -21.59 180)
					(length 5.08)
					(name "MGTXRXP0_118"
						(effects
							(font
								(size 1.27 1.27)
							)
						)
					)
					(number "E4"
						(effects
							(font
								(size 1.27 1.27)
							)
						)
					)
				)
				(pin bidirectional line
					(at 48.26 -24.13 180)
					(length 5.08)
					(name "MGTXRXN0_118"
						(effects
							(font
								(size 1.27 1.27)
							)
						)
					)
					(number "E3"
						(effects
							(font
								(size 1.27 1.27)
							)
						)
					)
				)
				(pin bidirectional line
					(at 48.26 -26.67 180)
					(length 5.08)
					(name "MGTXRXP1_118"
						(effects
							(font
								(size 1.27 1.27)
							)
						)
					)
					(number "D6"
						(effects
							(font
								(size 1.27 1.27)
							)
						)
					)
				)
				(pin bidirectional line
					(at 48.26 -29.21 180)
					(length 5.08)
					(name "MGTXRXN1_118"
						(effects
							(font
								(size 1.27 1.27)
							)
						)
					)
					(number "D5"
						(effects
							(font
								(size 1.27 1.27)
							)
						)
					)
				)
				(pin bidirectional line
					(at 48.26 -31.75 180)
					(length 5.08)
					(name "MGTXRXP2_118"
						(effects
							(font
								(size 1.27 1.27)
							)
						)
					)
					(number "B6"
						(effects
							(font
								(size 1.27 1.27)
							)
						)
					)
				)
				(pin bidirectional line
					(at 48.26 -34.29 180)
					(length 5.08)
					(name "MGTXRXN2_118"
						(effects
							(font
								(size 1.27 1.27)
							)
						)
					)
					(number "B5"
						(effects
							(font
								(size 1.27 1.27)
							)
						)
					)
				)
				(pin bidirectional line
					(at 48.26 -36.83 180)
					(length 5.08)
					(name "MGTXRXP3_118"
						(effects
							(font
								(size 1.27 1.27)
							)
						)
					)
					(number "A8"
						(effects
							(font
								(size 1.27 1.27)
							)
						)
					)
				)
				(pin bidirectional line
					(at 48.26 -39.37 180)
					(length 5.08)
					(name "MGTXRXN3_118"
						(effects
							(font
								(size 1.27 1.27)
							)
						)
					)
					(number "A7"
						(effects
							(font
								(size 1.27 1.27)
							)
						)
					)
				)
				(pin bidirectional line
					(at 48.26 -43.18 180)
					(length 5.08)
					(name "MGTREFCLK0P_118"
						(effects
							(font
								(size 1.27 1.27)
							)
						)
					)
					(number "C8"
						(effects
							(font
								(size 1.27 1.27)
							)
						)
					)
				)
				(pin bidirectional line
					(at 48.26 -45.72 180)
					(length 5.08)
					(name "MGTREFCLK0N_118"
						(effects
							(font
								(size 1.27 1.27)
							)
						)
					)
					(number "C7"
						(effects
							(font
								(size 1.27 1.27)
							)
						)
					)
				)
				(pin bidirectional line
					(at 48.26 -48.26 180)
					(length 5.08)
					(name "MGTREFCLK1P_118"
						(effects
							(font
								(size 1.27 1.27)
							)
						)
					)
					(number "E8"
						(effects
							(font
								(size 1.27 1.27)
							)
						)
					)
				)
				(pin bidirectional line
					(at 48.26 -50.8 180)
					(length 5.08)
					(name "MGTREFCLK1N_118"
						(effects
							(font
								(size 1.27 1.27)
							)
						)
					)
					(number "E7"
						(effects
							(font
								(size 1.27 1.27)
							)
						)
					)
				)
			)
			(symbol "XC7K410T-2FFG900I_8_1"
				(rectangle
					(start 5.08 2.54)
					(end 24.13 -13.97)
					(stroke
						(width 0.254)
						(type default)
					)
					(fill
						(type background)
					)
				)
				(pin bidirectional line
					(at 0 0 0)
					(length 5.08)
					(name "MGTAVCC"
						(effects
							(font
								(size 1.27 1.27)
							)
						)
					)
					(number "B7"
						(effects
							(font
								(size 1.27 1.27)
							)
						)
					)
				)
				(pin passive line
					(at 0 0 0)
					(length 5.08)
					(hide yes)
					(name "MGTAVCC"
						(effects
							(font
								(size 1.27 1.27)
							)
						)
					)
					(number "D7"
						(effects
							(font
								(size 1.27 1.27)
							)
						)
					)
				)
				(pin passive line
					(at 0 0 0)
					(length 5.08)
					(hide yes)
					(name "MGTAVCC"
						(effects
							(font
								(size 1.27 1.27)
							)
						)
					)
					(number "F7"
						(effects
							(font
								(size 1.27 1.27)
							)
						)
					)
				)
				(pin passive line
					(at 0 0 0)
					(length 5.08)
					(hide yes)
					(name "MGTAVCC"
						(effects
							(font
								(size 1.27 1.27)
							)
						)
					)
					(number "H7"
						(effects
							(font
								(size 1.27 1.27)
							)
						)
					)
				)
				(pin passive line
					(at 0 0 0)
					(length 5.08)
					(hide yes)
					(name "MGTAVCC"
						(effects
							(font
								(size 1.27 1.27)
							)
						)
					)
					(number "K7"
						(effects
							(font
								(size 1.27 1.27)
							)
						)
					)
				)
				(pin passive line
					(at 0 0 0)
					(length 5.08)
					(hide yes)
					(name "MGTAVCC"
						(effects
							(font
								(size 1.27 1.27)
							)
						)
					)
					(number "M7"
						(effects
							(font
								(size 1.27 1.27)
							)
						)
					)
				)
				(pin passive line
					(at 0 0 0)
					(length 5.08)
					(hide yes)
					(name "MGTAVCC"
						(effects
							(font
								(size 1.27 1.27)
							)
						)
					)
					(number "P7"
						(effects
							(font
								(size 1.27 1.27)
							)
						)
					)
				)
				(pin bidirectional line
					(at 0 -2.54 0)
					(length 5.08)
					(name "MGTVCCAUX"
						(effects
							(font
								(size 1.27 1.27)
							)
						)
					)
					(number "T7"
						(effects
							(font
								(size 1.27 1.27)
							)
						)
					)
				)
				(pin passive line
					(at 0 -2.54 0)
					(length 5.08)
					(hide yes)
					(name "MGTVCCAUX"
						(effects
							(font
								(size 1.27 1.27)
							)
						)
					)
					(number "V7"
						(effects
							(font
								(size 1.27 1.27)
							)
						)
					)
				)
				(pin bidirectional line
					(at 0 -6.35 0)
					(length 5.08)
					(name "MGTAVTTRCAL_115"
						(effects
							(font
								(size 1.27 1.27)
							)
						)
					)
					(number "W7"
						(effects
							(font
								(size 1.27 1.27)
							)
						)
					)
				)
				(pin bidirectional line
					(at 0 -8.89 0)
					(length 5.08)
					(name "MGTAVTT"
						(effects
							(font
								(size 1.27 1.27)
							)
						)
					)
					(number "B3"
						(effects
							(font
								(size 1.27 1.27)
							)
						)
					)
				)
				(pin passive line
					(at 0 -8.89 0)
					(length 5.08)
					(hide yes)
					(name "MGTAVTT"
						(effects
							(font
								(size 1.27 1.27)
							)
						)
					)
					(number "C5"
						(effects
							(font
								(size 1.27 1.27)
							)
						)
					)
				)
				(pin passive line
					(at 0 -8.89 0)
					(length 5.08)
					(hide yes)
					(name "MGTAVTT"
						(effects
							(font
								(size 1.27 1.27)
							)
						)
					)
					(number "D3"
						(effects
							(font
								(size 1.27 1.27)
							)
						)
					)
				)
				(pin passive line
					(at 0 -8.89 0)
					(length 5.08)
					(hide yes)
					(name "MGTAVTT"
						(effects
							(font
								(size 1.27 1.27)
							)
						)
					)
					(number "E5"
						(effects
							(font
								(size 1.27 1.27)
							)
						)
					)
				)
				(pin passive line
					(at 0 -8.89 0)
					(length 5.08)
					(hide yes)
					(name "MGTAVTT"
						(effects
							(font
								(size 1.27 1.27)
							)
						)
					)
					(number "F3"
						(effects
							(font
								(size 1.27 1.27)
							)
						)
					)
				)
				(pin passive line
					(at 0 -8.89 0)
					(length 5.08)
					(hide yes)
					(name "MGTAVTT"
						(effects
							(font
								(size 1.27 1.27)
							)
						)
					)
					(number "G5"
						(effects
							(font
								(size 1.27 1.27)
							)
						)
					)
				)
				(pin passive line
					(at 0 -8.89 0)
					(length 5.08)
					(hide yes)
					(name "MGTAVTT"
						(effects
							(font
								(size 1.27 1.27)
							)
						)
					)
					(number "H3"
						(effects
							(font
								(size 1.27 1.27)
							)
						)
					)
				)
				(pin passive line
					(at 0 -8.89 0)
					(length 5.08)
					(hide yes)
					(name "MGTAVTT"
						(effects
							(font
								(size 1.27 1.27)
							)
						)
					)
					(number "J5"
						(effects
							(font
								(size 1.27 1.27)
							)
						)
					)
				)
				(pin passive line
					(at 0 -8.89 0)
					(length 5.08)
					(hide yes)
					(name "MGTAVTT"
						(effects
							(font
								(size 1.27 1.27)
							)
						)
					)
					(number "K3"
						(effects
							(font
								(size 1.27 1.27)
							)
						)
					)
				)
				(pin passive line
					(at 0 -8.89 0)
					(length 5.08)
					(hide yes)
					(name "MGTAVTT"
						(effects
							(font
								(size 1.27 1.27)
							)
						)
					)
					(number "L5"
						(effects
							(font
								(size 1.27 1.27)
							)
						)
					)
				)
				(pin passive line
					(at 0 -8.89 0)
					(length 5.08)
					(hide yes)
					(name "MGTAVTT"
						(effects
							(font
								(size 1.27 1.27)
							)
						)
					)
					(number "M3"
						(effects
							(font
								(size 1.27 1.27)
							)
						)
					)
				)
				(pin passive line
					(at 0 -8.89 0)
					(length 5.08)
					(hide yes)
					(name "MGTAVTT"
						(effects
							(font
								(size 1.27 1.27)
							)
						)
					)
					(number "N5"
						(effects
							(font
								(size 1.27 1.27)
							)
						)
					)
				)
				(pin passive line
					(at 0 -8.89 0)
					(length 5.08)
					(hide yes)
					(name "MGTAVTT"
						(effects
							(font
								(size 1.27 1.27)
							)
						)
					)
					(number "P3"
						(effects
							(font
								(size 1.27 1.27)
							)
						)
					)
				)
				(pin passive line
					(at 0 -8.89 0)
					(length 5.08)
					(hide yes)
					(name "MGTAVTT"
						(effects
							(font
								(size 1.27 1.27)
							)
						)
					)
					(number "R5"
						(effects
							(font
								(size 1.27 1.27)
							)
						)
					)
				)
				(pin passive line
					(at 0 -8.89 0)
					(length 5.08)
					(hide yes)
					(name "MGTAVTT"
						(effects
							(font
								(size 1.27 1.27)
							)
						)
					)
					(number "T3"
						(effects
							(font
								(size 1.27 1.27)
							)
						)
					)
				)
				(pin passive line
					(at 0 -8.89 0)
					(length 5.08)
					(hide yes)
					(name "MGTAVTT"
						(effects
							(font
								(size 1.27 1.27)
							)
						)
					)
					(number "U5"
						(effects
							(font
								(size 1.27 1.27)
							)
						)
					)
				)
				(pin passive line
					(at 0 -8.89 0)
					(length 5.08)
					(hide yes)
					(name "MGTAVTT"
						(effects
							(font
								(size 1.27 1.27)
							)
						)
					)
					(number "V3"
						(effects
							(font
								(size 1.27 1.27)
							)
						)
					)
				)
				(pin passive line
					(at 0 -8.89 0)
					(length 5.08)
					(hide yes)
					(name "MGTAVTT"
						(effects
							(font
								(size 1.27 1.27)
							)
						)
					)
					(number "W5"
						(effects
							(font
								(size 1.27 1.27)
							)
						)
					)
				)
				(pin bidirectional line
					(at 0 -11.43 0)
					(length 5.08)
					(name "MGTRREF_115"
						(effects
							(font
								(size 1.27 1.27)
							)
						)
					)
					(number "W8"
						(effects
							(font
								(size 1.27 1.27)
							)
						)
					)
				)
			)
			(symbol "XC7K410T-2FFG900I_9_1"
				(rectangle
					(start 5.08 2.54)
					(end 27.94 -29.21)
					(stroke
						(width 0.254)
						(type default)
					)
					(fill
						(type background)
					)
				)
				(pin bidirectional line
					(at 0 0 0)
					(length 5.08)
					(name "VCCO_0"
						(effects
							(font
								(size 1.27 1.27)
							)
						)
					)
					(number "AB6"
						(effects
							(font
								(size 1.27 1.27)
							)
						)
					)
				)
				(pin passive line
					(at 0 0 0)
					(length 5.08)
					(hide yes)
					(name "VCCO_0"
						(effects
							(font
								(size 1.27 1.27)
							)
						)
					)
					(number "T9"
						(effects
							(font
								(size 1.27 1.27)
							)
						)
					)
				)
				(pin bidirectional line
					(at 0 -3.81 0)
					(length 5.08)
					(name "CCLK_0"
						(effects
							(font
								(size 1.27 1.27)
							)
						)
					)
					(number "B10"
						(effects
							(font
								(size 1.27 1.27)
							)
						)
					)
				)
				(pin bidirectional line
					(at 0 -6.35 0)
					(length 5.08)
					(name "M0_0"
						(effects
							(font
								(size 1.27 1.27)
							)
						)
					)
					(number "AB5"
						(effects
							(font
								(size 1.27 1.27)
							)
						)
					)
				)
				(pin bidirectional line
					(at 0 -8.89 0)
					(length 5.08)
					(name "M1_0"
						(effects
							(font
								(size 1.27 1.27)
							)
						)
					)
					(number "AB2"
						(effects
							(font
								(size 1.27 1.27)
							)
						)
					)
				)
				(pin bidirectional line
					(at 0 -11.43 0)
					(length 5.08)
					(name "M2_0"
						(effects
							(font
								(size 1.27 1.27)
							)
						)
					)
					(number "AB1"
						(effects
							(font
								(size 1.27 1.27)
							)
						)
					)
				)
				(pin bidirectional line
					(at 0 -15.24 0)
					(length 5.08)
					(name "TDI_0"
						(effects
							(font
								(size 1.27 1.27)
							)
						)
					)
					(number "H10"
						(effects
							(font
								(size 1.27 1.27)
							)
						)
					)
				)
				(pin bidirectional line
					(at 0 -17.78 0)
					(length 5.08)
					(name "TDO_0"
						(effects
							(font
								(size 1.27 1.27)
							)
						)
					)
					(number "G10"
						(effects
							(font
								(size 1.27 1.27)
							)
						)
					)
				)
				(pin bidirectional line
					(at 0 -20.32 0)
					(length 5.08)
					(name "TMS_0"
						(effects
							(font
								(size 1.27 1.27)
							)
						)
					)
					(number "F10"
						(effects
							(font
								(size 1.27 1.27)
							)
						)
					)
				)
				(pin bidirectional line
					(at 0 -22.86 0)
					(length 5.08)
					(name "TCK_0"
						(effects
							(font
								(size 1.27 1.27)
							)
						)
					)
					(number "E10"
						(effects
							(font
								(size 1.27 1.27)
							)
						)
					)
				)
				(pin bidirectional line
					(at 0 -26.67 0)
					(length 5.08)
					(name "CFGBVS_0"
						(effects
							(font
								(size 1.27 1.27)
							)
						)
					)
					(number "L10"
						(effects
							(font
								(size 1.27 1.27)
							)
						)
					)
				)
				(pin bidirectional line
					(at 33.02 0 180)
					(length 5.08)
					(name "DONE_0"
						(effects
							(font
								(size 1.27 1.27)
							)
						)
					)
					(number "M10"
						(effects
							(font
								(size 1.27 1.27)
							)
						)
					)
				)
				(pin bidirectional line
					(at 33.02 -2.54 180)
					(length 5.08)
					(name "INIT_B_0"
						(effects
							(font
								(size 1.27 1.27)
							)
						)
					)
					(number "A10"
						(effects
							(font
								(size 1.27 1.27)
							)
						)
					)
				)
				(pin bidirectional line
					(at 33.02 -5.08 180)
					(length 5.08)
					(name "PROGRAM_B_0"
						(effects
							(font
								(size 1.27 1.27)
							)
						)
					)
					(number "K10"
						(effects
							(font
								(size 1.27 1.27)
							)
						)
					)
				)
				(pin bidirectional line
					(at 33.02 -8.89 180)
					(length 5.08)
					(name "VP_0"
						(effects
							(font
								(size 1.27 1.27)
							)
						)
					)
					(number "R15"
						(effects
							(font
								(size 1.27 1.27)
							)
						)
					)
				)
				(pin bidirectional line
					(at 33.02 -11.43 180)
					(length 5.08)
					(name "VN_0"
						(effects
							(font
								(size 1.27 1.27)
							)
						)
					)
					(number "T14"
						(effects
							(font
								(size 1.27 1.27)
							)
						)
					)
				)
				(pin bidirectional line
					(at 33.02 -15.24 180)
					(length 5.08)
					(name "VREFP_0"
						(effects
							(font
								(size 1.27 1.27)
							)
						)
					)
					(number "T15"
						(effects
							(font
								(size 1.27 1.27)
							)
						)
					)
				)
				(pin bidirectional line
					(at 33.02 -17.78 180)
					(length 5.08)
					(name "VREFN_0"
						(effects
							(font
								(size 1.27 1.27)
							)
						)
					)
					(number "R14"
						(effects
							(font
								(size 1.27 1.27)
							)
						)
					)
				)
				(pin bidirectional line
					(at 33.02 -21.59 180)
					(length 5.08)
					(name "DXP_0"
						(effects
							(font
								(size 1.27 1.27)
							)
						)
					)
					(number "U15"
						(effects
							(font
								(size 1.27 1.27)
							)
						)
					)
				)
				(pin bidirectional line
					(at 33.02 -24.13 180)
					(length 5.08)
					(name "DXN_0"
						(effects
							(font
								(size 1.27 1.27)
							)
						)
					)
					(number "U14"
						(effects
							(font
								(size 1.27 1.27)
							)
						)
					)
				)
			)
			(symbol "XC7K410T-2FFG900I_10_1"
				(rectangle
					(start 5.08 2.54)
					(end 20.32 -21.59)
					(stroke
						(width 0.254)
						(type default)
					)
					(fill
						(type background)
					)
				)
				(pin bidirectional line
					(at 0 0 0)
					(length 5.08)
					(name "VCCAUX"
						(effects
							(font
								(size 1.27 1.27)
							)
						)
					)
					(number "P13"
						(effects
							(font
								(size 1.27 1.27)
							)
						)
					)
				)
				(pin passive line
					(at 0 0 0)
					(length 5.08)
					(hide yes)
					(name "VCCAUX"
						(effects
							(font
								(size 1.27 1.27)
							)
						)
					)
					(number "T13"
						(effects
							(font
								(size 1.27 1.27)
							)
						)
					)
				)
				(pin passive line
					(at 0 0 0)
					(length 5.08)
					(hide yes)
					(name "VCCAUX"
						(effects
							(font
								(size 1.27 1.27)
							)
						)
					)
					(number "V13"
						(effects
							(font
								(size 1.27 1.27)
							)
						)
					)
				)
				(pin passive line
					(at 0 0 0)
					(length 5.08)
					(hide yes)
					(name "VCCAUX"
						(effects
							(font
								(size 1.27 1.27)
							)
						)
					)
					(number "V15"
						(effects
							(font
								(size 1.27 1.27)
							)
						)
					)
				)
				(pin passive line
					(at 0 0 0)
					(length 5.08)
					(hide yes)
					(name "VCCAUX"
						(effects
							(font
								(size 1.27 1.27)
							)
						)
					)
					(number "W14"
						(effects
							(font
								(size 1.27 1.27)
							)
						)
					)
				)
				(pin bidirectional line
					(at 0 -2.54 0)
					(length 5.08)
					(name "VCCAUX_IO_G0"
						(effects
							(font
								(size 1.27 1.27)
							)
						)
					)
					(number "V11"
						(effects
							(font
								(size 1.27 1.27)
							)
						)
					)
				)
				(pin passive line
					(at 0 -2.54 0)
					(length 5.08)
					(hide yes)
					(name "VCCAUX_IO_G0"
						(effects
							(font
								(size 1.27 1.27)
							)
						)
					)
					(number "W10"
						(effects
							(font
								(size 1.27 1.27)
							)
						)
					)
				)
				(pin passive line
					(at 0 -2.54 0)
					(length 5.08)
					(hide yes)
					(name "VCCAUX_IO_G0"
						(effects
							(font
								(size 1.27 1.27)
							)
						)
					)
					(number "W12"
						(effects
							(font
								(size 1.27 1.27)
							)
						)
					)
				)
				(pin bidirectional line
					(at 0 -5.08 0)
					(length 5.08)
					(name "VCCADC_0"
						(effects
							(font
								(size 1.27 1.27)
							)
						)
					)
					(number "P15"
						(effects
							(font
								(size 1.27 1.27)
							)
						)
					)
				)
				(pin bidirectional line
					(at 0 -7.62 0)
					(length 5.08)
					(name "VCCBRAM"
						(effects
							(font
								(size 1.27 1.27)
							)
						)
					)
					(number "N16"
						(effects
							(font
								(size 1.27 1.27)
							)
						)
					)
				)
				(pin passive line
					(at 0 -7.62 0)
					(length 5.08)
					(hide yes)
					(name "VCCBRAM"
						(effects
							(font
								(size 1.27 1.27)
							)
						)
					)
					(number "R16"
						(effects
							(font
								(size 1.27 1.27)
							)
						)
					)
				)
				(pin passive line
					(at 0 -7.62 0)
					(length 5.08)
					(hide yes)
					(name "VCCBRAM"
						(effects
							(font
								(size 1.27 1.27)
							)
						)
					)
					(number "U16"
						(effects
							(font
								(size 1.27 1.27)
							)
						)
					)
				)
				(pin passive line
					(at 0 -7.62 0)
					(length 5.08)
					(hide yes)
					(name "VCCBRAM"
						(effects
							(font
								(size 1.27 1.27)
							)
						)
					)
					(number "W16"
						(effects
							(font
								(size 1.27 1.27)
							)
						)
					)
				)
				(pin bidirectional line
					(at 0 -10.16 0)
					(length 5.08)
					(name "VCCINT"
						(effects
							(font
								(size 1.27 1.27)
							)
						)
					)
					(number "M11"
						(effects
							(font
								(size 1.27 1.27)
							)
						)
					)
				)
				(pin passive line
					(at 0 -10.16 0)
					(length 5.08)
					(hide yes)
					(name "VCCINT"
						(effects
							(font
								(size 1.27 1.27)
							)
						)
					)
					(number "M13"
						(effects
							(font
								(size 1.27 1.27)
							)
						)
					)
				)
				(pin passive line
					(at 0 -10.16 0)
					(length 5.08)
					(hide yes)
					(name "VCCINT"
						(effects
							(font
								(size 1.27 1.27)
							)
						)
					)
					(number "M15"
						(effects
							(font
								(size 1.27 1.27)
							)
						)
					)
				)
				(pin passive line
					(at 0 -10.16 0)
					(length 5.08)
					(hide yes)
					(name "VCCINT"
						(effects
							(font
								(size 1.27 1.27)
							)
						)
					)
					(number "M17"
						(effects
							(font
								(size 1.27 1.27)
							)
						)
					)
				)
				(pin passive line
					(at 0 -10.16 0)
					(length 5.08)
					(hide yes)
					(name "VCCINT"
						(effects
							(font
								(size 1.27 1.27)
							)
						)
					)
					(number "N10"
						(effects
							(font
								(size 1.27 1.27)
							)
						)
					)
				)
				(pin passive line
					(at 0 -10.16 0)
					(length 5.08)
					(hide yes)
					(name "VCCINT"
						(effects
							(font
								(size 1.27 1.27)
							)
						)
					)
					(number "N12"
						(effects
							(font
								(size 1.27 1.27)
							)
						)
					)
				)
				(pin passive line
					(at 0 -10.16 0)
					(length 5.08)
					(hide yes)
					(name "VCCINT"
						(effects
							(font
								(size 1.27 1.27)
							)
						)
					)
					(number "N14"
						(effects
							(font
								(size 1.27 1.27)
							)
						)
					)
				)
				(pin passive line
					(at 0 -10.16 0)
					(length 5.08)
					(hide yes)
					(name "VCCINT"
						(effects
							(font
								(size 1.27 1.27)
							)
						)
					)
					(number "N18"
						(effects
							(font
								(size 1.27 1.27)
							)
						)
					)
				)
				(pin passive line
					(at 0 -10.16 0)
					(length 5.08)
					(hide yes)
					(name "VCCINT"
						(effects
							(font
								(size 1.27 1.27)
							)
						)
					)
					(number "P11"
						(effects
							(font
								(size 1.27 1.27)
							)
						)
					)
				)
				(pin passive line
					(at 0 -10.16 0)
					(length 5.08)
					(hide yes)
					(name "VCCINT"
						(effects
							(font
								(size 1.27 1.27)
							)
						)
					)
					(number "P17"
						(effects
							(font
								(size 1.27 1.27)
							)
						)
					)
				)
				(pin passive line
					(at 0 -10.16 0)
					(length 5.08)
					(hide yes)
					(name "VCCINT"
						(effects
							(font
								(size 1.27 1.27)
							)
						)
					)
					(number "R10"
						(effects
							(font
								(size 1.27 1.27)
							)
						)
					)
				)
				(pin passive line
					(at 0 -10.16 0)
					(length 5.08)
					(hide yes)
					(name "VCCINT"
						(effects
							(font
								(size 1.27 1.27)
							)
						)
					)
					(number "R12"
						(effects
							(font
								(size 1.27 1.27)
							)
						)
					)
				)
				(pin passive line
					(at 0 -10.16 0)
					(length 5.08)
					(hide yes)
					(name "VCCINT"
						(effects
							(font
								(size 1.27 1.27)
							)
						)
					)
					(number "R18"
						(effects
							(font
								(size 1.27 1.27)
							)
						)
					)
				)
				(pin passive line
					(at 0 -10.16 0)
					(length 5.08)
					(hide yes)
					(name "VCCINT"
						(effects
							(font
								(size 1.27 1.27)
							)
						)
					)
					(number "T11"
						(effects
							(font
								(size 1.27 1.27)
							)
						)
					)
				)
				(pin passive line
					(at 0 -10.16 0)
					(length 5.08)
					(hide yes)
					(name "VCCINT"
						(effects
							(font
								(size 1.27 1.27)
							)
						)
					)
					(number "T17"
						(effects
							(font
								(size 1.27 1.27)
							)
						)
					)
				)
				(pin passive line
					(at 0 -10.16 0)
					(length 5.08)
					(hide yes)
					(name "VCCINT"
						(effects
							(font
								(size 1.27 1.27)
							)
						)
					)
					(number "U10"
						(effects
							(font
								(size 1.27 1.27)
							)
						)
					)
				)
				(pin passive line
					(at 0 -10.16 0)
					(length 5.08)
					(hide yes)
					(name "VCCINT"
						(effects
							(font
								(size 1.27 1.27)
							)
						)
					)
					(number "U12"
						(effects
							(font
								(size 1.27 1.27)
							)
						)
					)
				)
				(pin passive line
					(at 0 -10.16 0)
					(length 5.08)
					(hide yes)
					(name "VCCINT"
						(effects
							(font
								(size 1.27 1.27)
							)
						)
					)
					(number "U18"
						(effects
							(font
								(size 1.27 1.27)
							)
						)
					)
				)
				(pin passive line
					(at 0 -10.16 0)
					(length 5.08)
					(hide yes)
					(name "VCCINT"
						(effects
							(font
								(size 1.27 1.27)
							)
						)
					)
					(number "V17"
						(effects
							(font
								(size 1.27 1.27)
							)
						)
					)
				)
				(pin passive line
					(at 0 -10.16 0)
					(length 5.08)
					(hide yes)
					(name "VCCINT"
						(effects
							(font
								(size 1.27 1.27)
							)
						)
					)
					(number "W18"
						(effects
							(font
								(size 1.27 1.27)
							)
						)
					)
				)
				(pin bidirectional line
					(at 0 -12.7 0)
					(length 5.08)
					(name "VCCBATT_0"
						(effects
							(font
								(size 1.27 1.27)
							)
						)
					)
					(number "C10"
						(effects
							(font
								(size 1.27 1.27)
							)
						)
					)
				)
				(pin bidirectional line
					(at 0 -16.51 0)
					(length 5.08)
					(name "GNDADC_0"
						(effects
							(font
								(size 1.27 1.27)
							)
						)
					)
					(number "P14"
						(effects
							(font
								(size 1.27 1.27)
							)
						)
					)
				)
				(pin bidirectional line
					(at 0 -19.05 0)
					(length 5.08)
					(name "GND"
						(effects
							(font
								(size 1.27 1.27)
							)
						)
					)
					(number "A1"
						(effects
							(font
								(size 1.27 1.27)
							)
						)
					)
				)
				(pin passive line
					(at 0 -19.05 0)
					(length 5.08)
					(hide yes)
					(name "GND"
						(effects
							(font
								(size 1.27 1.27)
							)
						)
					)
					(number "A14"
						(effects
							(font
								(size 1.27 1.27)
							)
						)
					)
				)
				(pin passive line
					(at 0 -19.05 0)
					(length 5.08)
					(hide yes)
					(name "GND"
						(effects
							(font
								(size 1.27 1.27)
							)
						)
					)
					(number "A2"
						(effects
							(font
								(size 1.27 1.27)
							)
						)
					)
				)
				(pin passive line
					(at 0 -19.05 0)
					(length 5.08)
					(hide yes)
					(name "GND"
						(effects
							(font
								(size 1.27 1.27)
							)
						)
					)
					(number "A24"
						(effects
							(font
								(size 1.27 1.27)
							)
						)
					)
				)
				(pin passive line
					(at 0 -19.05 0)
					(length 5.08)
					(hide yes)
					(name "GND"
						(effects
							(font
								(size 1.27 1.27)
							)
						)
					)
					(number "A5"
						(effects
							(font
								(size 1.27 1.27)
							)
						)
					)
				)
				(pin passive line
					(at 0 -19.05 0)
					(length 5.08)
					(hide yes)
					(name "GND"
						(effects
							(font
								(size 1.27 1.27)
							)
						)
					)
					(number "A6"
						(effects
							(font
								(size 1.27 1.27)
							)
						)
					)
				)
				(pin passive line
					(at 0 -19.05 0)
					(length 5.08)
					(hide yes)
					(name "GND"
						(effects
							(font
								(size 1.27 1.27)
							)
						)
					)
					(number "A9"
						(effects
							(font
								(size 1.27 1.27)
							)
						)
					)
				)
				(pin passive line
					(at 0 -19.05 0)
					(length 5.08)
					(hide yes)
					(name "GND"
						(effects
							(font
								(size 1.27 1.27)
							)
						)
					)
					(number "AA1"
						(effects
							(font
								(size 1.27 1.27)
							)
						)
					)
				)
				(pin passive line
					(at 0 -19.05 0)
					(length 5.08)
					(hide yes)
					(name "GND"
						(effects
							(font
								(size 1.27 1.27)
							)
						)
					)
					(number "AA14"
						(effects
							(font
								(size 1.27 1.27)
							)
						)
					)
				)
				(pin passive line
					(at 0 -19.05 0)
					(length 5.08)
					(hide yes)
					(name "GND"
						(effects
							(font
								(size 1.27 1.27)
							)
						)
					)
					(number "AA2"
						(effects
							(font
								(size 1.27 1.27)
							)
						)
					)
				)
				(pin passive line
					(at 0 -19.05 0)
					(length 5.08)
					(hide yes)
					(name "GND"
						(effects
							(font
								(size 1.27 1.27)
							)
						)
					)
					(number "AA24"
						(effects
							(font
								(size 1.27 1.27)
							)
						)
					)
				)
				(pin passive line
					(at 0 -19.05 0)
					(length 5.08)
					(hide yes)
					(name "GND"
						(effects
							(font
								(size 1.27 1.27)
							)
						)
					)
					(number "AA5"
						(effects
							(font
								(size 1.27 1.27)
							)
						)
					)
				)
				(pin passive line
					(at 0 -19.05 0)
					(length 5.08)
					(hide yes)
					(name "GND"
						(effects
							(font
								(size 1.27 1.27)
							)
						)
					)
					(number "AA6"
						(effects
							(font
								(size 1.27 1.27)
							)
						)
					)
				)
				(pin passive line
					(at 0 -19.05 0)
					(length 5.08)
					(hide yes)
					(name "GND"
						(effects
							(font
								(size 1.27 1.27)
							)
						)
					)
					(number "AA7"
						(effects
							(font
								(size 1.27 1.27)
							)
						)
					)
				)
				(pin passive line
					(at 0 -19.05 0)
					(length 5.08)
					(hide yes)
					(name "GND"
						(effects
							(font
								(size 1.27 1.27)
							)
						)
					)
					(number "AB11"
						(effects
							(font
								(size 1.27 1.27)
							)
						)
					)
				)
				(pin passive line
					(at 0 -19.05 0)
					(length 5.08)
					(hide yes)
					(name "GND"
						(effects
							(font
								(size 1.27 1.27)
							)
						)
					)
					(number "AB21"
						(effects
							(font
								(size 1.27 1.27)
							)
						)
					)
				)
				(pin passive line
					(at 0 -19.05 0)
					(length 5.08)
					(hide yes)
					(name "GND"
						(effects
							(font
								(size 1.27 1.27)
							)
						)
					)
					(number "AB3"
						(effects
							(font
								(size 1.27 1.27)
							)
						)
					)
				)
				(pin passive line
					(at 0 -19.05 0)
					(length 5.08)
					(hide yes)
					(name "GND"
						(effects
							(font
								(size 1.27 1.27)
							)
						)
					)
					(number "AB4"
						(effects
							(font
								(size 1.27 1.27)
							)
						)
					)
				)
				(pin passive line
					(at 0 -19.05 0)
					(length 5.08)
					(hide yes)
					(name "GND"
						(effects
							(font
								(size 1.27 1.27)
							)
						)
					)
					(number "AC18"
						(effects
							(font
								(size 1.27 1.27)
							)
						)
					)
				)
				(pin passive line
					(at 0 -19.05 0)
					(length 5.08)
					(hide yes)
					(name "GND"
						(effects
							(font
								(size 1.27 1.27)
							)
						)
					)
					(number "AC28"
						(effects
							(font
								(size 1.27 1.27)
							)
						)
					)
				)
				(pin passive line
					(at 0 -19.05 0)
					(length 5.08)
					(hide yes)
					(name "GND"
						(effects
							(font
								(size 1.27 1.27)
							)
						)
					)
					(number "AC8"
						(effects
							(font
								(size 1.27 1.27)
							)
						)
					)
				)
				(pin passive line
					(at 0 -19.05 0)
					(length 5.08)
					(hide yes)
					(name "GND"
						(effects
							(font
								(size 1.27 1.27)
							)
						)
					)
					(number "AD15"
						(effects
							(font
								(size 1.27 1.27)
							)
						)
					)
				)
				(pin passive line
					(at 0 -19.05 0)
					(length 5.08)
					(hide yes)
					(name "GND"
						(effects
							(font
								(size 1.27 1.27)
							)
						)
					)
					(number "AD25"
						(effects
							(font
								(size 1.27 1.27)
							)
						)
					)
				)
				(pin passive line
					(at 0 -19.05 0)
					(length 5.08)
					(hide yes)
					(name "GND"
						(effects
							(font
								(size 1.27 1.27)
							)
						)
					)
					(number "AD5"
						(effects
							(font
								(size 1.27 1.27)
							)
						)
					)
				)
				(pin passive line
					(at 0 -19.05 0)
					(length 5.08)
					(hide yes)
					(name "GND"
						(effects
							(font
								(size 1.27 1.27)
							)
						)
					)
					(number "AE12"
						(effects
							(font
								(size 1.27 1.27)
							)
						)
					)
				)
				(pin passive line
					(at 0 -19.05 0)
					(length 5.08)
					(hide yes)
					(name "GND"
						(effects
							(font
								(size 1.27 1.27)
							)
						)
					)
					(number "AE2"
						(effects
							(font
								(size 1.27 1.27)
							)
						)
					)
				)
				(pin passive line
					(at 0 -19.05 0)
					(length 5.08)
					(hide yes)
					(name "GND"
						(effects
							(font
								(size 1.27 1.27)
							)
						)
					)
					(number "AE22"
						(effects
							(font
								(size 1.27 1.27)
							)
						)
					)
				)
				(pin passive line
					(at 0 -19.05 0)
					(length 5.08)
					(hide yes)
					(name "GND"
						(effects
							(font
								(size 1.27 1.27)
							)
						)
					)
					(number "AF19"
						(effects
							(font
								(size 1.27 1.27)
							)
						)
					)
				)
				(pin passive line
					(at 0 -19.05 0)
					(length 5.08)
					(hide yes)
					(name "GND"
						(effects
							(font
								(size 1.27 1.27)
							)
						)
					)
					(number "AF29"
						(effects
							(font
								(size 1.27 1.27)
							)
						)
					)
				)
				(pin passive line
					(at 0 -19.05 0)
					(length 5.08)
					(hide yes)
					(name "GND"
						(effects
							(font
								(size 1.27 1.27)
							)
						)
					)
					(number "AF9"
						(effects
							(font
								(size 1.27 1.27)
							)
						)
					)
				)
				(pin passive line
					(at 0 -19.05 0)
					(length 5.08)
					(hide yes)
					(name "GND"
						(effects
							(font
								(size 1.27 1.27)
							)
						)
					)
					(number "AG16"
						(effects
							(font
								(size 1.27 1.27)
							)
						)
					)
				)
				(pin passive line
					(at 0 -19.05 0)
					(length 5.08)
					(hide yes)
					(name "GND"
						(effects
							(font
								(size 1.27 1.27)
							)
						)
					)
					(number "AG26"
						(effects
							(font
								(size 1.27 1.27)
							)
						)
					)
				)
				(pin passive line
					(at 0 -19.05 0)
					(length 5.08)
					(hide yes)
					(name "GND"
						(effects
							(font
								(size 1.27 1.27)
							)
						)
					)
					(number "AG6"
						(effects
							(font
								(size 1.27 1.27)
							)
						)
					)
				)
				(pin passive line
					(at 0 -19.05 0)
					(length 5.08)
					(hide yes)
					(name "GND"
						(effects
							(font
								(size 1.27 1.27)
							)
						)
					)
					(number "AH13"
						(effects
							(font
								(size 1.27 1.27)
							)
						)
					)
				)
				(pin passive line
					(at 0 -19.05 0)
					(length 5.08)
					(hide yes)
					(name "GND"
						(effects
							(font
								(size 1.27 1.27)
							)
						)
					)
					(number "AH23"
						(effects
							(font
								(size 1.27 1.27)
							)
						)
					)
				)
				(pin passive line
					(at 0 -19.05 0)
					(length 5.08)
					(hide yes)
					(name "GND"
						(effects
							(font
								(size 1.27 1.27)
							)
						)
					)
					(number "AH3"
						(effects
							(font
								(size 1.27 1.27)
							)
						)
					)
				)
				(pin passive line
					(at 0 -19.05 0)
					(length 5.08)
					(hide yes)
					(name "GND"
						(effects
							(font
								(size 1.27 1.27)
							)
						)
					)
					(number "AJ10"
						(effects
							(font
								(size 1.27 1.27)
							)
						)
					)
				)
				(pin passive line
					(at 0 -19.05 0)
					(length 5.08)
					(hide yes)
					(name "GND"
						(effects
							(font
								(size 1.27 1.27)
							)
						)
					)
					(number "AJ20"
						(effects
							(font
								(size 1.27 1.27)
							)
						)
					)
				)
				(pin passive line
					(at 0 -19.05 0)
					(length 5.08)
					(hide yes)
					(name "GND"
						(effects
							(font
								(size 1.27 1.27)
							)
						)
					)
					(number "AJ30"
						(effects
							(font
								(size 1.27 1.27)
							)
						)
					)
				)
				(pin passive line
					(at 0 -19.05 0)
					(length 5.08)
					(hide yes)
					(name "GND"
						(effects
							(font
								(size 1.27 1.27)
							)
						)
					)
					(number "AK17"
						(effects
							(font
								(size 1.27 1.27)
							)
						)
					)
				)
				(pin passive line
					(at 0 -19.05 0)
					(length 5.08)
					(hide yes)
					(name "GND"
						(effects
							(font
								(size 1.27 1.27)
							)
						)
					)
					(number "AK27"
						(effects
							(font
								(size 1.27 1.27)
							)
						)
					)
				)
				(pin passive line
					(at 0 -19.05 0)
					(length 5.08)
					(hide yes)
					(name "GND"
						(effects
							(font
								(size 1.27 1.27)
							)
						)
					)
					(number "AK7"
						(effects
							(font
								(size 1.27 1.27)
							)
						)
					)
				)
				(pin passive line
					(at 0 -19.05 0)
					(length 5.08)
					(hide yes)
					(name "GND"
						(effects
							(font
								(size 1.27 1.27)
							)
						)
					)
					(number "B11"
						(effects
							(font
								(size 1.27 1.27)
							)
						)
					)
				)
				(pin passive line
					(at 0 -19.05 0)
					(length 5.08)
					(hide yes)
					(name "GND"
						(effects
							(font
								(size 1.27 1.27)
							)
						)
					)
					(number "B21"
						(effects
							(font
								(size 1.27 1.27)
							)
						)
					)
				)
				(pin passive line
					(at 0 -19.05 0)
					(length 5.08)
					(hide yes)
					(name "GND"
						(effects
							(font
								(size 1.27 1.27)
							)
						)
					)
					(number "B4"
						(effects
							(font
								(size 1.27 1.27)
							)
						)
					)
				)
				(pin passive line
					(at 0 -19.05 0)
					(length 5.08)
					(hide yes)
					(name "GND"
						(effects
							(font
								(size 1.27 1.27)
							)
						)
					)
					(number "B8"
						(effects
							(font
								(size 1.27 1.27)
							)
						)
					)
				)
				(pin passive line
					(at 0 -19.05 0)
					(length 5.08)
					(hide yes)
					(name "GND"
						(effects
							(font
								(size 1.27 1.27)
							)
						)
					)
					(number "B9"
						(effects
							(font
								(size 1.27 1.27)
							)
						)
					)
				)
				(pin passive line
					(at 0 -19.05 0)
					(length 5.08)
					(hide yes)
					(name "GND"
						(effects
							(font
								(size 1.27 1.27)
							)
						)
					)
					(number "C1"
						(effects
							(font
								(size 1.27 1.27)
							)
						)
					)
				)
				(pin passive line
					(at 0 -19.05 0)
					(length 5.08)
					(hide yes)
					(name "GND"
						(effects
							(font
								(size 1.27 1.27)
							)
						)
					)
					(number "C18"
						(effects
							(font
								(size 1.27 1.27)
							)
						)
					)
				)
				(pin passive line
					(at 0 -19.05 0)
					(length 5.08)
					(hide yes)
					(name "GND"
						(effects
							(font
								(size 1.27 1.27)
							)
						)
					)
					(number "C2"
						(effects
							(font
								(size 1.27 1.27)
							)
						)
					)
				)
				(pin passive line
					(at 0 -19.05 0)
					(length 5.08)
					(hide yes)
					(name "GND"
						(effects
							(font
								(size 1.27 1.27)
							)
						)
					)
					(number "C28"
						(effects
							(font
								(size 1.27 1.27)
							)
						)
					)
				)
				(pin passive line
					(at 0 -19.05 0)
					(length 5.08)
					(hide yes)
					(name "GND"
						(effects
							(font
								(size 1.27 1.27)
							)
						)
					)
					(number "C6"
						(effects
							(font
								(size 1.27 1.27)
							)
						)
					)
				)
				(pin passive line
					(at 0 -19.05 0)
					(length 5.08)
					(hide yes)
					(name "GND"
						(effects
							(font
								(size 1.27 1.27)
							)
						)
					)
					(number "C9"
						(effects
							(font
								(size 1.27 1.27)
							)
						)
					)
				)
				(pin passive line
					(at 0 -19.05 0)
					(length 5.08)
					(hide yes)
					(name "GND"
						(effects
							(font
								(size 1.27 1.27)
							)
						)
					)
					(number "D15"
						(effects
							(font
								(size 1.27 1.27)
							)
						)
					)
				)
				(pin passive line
					(at 0 -19.05 0)
					(length 5.08)
					(hide yes)
					(name "GND"
						(effects
							(font
								(size 1.27 1.27)
							)
						)
					)
					(number "D25"
						(effects
							(font
								(size 1.27 1.27)
							)
						)
					)
				)
				(pin passive line
					(at 0 -19.05 0)
					(length 5.08)
					(hide yes)
					(name "GND"
						(effects
							(font
								(size 1.27 1.27)
							)
						)
					)
					(number "D4"
						(effects
							(font
								(size 1.27 1.27)
							)
						)
					)
				)
				(pin passive line
					(at 0 -19.05 0)
					(length 5.08)
					(hide yes)
					(name "GND"
						(effects
							(font
								(size 1.27 1.27)
							)
						)
					)
					(number "D8"
						(effects
							(font
								(size 1.27 1.27)
							)
						)
					)
				)
				(pin passive line
					(at 0 -19.05 0)
					(length 5.08)
					(hide yes)
					(name "GND"
						(effects
							(font
								(size 1.27 1.27)
							)
						)
					)
					(number "D9"
						(effects
							(font
								(size 1.27 1.27)
							)
						)
					)
				)
				(pin passive line
					(at 0 -19.05 0)
					(length 5.08)
					(hide yes)
					(name "GND"
						(effects
							(font
								(size 1.27 1.27)
							)
						)
					)
					(number "E1"
						(effects
							(font
								(size 1.27 1.27)
							)
						)
					)
				)
				(pin passive line
					(at 0 -19.05 0)
					(length 5.08)
					(hide yes)
					(name "GND"
						(effects
							(font
								(size 1.27 1.27)
							)
						)
					)
					(number "E12"
						(effects
							(font
								(size 1.27 1.27)
							)
						)
					)
				)
				(pin passive line
					(at 0 -19.05 0)
					(length 5.08)
					(hide yes)
					(name "GND"
						(effects
							(font
								(size 1.27 1.27)
							)
						)
					)
					(number "E2"
						(effects
							(font
								(size 1.27 1.27)
							)
						)
					)
				)
				(pin passive line
					(at 0 -19.05 0)
					(length 5.08)
					(hide yes)
					(name "GND"
						(effects
							(font
								(size 1.27 1.27)
							)
						)
					)
					(number "E22"
						(effects
							(font
								(size 1.27 1.27)
							)
						)
					)
				)
				(pin passive line
					(at 0 -19.05 0)
					(length 5.08)
					(hide yes)
					(name "GND"
						(effects
							(font
								(size 1.27 1.27)
							)
						)
					)
					(number "E6"
						(effects
							(font
								(size 1.27 1.27)
							)
						)
					)
				)
				(pin passive line
					(at 0 -19.05 0)
					(length 5.08)
					(hide yes)
					(name "GND"
						(effects
							(font
								(size 1.27 1.27)
							)
						)
					)
					(number "E9"
						(effects
							(font
								(size 1.27 1.27)
							)
						)
					)
				)
				(pin passive line
					(at 0 -19.05 0)
					(length 5.08)
					(hide yes)
					(name "GND"
						(effects
							(font
								(size 1.27 1.27)
							)
						)
					)
					(number "F19"
						(effects
							(font
								(size 1.27 1.27)
							)
						)
					)
				)
				(pin passive line
					(at 0 -19.05 0)
					(length 5.08)
					(hide yes)
					(name "GND"
						(effects
							(font
								(size 1.27 1.27)
							)
						)
					)
					(number "F29"
						(effects
							(font
								(size 1.27 1.27)
							)
						)
					)
				)
				(pin passive line
					(at 0 -19.05 0)
					(length 5.08)
					(hide yes)
					(name "GND"
						(effects
							(font
								(size 1.27 1.27)
							)
						)
					)
					(number "F4"
						(effects
							(font
								(size 1.27 1.27)
							)
						)
					)
				)
				(pin passive line
					(at 0 -19.05 0)
					(length 5.08)
					(hide yes)
					(name "GND"
						(effects
							(font
								(size 1.27 1.27)
							)
						)
					)
					(number "F8"
						(effects
							(font
								(size 1.27 1.27)
							)
						)
					)
				)
				(pin passive line
					(at 0 -19.05 0)
					(length 5.08)
					(hide yes)
					(name "GND"
						(effects
							(font
								(size 1.27 1.27)
							)
						)
					)
					(number "F9"
						(effects
							(font
								(size 1.27 1.27)
							)
						)
					)
				)
				(pin passive line
					(at 0 -19.05 0)
					(length 5.08)
					(hide yes)
					(name "GND"
						(effects
							(font
								(size 1.27 1.27)
							)
						)
					)
					(number "G1"
						(effects
							(font
								(size 1.27 1.27)
							)
						)
					)
				)
				(pin passive line
					(at 0 -19.05 0)
					(length 5.08)
					(hide yes)
					(name "GND"
						(effects
							(font
								(size 1.27 1.27)
							)
						)
					)
					(number "G16"
						(effects
							(font
								(size 1.27 1.27)
							)
						)
					)
				)
				(pin passive line
					(at 0 -19.05 0)
					(length 5.08)
					(hide yes)
					(name "GND"
						(effects
							(font
								(size 1.27 1.27)
							)
						)
					)
					(number "G2"
						(effects
							(font
								(size 1.27 1.27)
							)
						)
					)
				)
				(pin passive line
					(at 0 -19.05 0)
					(length 5.08)
					(hide yes)
					(name "GND"
						(effects
							(font
								(size 1.27 1.27)
							)
						)
					)
					(number "G26"
						(effects
							(font
								(size 1.27 1.27)
							)
						)
					)
				)
				(pin passive line
					(at 0 -19.05 0)
					(length 5.08)
					(hide yes)
					(name "GND"
						(effects
							(font
								(size 1.27 1.27)
							)
						)
					)
					(number "G6"
						(effects
							(font
								(size 1.27 1.27)
							)
						)
					)
				)
				(pin passive line
					(at 0 -19.05 0)
					(length 5.08)
					(hide yes)
					(name "GND"
						(effects
							(font
								(size 1.27 1.27)
							)
						)
					)
					(number "G9"
						(effects
							(font
								(size 1.27 1.27)
							)
						)
					)
				)
				(pin passive line
					(at 0 -19.05 0)
					(length 5.08)
					(hide yes)
					(name "GND"
						(effects
							(font
								(size 1.27 1.27)
							)
						)
					)
					(number "H13"
						(effects
							(font
								(size 1.27 1.27)
							)
						)
					)
				)
				(pin passive line
					(at 0 -19.05 0)
					(length 5.08)
					(hide yes)
					(name "GND"
						(effects
							(font
								(size 1.27 1.27)
							)
						)
					)
					(number "H23"
						(effects
							(font
								(size 1.27 1.27)
							)
						)
					)
				)
				(pin passive line
					(at 0 -19.05 0)
					(length 5.08)
					(hide yes)
					(name "GND"
						(effects
							(font
								(size 1.27 1.27)
							)
						)
					)
					(number "H4"
						(effects
							(font
								(size 1.27 1.27)
							)
						)
					)
				)
				(pin passive line
					(at 0 -19.05 0)
					(length 5.08)
					(hide yes)
					(name "GND"
						(effects
							(font
								(size 1.27 1.27)
							)
						)
					)
					(number "H8"
						(effects
							(font
								(size 1.27 1.27)
							)
						)
					)
				)
				(pin passive line
					(at 0 -19.05 0)
					(length 5.08)
					(hide yes)
					(name "GND"
						(effects
							(font
								(size 1.27 1.27)
							)
						)
					)
					(number "H9"
						(effects
							(font
								(size 1.27 1.27)
							)
						)
					)
				)
				(pin passive line
					(at 0 -19.05 0)
					(length 5.08)
					(hide yes)
					(name "GND"
						(effects
							(font
								(size 1.27 1.27)
							)
						)
					)
					(number "J1"
						(effects
							(font
								(size 1.27 1.27)
							)
						)
					)
				)
				(pin passive line
					(at 0 -19.05 0)
					(length 5.08)
					(hide yes)
					(name "GND"
						(effects
							(font
								(size 1.27 1.27)
							)
						)
					)
					(number "J10"
						(effects
							(font
								(size 1.27 1.27)
							)
						)
					)
				)
				(pin passive line
					(at 0 -19.05 0)
					(length 5.08)
					(hide yes)
					(name "GND"
						(effects
							(font
								(size 1.27 1.27)
							)
						)
					)
					(number "J2"
						(effects
							(font
								(size 1.27 1.27)
							)
						)
					)
				)
				(pin passive line
					(at 0 -19.05 0)
					(length 5.08)
					(hide yes)
					(name "GND"
						(effects
							(font
								(size 1.27 1.27)
							)
						)
					)
					(number "J20"
						(effects
							(font
								(size 1.27 1.27)
							)
						)
					)
				)
				(pin passive line
					(at 0 -19.05 0)
					(length 5.08)
					(hide yes)
					(name "GND"
						(effects
							(font
								(size 1.27 1.27)
							)
						)
					)
					(number "J30"
						(effects
							(font
								(size 1.27 1.27)
							)
						)
					)
				)
				(pin passive line
					(at 0 -19.05 0)
					(length 5.08)
					(hide yes)
					(name "GND"
						(effects
							(font
								(size 1.27 1.27)
							)
						)
					)
					(number "J6"
						(effects
							(font
								(size 1.27 1.27)
							)
						)
					)
				)
				(pin passive line
					(at 0 -19.05 0)
					(length 5.08)
					(hide yes)
					(name "GND"
						(effects
							(font
								(size 1.27 1.27)
							)
						)
					)
					(number "J9"
						(effects
							(font
								(size 1.27 1.27)
							)
						)
					)
				)
				(pin passive line
					(at 0 -19.05 0)
					(length 5.08)
					(hide yes)
					(name "GND"
						(effects
							(font
								(size 1.27 1.27)
							)
						)
					)
					(number "K17"
						(effects
							(font
								(size 1.27 1.27)
							)
						)
					)
				)
				(pin passive line
					(at 0 -19.05 0)
					(length 5.08)
					(hide yes)
					(name "GND"
						(effects
							(font
								(size 1.27 1.27)
							)
						)
					)
					(number "K27"
						(effects
							(font
								(size 1.27 1.27)
							)
						)
					)
				)
				(pin passive line
					(at 0 -19.05 0)
					(length 5.08)
					(hide yes)
					(name "GND"
						(effects
							(font
								(size 1.27 1.27)
							)
						)
					)
					(number "K4"
						(effects
							(font
								(size 1.27 1.27)
							)
						)
					)
				)
				(pin passive line
					(at 0 -19.05 0)
					(length 5.08)
					(hide yes)
					(name "GND"
						(effects
							(font
								(size 1.27 1.27)
							)
						)
					)
					(number "K8"
						(effects
							(font
								(size 1.27 1.27)
							)
						)
					)
				)
				(pin passive line
					(at 0 -19.05 0)
					(length 5.08)
					(hide yes)
					(name "GND"
						(effects
							(font
								(size 1.27 1.27)
							)
						)
					)
					(number "K9"
						(effects
							(font
								(size 1.27 1.27)
							)
						)
					)
				)
				(pin passive line
					(at 0 -19.05 0)
					(length 5.08)
					(hide yes)
					(name "GND"
						(effects
							(font
								(size 1.27 1.27)
							)
						)
					)
					(number "L1"
						(effects
							(font
								(size 1.27 1.27)
							)
						)
					)
				)
				(pin passive line
					(at 0 -19.05 0)
					(length 5.08)
					(hide yes)
					(name "GND"
						(effects
							(font
								(size 1.27 1.27)
							)
						)
					)
					(number "L14"
						(effects
							(font
								(size 1.27 1.27)
							)
						)
					)
				)
				(pin passive line
					(at 0 -19.05 0)
					(length 5.08)
					(hide yes)
					(name "GND"
						(effects
							(font
								(size 1.27 1.27)
							)
						)
					)
					(number "L2"
						(effects
							(font
								(size 1.27 1.27)
							)
						)
					)
				)
				(pin passive line
					(at 0 -19.05 0)
					(length 5.08)
					(hide yes)
					(name "GND"
						(effects
							(font
								(size 1.27 1.27)
							)
						)
					)
					(number "L24"
						(effects
							(font
								(size 1.27 1.27)
							)
						)
					)
				)
				(pin passive line
					(at 0 -19.05 0)
					(length 5.08)
					(hide yes)
					(name "GND"
						(effects
							(font
								(size 1.27 1.27)
							)
						)
					)
					(number "L6"
						(effects
							(font
								(size 1.27 1.27)
							)
						)
					)
				)
				(pin passive line
					(at 0 -19.05 0)
					(length 5.08)
					(hide yes)
					(name "GND"
						(effects
							(font
								(size 1.27 1.27)
							)
						)
					)
					(number "L9"
						(effects
							(font
								(size 1.27 1.27)
							)
						)
					)
				)
				(pin passive line
					(at 0 -19.05 0)
					(length 5.08)
					(hide yes)
					(name "GND"
						(effects
							(font
								(size 1.27 1.27)
							)
						)
					)
					(number "M12"
						(effects
							(font
								(size 1.27 1.27)
							)
						)
					)
				)
				(pin passive line
					(at 0 -19.05 0)
					(length 5.08)
					(hide yes)
					(name "GND"
						(effects
							(font
								(size 1.27 1.27)
							)
						)
					)
					(number "M14"
						(effects
							(font
								(size 1.27 1.27)
							)
						)
					)
				)
				(pin passive line
					(at 0 -19.05 0)
					(length 5.08)
					(hide yes)
					(name "GND"
						(effects
							(font
								(size 1.27 1.27)
							)
						)
					)
					(number "M16"
						(effects
							(font
								(size 1.27 1.27)
							)
						)
					)
				)
				(pin passive line
					(at 0 -19.05 0)
					(length 5.08)
					(hide yes)
					(name "GND"
						(effects
							(font
								(size 1.27 1.27)
							)
						)
					)
					(number "M18"
						(effects
							(font
								(size 1.27 1.27)
							)
						)
					)
				)
				(pin passive line
					(at 0 -19.05 0)
					(length 5.08)
					(hide yes)
					(name "GND"
						(effects
							(font
								(size 1.27 1.27)
							)
						)
					)
					(number "M21"
						(effects
							(font
								(size 1.27 1.27)
							)
						)
					)
				)
				(pin passive line
					(at 0 -19.05 0)
					(length 5.08)
					(hide yes)
					(name "GND"
						(effects
							(font
								(size 1.27 1.27)
							)
						)
					)
					(number "M4"
						(effects
							(font
								(size 1.27 1.27)
							)
						)
					)
				)
				(pin passive line
					(at 0 -19.05 0)
					(length 5.08)
					(hide yes)
					(name "GND"
						(effects
							(font
								(size 1.27 1.27)
							)
						)
					)
					(number "M8"
						(effects
							(font
								(size 1.27 1.27)
							)
						)
					)
				)
				(pin passive line
					(at 0 -19.05 0)
					(length 5.08)
					(hide yes)
					(name "GND"
						(effects
							(font
								(size 1.27 1.27)
							)
						)
					)
					(number "M9"
						(effects
							(font
								(size 1.27 1.27)
							)
						)
					)
				)
				(pin passive line
					(at 0 -19.05 0)
					(length 5.08)
					(hide yes)
					(name "GND"
						(effects
							(font
								(size 1.27 1.27)
							)
						)
					)
					(number "N1"
						(effects
							(font
								(size 1.27 1.27)
							)
						)
					)
				)
				(pin passive line
					(at 0 -19.05 0)
					(length 5.08)
					(hide yes)
					(name "GND"
						(effects
							(font
								(size 1.27 1.27)
							)
						)
					)
					(number "N11"
						(effects
							(font
								(size 1.27 1.27)
							)
						)
					)
				)
				(pin passive line
					(at 0 -19.05 0)
					(length 5.08)
					(hide yes)
					(name "GND"
						(effects
							(font
								(size 1.27 1.27)
							)
						)
					)
					(number "N13"
						(effects
							(font
								(size 1.27 1.27)
							)
						)
					)
				)
				(pin passive line
					(at 0 -19.05 0)
					(length 5.08)
					(hide yes)
					(name "GND"
						(effects
							(font
								(size 1.27 1.27)
							)
						)
					)
					(number "N15"
						(effects
							(font
								(size 1.27 1.27)
							)
						)
					)
				)
				(pin passive line
					(at 0 -19.05 0)
					(length 5.08)
					(hide yes)
					(name "GND"
						(effects
							(font
								(size 1.27 1.27)
							)
						)
					)
					(number "N17"
						(effects
							(font
								(size 1.27 1.27)
							)
						)
					)
				)
				(pin passive line
					(at 0 -19.05 0)
					(length 5.08)
					(hide yes)
					(name "GND"
						(effects
							(font
								(size 1.27 1.27)
							)
						)
					)
					(number "N2"
						(effects
							(font
								(size 1.27 1.27)
							)
						)
					)
				)
				(pin passive line
					(at 0 -19.05 0)
					(length 5.08)
					(hide yes)
					(name "GND"
						(effects
							(font
								(size 1.27 1.27)
							)
						)
					)
					(number "N28"
						(effects
							(font
								(size 1.27 1.27)
							)
						)
					)
				)
				(pin passive line
					(at 0 -19.05 0)
					(length 5.08)
					(hide yes)
					(name "GND"
						(effects
							(font
								(size 1.27 1.27)
							)
						)
					)
					(number "N6"
						(effects
							(font
								(size 1.27 1.27)
							)
						)
					)
				)
				(pin passive line
					(at 0 -19.05 0)
					(length 5.08)
					(hide yes)
					(name "GND"
						(effects
							(font
								(size 1.27 1.27)
							)
						)
					)
					(number "N9"
						(effects
							(font
								(size 1.27 1.27)
							)
						)
					)
				)
				(pin passive line
					(at 0 -19.05 0)
					(length 5.08)
					(hide yes)
					(name "GND"
						(effects
							(font
								(size 1.27 1.27)
							)
						)
					)
					(number "P10"
						(effects
							(font
								(size 1.27 1.27)
							)
						)
					)
				)
				(pin passive line
					(at 0 -19.05 0)
					(length 5.08)
					(hide yes)
					(name "GND"
						(effects
							(font
								(size 1.27 1.27)
							)
						)
					)
					(number "P12"
						(effects
							(font
								(size 1.27 1.27)
							)
						)
					)
				)
				(pin passive line
					(at 0 -19.05 0)
					(length 5.08)
					(hide yes)
					(name "GND"
						(effects
							(font
								(size 1.27 1.27)
							)
						)
					)
					(number "P16"
						(effects
							(font
								(size 1.27 1.27)
							)
						)
					)
				)
				(pin passive line
					(at 0 -19.05 0)
					(length 5.08)
					(hide yes)
					(name "GND"
						(effects
							(font
								(size 1.27 1.27)
							)
						)
					)
					(number "P18"
						(effects
							(font
								(size 1.27 1.27)
							)
						)
					)
				)
				(pin passive line
					(at 0 -19.05 0)
					(length 5.08)
					(hide yes)
					(name "GND"
						(effects
							(font
								(size 1.27 1.27)
							)
						)
					)
					(number "P25"
						(effects
							(font
								(size 1.27 1.27)
							)
						)
					)
				)
				(pin passive line
					(at 0 -19.05 0)
					(length 5.08)
					(hide yes)
					(name "GND"
						(effects
							(font
								(size 1.27 1.27)
							)
						)
					)
					(number "P4"
						(effects
							(font
								(size 1.27 1.27)
							)
						)
					)
				)
				(pin passive line
					(at 0 -19.05 0)
					(length 5.08)
					(hide yes)
					(name "GND"
						(effects
							(font
								(size 1.27 1.27)
							)
						)
					)
					(number "P8"
						(effects
							(font
								(size 1.27 1.27)
							)
						)
					)
				)
				(pin passive line
					(at 0 -19.05 0)
					(length 5.08)
					(hide yes)
					(name "GND"
						(effects
							(font
								(size 1.27 1.27)
							)
						)
					)
					(number "P9"
						(effects
							(font
								(size 1.27 1.27)
							)
						)
					)
				)
				(pin passive line
					(at 0 -19.05 0)
					(length 5.08)
					(hide yes)
					(name "GND"
						(effects
							(font
								(size 1.27 1.27)
							)
						)
					)
					(number "R1"
						(effects
							(font
								(size 1.27 1.27)
							)
						)
					)
				)
				(pin passive line
					(at 0 -19.05 0)
					(length 5.08)
					(hide yes)
					(name "GND"
						(effects
							(font
								(size 1.27 1.27)
							)
						)
					)
					(number "R11"
						(effects
							(font
								(size 1.27 1.27)
							)
						)
					)
				)
				(pin passive line
					(at 0 -19.05 0)
					(length 5.08)
					(hide yes)
					(name "GND"
						(effects
							(font
								(size 1.27 1.27)
							)
						)
					)
					(number "R13"
						(effects
							(font
								(size 1.27 1.27)
							)
						)
					)
				)
				(pin passive line
					(at 0 -19.05 0)
					(length 5.08)
					(hide yes)
					(name "GND"
						(effects
							(font
								(size 1.27 1.27)
							)
						)
					)
					(number "R17"
						(effects
							(font
								(size 1.27 1.27)
							)
						)
					)
				)
				(pin passive line
					(at 0 -19.05 0)
					(length 5.08)
					(hide yes)
					(name "GND"
						(effects
							(font
								(size 1.27 1.27)
							)
						)
					)
					(number "R2"
						(effects
							(font
								(size 1.27 1.27)
							)
						)
					)
				)
				(pin passive line
					(at 0 -19.05 0)
					(length 5.08)
					(hide yes)
					(name "GND"
						(effects
							(font
								(size 1.27 1.27)
							)
						)
					)
					(number "R22"
						(effects
							(font
								(size 1.27 1.27)
							)
						)
					)
				)
				(pin passive line
					(at 0 -19.05 0)
					(length 5.08)
					(hide yes)
					(name "GND"
						(effects
							(font
								(size 1.27 1.27)
							)
						)
					)
					(number "R6"
						(effects
							(font
								(size 1.27 1.27)
							)
						)
					)
				)
				(pin passive line
					(at 0 -19.05 0)
					(length 5.08)
					(hide yes)
					(name "GND"
						(effects
							(font
								(size 1.27 1.27)
							)
						)
					)
					(number "R9"
						(effects
							(font
								(size 1.27 1.27)
							)
						)
					)
				)
				(pin passive line
					(at 0 -19.05 0)
					(length 5.08)
					(hide yes)
					(name "GND"
						(effects
							(font
								(size 1.27 1.27)
							)
						)
					)
					(number "T10"
						(effects
							(font
								(size 1.27 1.27)
							)
						)
					)
				)
				(pin passive line
					(at 0 -19.05 0)
					(length 5.08)
					(hide yes)
					(name "GND"
						(effects
							(font
								(size 1.27 1.27)
							)
						)
					)
					(number "T12"
						(effects
							(font
								(size 1.27 1.27)
							)
						)
					)
				)
				(pin passive line
					(at 0 -19.05 0)
					(length 5.08)
					(hide yes)
					(name "GND"
						(effects
							(font
								(size 1.27 1.27)
							)
						)
					)
					(number "T16"
						(effects
							(font
								(size 1.27 1.27)
							)
						)
					)
				)
				(pin passive line
					(at 0 -19.05 0)
					(length 5.08)
					(hide yes)
					(name "GND"
						(effects
							(font
								(size 1.27 1.27)
							)
						)
					)
					(number "T18"
						(effects
							(font
								(size 1.27 1.27)
							)
						)
					)
				)
				(pin passive line
					(at 0 -19.05 0)
					(length 5.08)
					(hide yes)
					(name "GND"
						(effects
							(font
								(size 1.27 1.27)
							)
						)
					)
					(number "T19"
						(effects
							(font
								(size 1.27 1.27)
							)
						)
					)
				)
				(pin passive line
					(at 0 -19.05 0)
					(length 5.08)
					(hide yes)
					(name "GND"
						(effects
							(font
								(size 1.27 1.27)
							)
						)
					)
					(number "T29"
						(effects
							(font
								(size 1.27 1.27)
							)
						)
					)
				)
				(pin passive line
					(at 0 -19.05 0)
					(length 5.08)
					(hide yes)
					(name "GND"
						(effects
							(font
								(size 1.27 1.27)
							)
						)
					)
					(number "T4"
						(effects
							(font
								(size 1.27 1.27)
							)
						)
					)
				)
				(pin passive line
					(at 0 -19.05 0)
					(length 5.08)
					(hide yes)
					(name "GND"
						(effects
							(font
								(size 1.27 1.27)
							)
						)
					)
					(number "T8"
						(effects
							(font
								(size 1.27 1.27)
							)
						)
					)
				)
				(pin passive line
					(at 0 -19.05 0)
					(length 5.08)
					(hide yes)
					(name "GND"
						(effects
							(font
								(size 1.27 1.27)
							)
						)
					)
					(number "U1"
						(effects
							(font
								(size 1.27 1.27)
							)
						)
					)
				)
				(pin passive line
					(at 0 -19.05 0)
					(length 5.08)
					(hide yes)
					(name "GND"
						(effects
							(font
								(size 1.27 1.27)
							)
						)
					)
					(number "U11"
						(effects
							(font
								(size 1.27 1.27)
							)
						)
					)
				)
				(pin passive line
					(at 0 -19.05 0)
					(length 5.08)
					(hide yes)
					(name "GND"
						(effects
							(font
								(size 1.27 1.27)
							)
						)
					)
					(number "U13"
						(effects
							(font
								(size 1.27 1.27)
							)
						)
					)
				)
				(pin passive line
					(at 0 -19.05 0)
					(length 5.08)
					(hide yes)
					(name "GND"
						(effects
							(font
								(size 1.27 1.27)
							)
						)
					)
					(number "U17"
						(effects
							(font
								(size 1.27 1.27)
							)
						)
					)
				)
				(pin passive line
					(at 0 -19.05 0)
					(length 5.08)
					(hide yes)
					(name "GND"
						(effects
							(font
								(size 1.27 1.27)
							)
						)
					)
					(number "U2"
						(effects
							(font
								(size 1.27 1.27)
							)
						)
					)
				)
				(pin passive line
					(at 0 -19.05 0)
					(length 5.08)
					(hide yes)
					(name "GND"
						(effects
							(font
								(size 1.27 1.27)
							)
						)
					)
					(number "U26"
						(effects
							(font
								(size 1.27 1.27)
							)
						)
					)
				)
				(pin passive line
					(at 0 -19.05 0)
					(length 5.08)
					(hide yes)
					(name "GND"
						(effects
							(font
								(size 1.27 1.27)
							)
						)
					)
					(number "U6"
						(effects
							(font
								(size 1.27 1.27)
							)
						)
					)
				)
				(pin passive line
					(at 0 -19.05 0)
					(length 5.08)
					(hide yes)
					(name "GND"
						(effects
							(font
								(size 1.27 1.27)
							)
						)
					)
					(number "U9"
						(effects
							(font
								(size 1.27 1.27)
							)
						)
					)
				)
				(pin passive line
					(at 0 -19.05 0)
					(length 5.08)
					(hide yes)
					(name "GND"
						(effects
							(font
								(size 1.27 1.27)
							)
						)
					)
					(number "V10"
						(effects
							(font
								(size 1.27 1.27)
							)
						)
					)
				)
				(pin passive line
					(at 0 -19.05 0)
					(length 5.08)
					(hide yes)
					(name "GND"
						(effects
							(font
								(size 1.27 1.27)
							)
						)
					)
					(number "V12"
						(effects
							(font
								(size 1.27 1.27)
							)
						)
					)
				)
				(pin passive line
					(at 0 -19.05 0)
					(length 5.08)
					(hide yes)
					(name "GND"
						(effects
							(font
								(size 1.27 1.27)
							)
						)
					)
					(number "V14"
						(effects
							(font
								(size 1.27 1.27)
							)
						)
					)
				)
				(pin passive line
					(at 0 -19.05 0)
					(length 5.08)
					(hide yes)
					(name "GND"
						(effects
							(font
								(size 1.27 1.27)
							)
						)
					)
					(number "V16"
						(effects
							(font
								(size 1.27 1.27)
							)
						)
					)
				)
				(pin passive line
					(at 0 -19.05 0)
					(length 5.08)
					(hide yes)
					(name "GND"
						(effects
							(font
								(size 1.27 1.27)
							)
						)
					)
					(number "V18"
						(effects
							(font
								(size 1.27 1.27)
							)
						)
					)
				)
				(pin passive line
					(at 0 -19.05 0)
					(length 5.08)
					(hide yes)
					(name "GND"
						(effects
							(font
								(size 1.27 1.27)
							)
						)
					)
					(number "V23"
						(effects
							(font
								(size 1.27 1.27)
							)
						)
					)
				)
				(pin passive line
					(at 0 -19.05 0)
					(length 5.08)
					(hide yes)
					(name "GND"
						(effects
							(font
								(size 1.27 1.27)
							)
						)
					)
					(number "V4"
						(effects
							(font
								(size 1.27 1.27)
							)
						)
					)
				)
				(pin passive line
					(at 0 -19.05 0)
					(length 5.08)
					(hide yes)
					(name "GND"
						(effects
							(font
								(size 1.27 1.27)
							)
						)
					)
					(number "V8"
						(effects
							(font
								(size 1.27 1.27)
							)
						)
					)
				)
				(pin passive line
					(at 0 -19.05 0)
					(length 5.08)
					(hide yes)
					(name "GND"
						(effects
							(font
								(size 1.27 1.27)
							)
						)
					)
					(number "V9"
						(effects
							(font
								(size 1.27 1.27)
							)
						)
					)
				)
				(pin passive line
					(at 0 -19.05 0)
					(length 5.08)
					(hide yes)
					(name "GND"
						(effects
							(font
								(size 1.27 1.27)
							)
						)
					)
					(number "W1"
						(effects
							(font
								(size 1.27 1.27)
							)
						)
					)
				)
				(pin passive line
					(at 0 -19.05 0)
					(length 5.08)
					(hide yes)
					(name "GND"
						(effects
							(font
								(size 1.27 1.27)
							)
						)
					)
					(number "W11"
						(effects
							(font
								(size 1.27 1.27)
							)
						)
					)
				)
				(pin passive line
					(at 0 -19.05 0)
					(length 5.08)
					(hide yes)
					(name "GND"
						(effects
							(font
								(size 1.27 1.27)
							)
						)
					)
					(number "W13"
						(effects
							(font
								(size 1.27 1.27)
							)
						)
					)
				)
				(pin passive line
					(at 0 -19.05 0)
					(length 5.08)
					(hide yes)
					(name "GND"
						(effects
							(font
								(size 1.27 1.27)
							)
						)
					)
					(number "W15"
						(effects
							(font
								(size 1.27 1.27)
							)
						)
					)
				)
				(pin passive line
					(at 0 -19.05 0)
					(length 5.08)
					(hide yes)
					(name "GND"
						(effects
							(font
								(size 1.27 1.27)
							)
						)
					)
					(number "W17"
						(effects
							(font
								(size 1.27 1.27)
							)
						)
					)
				)
				(pin passive line
					(at 0 -19.05 0)
					(length 5.08)
					(hide yes)
					(name "GND"
						(effects
							(font
								(size 1.27 1.27)
							)
						)
					)
					(number "W2"
						(effects
							(font
								(size 1.27 1.27)
							)
						)
					)
				)
				(pin passive line
					(at 0 -19.05 0)
					(length 5.08)
					(hide yes)
					(name "GND"
						(effects
							(font
								(size 1.27 1.27)
							)
						)
					)
					(number "W20"
						(effects
							(font
								(size 1.27 1.27)
							)
						)
					)
				)
				(pin passive line
					(at 0 -19.05 0)
					(length 5.08)
					(hide yes)
					(name "GND"
						(effects
							(font
								(size 1.27 1.27)
							)
						)
					)
					(number "W30"
						(effects
							(font
								(size 1.27 1.27)
							)
						)
					)
				)
				(pin passive line
					(at 0 -19.05 0)
					(length 5.08)
					(hide yes)
					(name "GND"
						(effects
							(font
								(size 1.27 1.27)
							)
						)
					)
					(number "W6"
						(effects
							(font
								(size 1.27 1.27)
							)
						)
					)
				)
				(pin passive line
					(at 0 -19.05 0)
					(length 5.08)
					(hide yes)
					(name "GND"
						(effects
							(font
								(size 1.27 1.27)
							)
						)
					)
					(number "W9"
						(effects
							(font
								(size 1.27 1.27)
							)
						)
					)
				)
				(pin passive line
					(at 0 -19.05 0)
					(length 5.08)
					(hide yes)
					(name "GND"
						(effects
							(font
								(size 1.27 1.27)
							)
						)
					)
					(number "Y17"
						(effects
							(font
								(size 1.27 1.27)
							)
						)
					)
				)
				(pin passive line
					(at 0 -19.05 0)
					(length 5.08)
					(hide yes)
					(name "GND"
						(effects
							(font
								(size 1.27 1.27)
							)
						)
					)
					(number "Y27"
						(effects
							(font
								(size 1.27 1.27)
							)
						)
					)
				)
				(pin passive line
					(at 0 -19.05 0)
					(length 5.08)
					(hide yes)
					(name "GND"
						(effects
							(font
								(size 1.27 1.27)
							)
						)
					)
					(number "Y3"
						(effects
							(font
								(size 1.27 1.27)
							)
						)
					)
				)
				(pin passive line
					(at 0 -19.05 0)
					(length 5.08)
					(hide yes)
					(name "GND"
						(effects
							(font
								(size 1.27 1.27)
							)
						)
					)
					(number "Y4"
						(effects
							(font
								(size 1.27 1.27)
							)
						)
					)
				)
				(pin passive line
					(at 0 -19.05 0)
					(length 5.08)
					(hide yes)
					(name "GND"
						(effects
							(font
								(size 1.27 1.27)
							)
						)
					)
					(number "Y7"
						(effects
							(font
								(size 1.27 1.27)
							)
						)
					)
				)
				(pin passive line
					(at 0 -19.05 0)
					(length 5.08)
					(hide yes)
					(name "GND"
						(effects
							(font
								(size 1.27 1.27)
							)
						)
					)
					(number "Y8"
						(effects
							(font
								(size 1.27 1.27)
							)
						)
					)
				)
				(pin passive line
					(at 0 -19.05 0)
					(length 5.08)
					(hide yes)
					(name "GND"
						(effects
							(font
								(size 1.27 1.27)
							)
						)
					)
					(number "Y9"
						(effects
							(font
								(size 1.27 1.27)
							)
						)
					)
				)
			)
		)
	(symbol "antmicroFerriteBeadsandChips:FB_120Z_1.3A_Murata-BLM15PD_0402"
			(pin_numbers
				(hide yes)
			)
			(pin_names
				(hide yes)
			)
			(exclude_from_sim no)
			(in_bom yes)
			(on_board yes)
			(property "Reference" "FB"
				(at 13.97 0 0)
				(effects
					(font
						(size 1.27 1.27)
						(thickness 0.15)
					)
					(justify left bottom)
				)
			)
			(property "Value" "FB_120Z_1.3A_Murata-BLM15PD_0402"
				(at 13.97 -2.54 0)
				(effects
					(font
						(size 1.27 1.27)
						(thickness 0.15)
					)
					(justify left bottom)
					(hide yes)
				)
			)
			(property "Footprint" "antmicro-footprints:FB_0402_1005Metric"
				(at 13.97 -7.62 0)
				(effects
					(font
						(size 1.27 1.27)
						(thickness 0.15)
					)
					(justify left bottom)
					(hide yes)
				)
			)
			(property "Datasheet" "https://www.murata.com/en-us/products/productdata/8796740059166/ENFA0018.pdf"
				(at 13.97 -10.16 0)
				(effects
					(font
						(size 1.27 1.27)
						(thickness 0.15)
					)
					(justify left bottom)
					(hide yes)
				)
			)
			(property "Description" "Ferrite Bead, 0402 [1005 Metric], 120 ohm, 1.3 A, BLM15PD, 0.09 ohm, ± 25%, DC power line"
				(at 0 0 0)
				(effects
					(font
						(size 1.27 1.27)
					)
					(hide yes)
				)
			)
			(property "Val" "120Z/1.3A"
				(at 13.97 -5.08 0)
				(effects
					(font
						(size 1.27 1.27)
					)
					(justify left bottom)
				)
			)
			(property "MPN" "BLM15PD121SN1D"
				(at 13.97 -12.7 0)
				(effects
					(font
						(size 1.27 1.27)
						(thickness 0.15)
					)
					(justify left bottom)
					(hide yes)
				)
			)
			(property "Manufacturer" "Murata"
				(at 13.97 -15.24 0)
				(effects
					(font
						(size 1.27 1.27)
						(thickness 0.15)
					)
					(justify left bottom)
					(hide yes)
				)
			)
			(property "Current" ""
				(at 20.32 -22.86 0)
				(effects
					(font
						(size 1.27 1.27)
						(thickness 0.15)
					)
					(justify left bottom)
					(hide yes)
				)
			)
			(property "Author" "Antmicro"
				(at 13.97 -17.78 0)
				(effects
					(font
						(size 1.27 1.27)
						(thickness 0.15)
					)
					(justify left bottom)
					(hide yes)
				)
			)
			(property "License" "Apache-2.0"
				(at 13.97 -20.32 0)
				(effects
					(font
						(size 1.27 1.27)
						(thickness 0.15)
					)
					(justify left bottom)
					(hide yes)
				)
			)
			(property "ki_keywords" "0402, SMT, FERRITE BEAD, PASSIVE"
				(at 0 0 0)
				(effects
					(font
						(size 1.27 1.27)
					)
					(hide yes)
				)
			)
			(symbol "FB_120Z_1.3A_Murata-BLM15PD_0402_0_1"
				(polyline
					(pts
						(xy 1.651 0) (xy 1.2446 0)
					)
					(stroke
						(width 0)
						(type default)
					)
					(fill
						(type none)
					)
				)
				(polyline
					(pts
						(xy 2.2606 -1.8288) (xy 1.0414 -1.1176) (xy 2.7432 1.8288) (xy 3.9624 1.1176) (xy 2.2606 -1.8288)
					)
					(stroke
						(width 0)
						(type default)
					)
					(fill
						(type none)
					)
				)
				(polyline
					(pts
						(xy 3.81 0) (xy 3.3274 0)
					)
					(stroke
						(width 0)
						(type default)
					)
					(fill
						(type none)
					)
				)
			)
			(symbol "FB_120Z_1.3A_Murata-BLM15PD_0402_1_1"
				(pin passive line
					(at 0 0 0)
					(length 1.27)
					(name "~"
						(effects
							(font
								(size 1.27 1.27)
							)
						)
					)
					(number "1"
						(effects
							(font
								(size 1.27 1.27)
							)
						)
					)
				)
				(pin passive line
					(at 5.08 0 180)
					(length 1.27)
					(name "~"
						(effects
							(font
								(size 1.27 1.27)
							)
						)
					)
					(number "2"
						(effects
							(font
								(size 1.27 1.27)
							)
						)
					)
				)
			)
		)
	(symbol "antmicroFerriteBeadsandChips:FB_120Z_2A_Murata-BLM18PG_0603"
			(pin_numbers
				(hide yes)
			)
			(pin_names
				(hide yes)
			)
			(exclude_from_sim no)
			(in_bom yes)
			(on_board yes)
			(property "Reference" "FB"
				(at 15.24 0 0)
				(effects
					(font
						(size 1.27 1.27)
						(thickness 0.15)
					)
					(justify left bottom)
				)
			)
			(property "Value" "FB_120Z_2A_Murata-BLM18PG_0603"
				(at 15.24 -2.54 0)
				(effects
					(font
						(size 1.27 1.27)
						(thickness 0.15)
					)
					(justify left bottom)
					(hide yes)
				)
			)
			(property "Footprint" "antmicro-footprints:FB_0603_1608Metric"
				(at 15.24 -7.62 0)
				(effects
					(font
						(size 1.27 1.27)
						(thickness 0.15)
					)
					(justify left bottom)
					(hide yes)
				)
			)
			(property "Datasheet" "https://www.murata.com/en-us/products/productdata/8796738650142/ENFA0003.pdf"
				(at 15.24 -10.16 0)
				(effects
					(font
						(size 1.27 1.27)
						(thickness 0.15)
					)
					(justify left bottom)
					(hide yes)
				)
			)
			(property "Description" "Ferrite Bead, 0603 [1608 Metric], 120 ohm, 2 A, BLM18P, 0.05 ohm, ± 25%, DC power line"
				(at 0 0 0)
				(effects
					(font
						(size 1.27 1.27)
					)
					(hide yes)
				)
			)
			(property "Val" "120Z/2A"
				(at 15.24 -5.08 0)
				(effects
					(font
						(size 1.27 1.27)
					)
					(justify left bottom)
				)
			)
			(property "MPN" "BLM18PG121SN1D"
				(at 15.24 -12.7 0)
				(effects
					(font
						(size 1.27 1.27)
						(thickness 0.15)
					)
					(justify left bottom)
					(hide yes)
				)
			)
			(property "Manufacturer" "Murata"
				(at 15.24 -15.24 0)
				(effects
					(font
						(size 1.27 1.27)
						(thickness 0.15)
					)
					(justify left bottom)
					(hide yes)
				)
			)
			(property "Current" ""
				(at 20.32 -22.86 0)
				(effects
					(font
						(size 1.27 1.27)
						(thickness 0.15)
					)
					(justify left bottom)
					(hide yes)
				)
			)
			(property "Author" "Antmicro"
				(at 15.24 -17.78 0)
				(effects
					(font
						(size 1.27 1.27)
						(thickness 0.15)
					)
					(justify left bottom)
					(hide yes)
				)
			)
			(property "License" "Apache-2.0"
				(at 15.24 -20.32 0)
				(effects
					(font
						(size 1.27 1.27)
						(thickness 0.15)
					)
					(justify left bottom)
					(hide yes)
				)
			)
			(property "ki_keywords" "0603, SMT, FERRITE BEAD, PASSIVE"
				(at 0 0 0)
				(effects
					(font
						(size 1.27 1.27)
					)
					(hide yes)
				)
			)
			(symbol "FB_120Z_2A_Murata-BLM18PG_0603_0_1"
				(polyline
					(pts
						(xy 1.651 0) (xy 1.2446 0)
					)
					(stroke
						(width 0)
						(type default)
					)
					(fill
						(type none)
					)
				)
				(polyline
					(pts
						(xy 2.2606 -1.8288) (xy 1.0414 -1.1176) (xy 2.7432 1.8288) (xy 3.9624 1.1176) (xy 2.2606 -1.8288)
					)
					(stroke
						(width 0)
						(type default)
					)
					(fill
						(type none)
					)
				)
				(polyline
					(pts
						(xy 3.81 0) (xy 3.3274 0)
					)
					(stroke
						(width 0)
						(type default)
					)
					(fill
						(type none)
					)
				)
			)
			(symbol "FB_120Z_2A_Murata-BLM18PG_0603_1_1"
				(pin passive line
					(at 0 0 0)
					(length 1.27)
					(name "~"
						(effects
							(font
								(size 1.27 1.27)
							)
						)
					)
					(number "1"
						(effects
							(font
								(size 1.27 1.27)
							)
						)
					)
				)
				(pin passive line
					(at 5.08 0 180)
					(length 1.27)
					(name "~"
						(effects
							(font
								(size 1.27 1.27)
							)
						)
					)
					(number "2"
						(effects
							(font
								(size 1.27 1.27)
							)
						)
					)
				)
			)
		)
	(symbol "antmicroFerriteBeadsandChips:FB_220Z_2A_Murata-BLM21PG_0805"
			(pin_numbers
				(hide yes)
			)
			(pin_names
				(hide yes)
			)
			(exclude_from_sim no)
			(in_bom yes)
			(on_board yes)
			(property "Reference" "FB"
				(at 13.97 0 0)
				(effects
					(font
						(size 1.27 1.27)
						(thickness 0.15)
					)
					(justify left bottom)
				)
			)
			(property "Value" "FB_220Z_2A_Murata-BLM21PG_0805"
				(at 13.97 -2.54 0)
				(effects
					(font
						(size 1.27 1.27)
						(thickness 0.15)
					)
					(justify left bottom)
					(hide yes)
				)
			)
			(property "Footprint" "antmicro-footprints:FB_0805_2012Metric"
				(at 13.97 -7.62 0)
				(effects
					(font
						(size 1.27 1.27)
						(thickness 0.15)
					)
					(justify left bottom)
					(hide yes)
				)
			)
			(property "Datasheet" "https://www.murata.com/products/productdata/8796738977822/ENFA0005.pdf?1653276712000"
				(at 13.97 -10.16 0)
				(effects
					(font
						(size 1.27 1.27)
						(thickness 0.15)
					)
					(justify left bottom)
					(hide yes)
				)
			)
			(property "Description" "Ferrite Bead, 0805 [2012 Metric], 220 ohm, 2 A, BLM21, 0.045 ohm, ± 25%, DC power line"
				(at 0 0 0)
				(effects
					(font
						(size 1.27 1.27)
					)
					(hide yes)
				)
			)
			(property "Val" "220Z/2A"
				(at 13.97 -5.08 0)
				(effects
					(font
						(size 1.27 1.27)
					)
					(justify left bottom)
				)
			)
			(property "MPN" "BLM21PG221SN1D"
				(at 13.97 -12.7 0)
				(effects
					(font
						(size 1.27 1.27)
						(thickness 0.15)
					)
					(justify left bottom)
					(hide yes)
				)
			)
			(property "Manufacturer" "Murata"
				(at 13.97 -15.24 0)
				(effects
					(font
						(size 1.27 1.27)
						(thickness 0.15)
					)
					(justify left bottom)
					(hide yes)
				)
			)
			(property "Current" ""
				(at 20.32 -22.86 0)
				(effects
					(font
						(size 1.27 1.27)
						(thickness 0.15)
					)
					(justify left bottom)
					(hide yes)
				)
			)
			(property "Author" "Antmicro"
				(at 13.97 -17.78 0)
				(effects
					(font
						(size 1.27 1.27)
						(thickness 0.15)
					)
					(justify left bottom)
					(hide yes)
				)
			)
			(property "License" "Apache-2.0"
				(at 13.97 -20.32 0)
				(effects
					(font
						(size 1.27 1.27)
						(thickness 0.15)
					)
					(justify left bottom)
					(hide yes)
				)
			)
			(property "ki_keywords" "FERRITE BEAD, PASSIVE"
				(at 0 0 0)
				(effects
					(font
						(size 1.27 1.27)
					)
					(hide yes)
				)
			)
			(symbol "FB_220Z_2A_Murata-BLM21PG_0805_0_1"
				(polyline
					(pts
						(xy 1.651 0) (xy 1.2446 0)
					)
					(stroke
						(width 0)
						(type default)
					)
					(fill
						(type none)
					)
				)
				(polyline
					(pts
						(xy 2.2606 -1.8288) (xy 1.0414 -1.1176) (xy 2.7432 1.8288) (xy 3.9624 1.1176) (xy 2.2606 -1.8288)
					)
					(stroke
						(width 0)
						(type default)
					)
					(fill
						(type none)
					)
				)
				(polyline
					(pts
						(xy 3.81 0) (xy 3.3274 0)
					)
					(stroke
						(width 0)
						(type default)
					)
					(fill
						(type none)
					)
				)
			)
			(symbol "FB_220Z_2A_Murata-BLM21PG_0805_1_1"
				(pin passive line
					(at 0 0 0)
					(length 1.27)
					(name "~"
						(effects
							(font
								(size 1.27 1.27)
							)
						)
					)
					(number "1"
						(effects
							(font
								(size 1.27 1.27)
							)
						)
					)
				)
				(pin passive line
					(at 5.08 0 180)
					(length 1.27)
					(name "~"
						(effects
							(font
								(size 1.27 1.27)
							)
						)
					)
					(number "2"
						(effects
							(font
								(size 1.27 1.27)
							)
						)
					)
				)
			)
		)
	(symbol "antmicroFerriteBeadsandChips:FB_600Z_0.5A_Murata-BLM18AG_0603"
			(pin_numbers
				(hide yes)
			)
			(pin_names
				(hide yes)
			)
			(exclude_from_sim no)
			(in_bom yes)
			(on_board yes)
			(property "Reference" "FB"
				(at 15.24 0 0)
				(effects
					(font
						(size 1.27 1.27)
						(thickness 0.15)
					)
					(justify left bottom)
				)
			)
			(property "Value" "FB_600Z_0.5A_Murata-BLM18AG_0603"
				(at 15.24 -2.54 0)
				(effects
					(font
						(size 1.27 1.27)
						(thickness 0.15)
					)
					(justify left bottom)
					(hide yes)
				)
			)
			(property "Footprint" "antmicro-footprints:FB_0603_1608Metric"
				(at 15.24 -7.62 0)
				(effects
					(font
						(size 1.27 1.27)
						(thickness 0.15)
					)
					(justify left bottom)
					(hide yes)
				)
			)
			(property "Datasheet" "https://www.murata.com/en-us/products/productdata/8796738650142/ENFA0003.pdf"
				(at 15.24 -10.16 0)
				(effects
					(font
						(size 1.27 1.27)
						(thickness 0.15)
					)
					(justify left bottom)
					(hide yes)
				)
			)
			(property "Description" "Ferrite Bead, 0603 [1608 Metric], 600 ohm, 500 mA, BLM18A, 0.38 ohm, ± 25%, General use"
				(at 0 0 0)
				(effects
					(font
						(size 1.27 1.27)
					)
					(hide yes)
				)
			)
			(property "Val" "600Z/0.5A"
				(at 15.24 -5.08 0)
				(effects
					(font
						(size 1.27 1.27)
					)
					(justify left bottom)
				)
			)
			(property "MPN" "BLM18AG601SN1D"
				(at 15.24 -12.7 0)
				(effects
					(font
						(size 1.27 1.27)
						(thickness 0.15)
					)
					(justify left bottom)
					(hide yes)
				)
			)
			(property "Manufacturer" "Murata"
				(at 15.24 -15.24 0)
				(effects
					(font
						(size 1.27 1.27)
						(thickness 0.15)
					)
					(justify left bottom)
					(hide yes)
				)
			)
			(property "Current" ""
				(at 20.32 -22.86 0)
				(effects
					(font
						(size 1.27 1.27)
						(thickness 0.15)
					)
					(justify left bottom)
					(hide yes)
				)
			)
			(property "Author" "Antmicro"
				(at 15.24 -17.78 0)
				(effects
					(font
						(size 1.27 1.27)
						(thickness 0.15)
					)
					(justify left bottom)
					(hide yes)
				)
			)
			(property "License" "Apache-2.0"
				(at 15.24 -20.32 0)
				(effects
					(font
						(size 1.27 1.27)
						(thickness 0.15)
					)
					(justify left bottom)
					(hide yes)
				)
			)
			(property "ki_keywords" "0603, SMT, FERRITE BEAD, PASSIVE"
				(at 0 0 0)
				(effects
					(font
						(size 1.27 1.27)
					)
					(hide yes)
				)
			)
			(symbol "FB_600Z_0.5A_Murata-BLM18AG_0603_0_1"
				(polyline
					(pts
						(xy 1.651 0) (xy 1.2446 0)
					)
					(stroke
						(width 0)
						(type default)
					)
					(fill
						(type none)
					)
				)
				(polyline
					(pts
						(xy 2.2606 -1.8288) (xy 1.0414 -1.1176) (xy 2.7432 1.8288) (xy 3.9624 1.1176) (xy 2.2606 -1.8288)
					)
					(stroke
						(width 0)
						(type default)
					)
					(fill
						(type none)
					)
				)
				(polyline
					(pts
						(xy 3.81 0) (xy 3.3274 0)
					)
					(stroke
						(width 0)
						(type default)
					)
					(fill
						(type none)
					)
				)
			)
			(symbol "FB_600Z_0.5A_Murata-BLM18AG_0603_1_1"
				(pin passive line
					(at 0 0 0)
					(length 1.27)
					(name "~"
						(effects
							(font
								(size 1.27 1.27)
							)
						)
					)
					(number "1"
						(effects
							(font
								(size 1.27 1.27)
							)
						)
					)
				)
				(pin passive line
					(at 5.08 0 180)
					(length 1.27)
					(name "~"
						(effects
							(font
								(size 1.27 1.27)
							)
						)
					)
					(number "2"
						(effects
							(font
								(size 1.27 1.27)
							)
						)
					)
				)
			)
		)
	(symbol "antmicroFixedInductors:L_1u5_17A_Bourns-SRP6050CA"
			(pin_numbers
				(hide yes)
			)
			(pin_names
				(hide yes)
			)
			(exclude_from_sim no)
			(in_bom yes)
			(on_board yes)
			(property "Reference" "L"
				(at 13.97 0 0)
				(effects
					(font
						(size 1.27 1.27)
						(thickness 0.15)
					)
					(justify left bottom)
				)
			)
			(property "Value" "L_1u5_17A_Bourns-SRP6050CA"
				(at 13.97 -2.54 0)
				(effects
					(font
						(size 1.27 1.27)
						(thickness 0.15)
					)
					(justify left bottom)
					(hide yes)
				)
			)
			(property "Footprint" "antmicro-footprints:L_Bourns-SRP6050CA"
				(at 13.97 -7.62 0)
				(effects
					(font
						(size 1.27 1.27)
						(thickness 0.15)
					)
					(justify left bottom)
					(hide yes)
				)
			)
			(property "Datasheet" "https://www.bourns.com/docs/Product-Datasheets/SRP6050CA.pdf"
				(at 13.97 -10.16 0)
				(effects
					(font
						(size 1.27 1.27)
						(thickness 0.15)
					)
					(justify left bottom)
					(hide yes)
				)
			)
			(property "Description" "Power Inductor (SMT), 1.5 µH, 17 A, Shielded, 19.5 A, SRP6050CA"
				(at 0 0 0)
				(effects
					(font
						(size 1.27 1.27)
					)
					(hide yes)
				)
			)
			(property "Val" "1u5/17A"
				(at 13.97 -5.08 0)
				(effects
					(font
						(size 1.27 1.27)
						(thickness 0.15)
					)
					(justify left bottom)
				)
			)
			(property "Manufacturer" "Bourns"
				(at 13.97 -12.7 0)
				(effects
					(font
						(size 1.27 1.27)
						(thickness 0.15)
					)
					(justify left bottom)
					(hide yes)
				)
			)
			(property "MPN" "SRP6050CA-1R5M"
				(at 13.97 -15.24 0)
				(effects
					(font
						(size 1.27 1.27)
						(thickness 0.15)
					)
					(justify left bottom)
					(hide yes)
				)
			)
			(property "ISat" "19.5 A"
				(at 13.97 -16.51 0)
				(effects
					(font
						(size 1.27 1.27)
					)
					(justify left)
					(hide yes)
				)
			)
			(property "IMax" "17 A"
				(at 13.97 -20.32 0)
				(effects
					(font
						(size 1.27 1.27)
						(thickness 0.15)
					)
					(justify left bottom)
					(hide yes)
				)
			)
			(property "Size" "6.6x6.6"
				(at 13.97 -22.86 0)
				(effects
					(font
						(size 1.27 1.27)
						(thickness 0.15)
					)
					(justify left bottom)
					(hide yes)
				)
			)
			(property "Author" "Antmicro"
				(at 13.97 -25.4 0)
				(effects
					(font
						(size 1.27 1.27)
						(thickness 0.15)
					)
					(justify left bottom)
					(hide yes)
				)
			)
			(property "License" "Apache-2.0"
				(at 13.97 -27.94 0)
				(effects
					(font
						(size 1.27 1.27)
						(thickness 0.15)
					)
					(justify left bottom)
					(hide yes)
				)
			)
			(property "ki_keywords" "SMT, INDUCTOR, PASSIVE"
				(at 0 0 0)
				(effects
					(font
						(size 1.27 1.27)
					)
					(hide yes)
				)
			)
			(symbol "L_1u5_17A_Bourns-SRP6050CA_0_1"
				(arc
					(start 0.508 0)
					(mid 1.016 0.5058)
					(end 1.524 0)
					(stroke
						(width 0)
						(type default)
					)
					(fill
						(type none)
					)
				)
				(arc
					(start 1.524 0)
					(mid 2.032 0.5058)
					(end 2.54 0)
					(stroke
						(width 0)
						(type default)
					)
					(fill
						(type none)
					)
				)
				(arc
					(start 2.54 0)
					(mid 3.048 0.5058)
					(end 3.556 0)
					(stroke
						(width 0)
						(type default)
					)
					(fill
						(type none)
					)
				)
				(arc
					(start 3.556 0)
					(mid 4.064 0.5058)
					(end 4.572 0)
					(stroke
						(width 0)
						(type default)
					)
					(fill
						(type none)
					)
				)
			)
			(symbol "L_1u5_17A_Bourns-SRP6050CA_1_1"
				(pin passive line
					(at 0 0 0)
					(length 0.508)
					(name "~"
						(effects
							(font
								(size 1.27 1.27)
							)
						)
					)
					(number "1"
						(effects
							(font
								(size 1.27 1.27)
							)
						)
					)
				)
				(pin passive line
					(at 5.08 0 180)
					(length 0.508)
					(name "~"
						(effects
							(font
								(size 1.27 1.27)
							)
						)
					)
					(number "2"
						(effects
							(font
								(size 1.27 1.27)
							)
						)
					)
				)
			)
		)
	(symbol "antmicroFuses:F_10A_1206"
			(pin_numbers
				(hide yes)
			)
			(pin_names
				(offset 1.016)
				(hide yes)
			)
			(exclude_from_sim no)
			(in_bom yes)
			(on_board yes)
			(property "Reference" "F"
				(at 20.32 -5.08 0)
				(effects
					(font
						(size 1.27 1.27)
						(thickness 0.15)
					)
					(justify left bottom)
				)
			)
			(property "Value" "F_10A_1206"
				(at 20.32 -7.62 0)
				(effects
					(font
						(size 1.27 1.27)
						(thickness 0.15)
					)
					(justify left bottom)
					(hide yes)
				)
			)
			(property "Footprint" "antmicro-footprints:F_1206_3216Metric"
				(at 20.32 -10.16 0)
				(effects
					(font
						(size 1.27 1.27)
						(thickness 0.15)
					)
					(justify left bottom)
					(hide yes)
				)
			)
			(property "Datasheet" "https://us.schurter.com/pdf/english/typ_UST_1206.pdf"
				(at 20.32 -12.7 0)
				(effects
					(font
						(size 1.27 1.27)
						(thickness 0.15)
					)
					(justify left bottom)
					(hide yes)
				)
			)
			(property "Description" "Fuse, Surface Mount, 10 A, Slow Blow, 32 VAC, 63 VDC, 1206 (3216 Metric), UST 1206"
				(at 0 0 0)
				(effects
					(font
						(size 1.27 1.27)
					)
					(hide yes)
				)
			)
			(property "Manufacturer" "Schurter"
				(at 20.32 -15.24 0)
				(effects
					(font
						(size 1.27 1.27)
						(thickness 0.15)
					)
					(justify left bottom)
					(hide yes)
				)
			)
			(property "MPN" "3413.0328.22"
				(at 20.32 -17.78 0)
				(effects
					(font
						(size 1.27 1.27)
						(thickness 0.15)
					)
					(justify left bottom)
				)
			)
			(property "Author" "Antmicro"
				(at 20.32 -20.32 0)
				(effects
					(font
						(size 1.27 1.27)
						(thickness 0.15)
					)
					(justify left bottom)
					(hide yes)
				)
			)
			(property "License" "Apache-2.0"
				(at 20.32 -22.86 0)
				(effects
					(font
						(size 1.27 1.27)
						(thickness 0.15)
					)
					(justify left bottom)
					(hide yes)
				)
			)
			(property "ki_keywords" "FUSE, PASSIVE"
				(at 0 0 0)
				(effects
					(font
						(size 1.27 1.27)
					)
					(hide yes)
				)
			)
			(symbol "F_10A_1206_0_1"
				(rectangle
					(start 1.27 0.508)
					(end 3.81 -0.508)
					(stroke
						(width 0)
						(type default)
					)
					(fill
						(type none)
					)
				)
				(polyline
					(pts
						(xy 1.27 0) (xy 3.81 0)
					)
					(stroke
						(width 0)
						(type default)
					)
					(fill
						(type none)
					)
				)
			)
			(symbol "F_10A_1206_1_1"
				(pin passive line
					(at 0 0 0)
					(length 1.27)
					(name "~"
						(effects
							(font
								(size 1.27 1.27)
							)
						)
					)
					(number "1"
						(effects
							(font
								(size 1.27 1.27)
							)
						)
					)
				)
				(pin passive line
					(at 5.08 0 180)
					(length 1.27)
					(name "~"
						(effects
							(font
								(size 1.27 1.27)
							)
						)
					)
					(number "2"
						(effects
							(font
								(size 1.27 1.27)
							)
						)
					)
				)
			)
		)
	(symbol "antmicroGenericPinHeaders:PinHeader_2x10_P1.27mm_SMD_Shrouded"
			(exclude_from_sim no)
			(in_bom yes)
			(on_board yes)
			(property "Reference" "J"
				(at 18.415 -3.175 0)
				(effects
					(font
						(size 1.27 1.27)
						(thickness 0.15)
					)
					(justify left bottom)
				)
			)
			(property "Value" "PinHeader_2x10_P1.27mm_SMD_Shrouded"
				(at 18.415 -5.715 0)
				(effects
					(font
						(size 1.27 1.27)
						(thickness 0.15)
					)
					(justify left bottom)
				)
			)
			(property "Footprint" "antmicro-footprints:PinHeader_2x10_P1.27mm_SMD_Shrouded"
				(at 18.415 -8.255 0)
				(effects
					(font
						(size 1.27 1.27)
						(thickness 0.15)
					)
					(justify left bottom)
					(hide yes)
				)
			)
			(property "Datasheet" "https://www.we-online.com/catalog/datasheet/62732020621.pdf"
				(at 18.415 -10.795 0)
				(effects
					(font
						(size 1.27 1.27)
						(thickness 0.15)
					)
					(justify left bottom)
					(hide yes)
				)
			)
			(property "Description" "Pin Header, Wire-to-Board, 1.27 mm, 2 Rows, 20 Contacts, Surface Mount Straight, WR-BHD"
				(at 0 0 0)
				(effects
					(font
						(size 1.27 1.27)
					)
					(hide yes)
				)
			)
			(property "MPN" "62732020621"
				(at 18.415 -13.335 0)
				(effects
					(font
						(size 1.27 1.27)
						(thickness 0.15)
					)
					(justify left bottom)
					(hide yes)
				)
			)
			(property "Manufacturer" "Würth Elektronik"
				(at 18.415 -15.875 0)
				(effects
					(font
						(size 1.27 1.27)
						(thickness 0.15)
					)
					(justify left bottom)
					(hide yes)
				)
			)
			(property "Author" "Antmicro"
				(at 18.415 -18.415 0)
				(effects
					(font
						(size 1.27 1.27)
						(thickness 0.15)
					)
					(justify left bottom)
					(hide yes)
				)
			)
			(property "License" "Apache-2.0"
				(at 18.415 -20.955 0)
				(effects
					(font
						(size 1.27 1.27)
						(thickness 0.15)
					)
					(justify left bottom)
					(hide yes)
				)
			)
			(property "ki_keywords" "PINSTRIP, HEADER, SMT"
				(at 0 0 0)
				(effects
					(font
						(size 1.27 1.27)
					)
					(hide yes)
				)
			)
			(symbol "PinHeader_2x10_P1.27mm_SMD_Shrouded_1_1"
				(rectangle
					(start 1.905 -5.08)
					(end 1.905 -5.08)
					(stroke
						(width 0.254)
						(type default)
					)
					(fill
						(type background)
					)
				)
				(rectangle
					(start 2.54 1.27)
					(end 7.62 -24.13)
					(stroke
						(width 0.254)
						(type default)
					)
					(fill
						(type background)
					)
				)
				(rectangle
					(start 3.81 -2.54)
					(end 3.81 -2.54)
					(stroke
						(width 0.254)
						(type default)
					)
					(fill
						(type background)
					)
				)
				(rectangle
					(start 4.191 -0.254)
					(end 3.683 0.254)
					(stroke
						(width 0.254)
						(type default)
					)
					(fill
						(type background)
					)
				)
				(rectangle
					(start 4.191 -2.794)
					(end 3.683 -2.286)
					(stroke
						(width 0.254)
						(type default)
					)
					(fill
						(type background)
					)
				)
				(rectangle
					(start 4.191 -5.334)
					(end 3.683 -4.826)
					(stroke
						(width 0.254)
						(type default)
					)
					(fill
						(type background)
					)
				)
				(rectangle
					(start 4.191 -7.874)
					(end 3.683 -7.366)
					(stroke
						(width 0.254)
						(type default)
					)
					(fill
						(type background)
					)
				)
				(rectangle
					(start 4.191 -10.414)
					(end 3.683 -9.906)
					(stroke
						(width 0.254)
						(type default)
					)
					(fill
						(type background)
					)
				)
				(rectangle
					(start 4.191 -12.954)
					(end 3.683 -12.446)
					(stroke
						(width 0.254)
						(type default)
					)
					(fill
						(type background)
					)
				)
				(rectangle
					(start 4.191 -15.494)
					(end 3.683 -14.986)
					(stroke
						(width 0.254)
						(type default)
					)
					(fill
						(type background)
					)
				)
				(rectangle
					(start 4.191 -18.034)
					(end 3.683 -17.526)
					(stroke
						(width 0.254)
						(type default)
					)
					(fill
						(type background)
					)
				)
				(rectangle
					(start 4.191 -20.574)
					(end 3.683 -20.066)
					(stroke
						(width 0.254)
						(type default)
					)
					(fill
						(type background)
					)
				)
				(rectangle
					(start 4.191 -23.114)
					(end 3.683 -22.606)
					(stroke
						(width 0.254)
						(type default)
					)
					(fill
						(type background)
					)
				)
				(rectangle
					(start 6.7056 -23.114)
					(end 6.1976 -22.606)
					(stroke
						(width 0.254)
						(type default)
					)
					(fill
						(type background)
					)
				)
				(rectangle
					(start 6.731 -0.254)
					(end 6.223 0.254)
					(stroke
						(width 0.254)
						(type default)
					)
					(fill
						(type background)
					)
				)
				(rectangle
					(start 6.731 -2.794)
					(end 6.223 -2.286)
					(stroke
						(width 0.254)
						(type default)
					)
					(fill
						(type background)
					)
				)
				(rectangle
					(start 6.731 -5.334)
					(end 6.223 -4.826)
					(stroke
						(width 0.254)
						(type default)
					)
					(fill
						(type background)
					)
				)
				(rectangle
					(start 6.731 -7.874)
					(end 6.223 -7.366)
					(stroke
						(width 0.254)
						(type default)
					)
					(fill
						(type background)
					)
				)
				(rectangle
					(start 6.731 -10.414)
					(end 6.223 -9.906)
					(stroke
						(width 0.254)
						(type default)
					)
					(fill
						(type background)
					)
				)
				(rectangle
					(start 6.731 -12.954)
					(end 6.223 -12.446)
					(stroke
						(width 0.254)
						(type default)
					)
					(fill
						(type background)
					)
				)
				(rectangle
					(start 6.731 -15.494)
					(end 6.223 -14.986)
					(stroke
						(width 0.254)
						(type default)
					)
					(fill
						(type background)
					)
				)
				(rectangle
					(start 6.731 -18.034)
					(end 6.223 -17.526)
					(stroke
						(width 0.254)
						(type default)
					)
					(fill
						(type background)
					)
				)
				(rectangle
					(start 6.731 -20.574)
					(end 6.223 -20.066)
					(stroke
						(width 0.254)
						(type default)
					)
					(fill
						(type background)
					)
				)
				(pin passive line
					(at 0 0 0)
					(length 2.54)
					(name "~"
						(effects
							(font
								(size 1.27 1.27)
							)
						)
					)
					(number "1"
						(effects
							(font
								(size 1.27 1.27)
							)
						)
					)
				)
				(pin passive line
					(at 0 -2.54 0)
					(length 2.54)
					(name "~"
						(effects
							(font
								(size 1.27 1.27)
							)
						)
					)
					(number "3"
						(effects
							(font
								(size 1.27 1.27)
							)
						)
					)
				)
				(pin passive line
					(at 0 -5.08 0)
					(length 2.54)
					(name "~"
						(effects
							(font
								(size 1.27 1.27)
							)
						)
					)
					(number "5"
						(effects
							(font
								(size 1.27 1.27)
							)
						)
					)
				)
				(pin passive line
					(at 0 -7.62 0)
					(length 2.54)
					(name "~"
						(effects
							(font
								(size 1.27 1.27)
							)
						)
					)
					(number "7"
						(effects
							(font
								(size 1.27 1.27)
							)
						)
					)
				)
				(pin passive line
					(at 0 -10.16 0)
					(length 2.54)
					(name "~"
						(effects
							(font
								(size 1.27 1.27)
							)
						)
					)
					(number "9"
						(effects
							(font
								(size 1.27 1.27)
							)
						)
					)
				)
				(pin passive line
					(at 0 -12.7 0)
					(length 2.54)
					(name "~"
						(effects
							(font
								(size 1.27 1.27)
							)
						)
					)
					(number "11"
						(effects
							(font
								(size 1.27 1.27)
							)
						)
					)
				)
				(pin passive line
					(at 0 -15.24 0)
					(length 2.54)
					(name "~"
						(effects
							(font
								(size 1.27 1.27)
							)
						)
					)
					(number "13"
						(effects
							(font
								(size 1.27 1.27)
							)
						)
					)
				)
				(pin passive line
					(at 0 -17.78 0)
					(length 2.54)
					(name "~"
						(effects
							(font
								(size 1.27 1.27)
							)
						)
					)
					(number "15"
						(effects
							(font
								(size 1.27 1.27)
							)
						)
					)
				)
				(pin passive line
					(at 0 -20.32 0)
					(length 2.54)
					(name "~"
						(effects
							(font
								(size 1.27 1.27)
							)
						)
					)
					(number "17"
						(effects
							(font
								(size 1.27 1.27)
							)
						)
					)
				)
				(pin passive line
					(at 0 -22.86 0)
					(length 2.54)
					(name "~"
						(effects
							(font
								(size 1.27 1.27)
							)
						)
					)
					(number "19"
						(effects
							(font
								(size 1.27 1.27)
							)
						)
					)
				)
				(pin passive line
					(at 10.16 0 180)
					(length 2.54)
					(name "~"
						(effects
							(font
								(size 1.27 1.27)
							)
						)
					)
					(number "2"
						(effects
							(font
								(size 1.27 1.27)
							)
						)
					)
				)
				(pin passive line
					(at 10.16 -2.54 180)
					(length 2.54)
					(name "~"
						(effects
							(font
								(size 1.27 1.27)
							)
						)
					)
					(number "4"
						(effects
							(font
								(size 1.27 1.27)
							)
						)
					)
				)
				(pin passive line
					(at 10.16 -5.08 180)
					(length 2.54)
					(name "~"
						(effects
							(font
								(size 1.27 1.27)
							)
						)
					)
					(number "6"
						(effects
							(font
								(size 1.27 1.27)
							)
						)
					)
				)
				(pin passive line
					(at 10.16 -7.62 180)
					(length 2.54)
					(name "~"
						(effects
							(font
								(size 1.27 1.27)
							)
						)
					)
					(number "8"
						(effects
							(font
								(size 1.27 1.27)
							)
						)
					)
				)
				(pin passive line
					(at 10.16 -10.16 180)
					(length 2.54)
					(name "~"
						(effects
							(font
								(size 1.27 1.27)
							)
						)
					)
					(number "10"
						(effects
							(font
								(size 1.27 1.27)
							)
						)
					)
				)
				(pin passive line
					(at 10.16 -12.7 180)
					(length 2.54)
					(name "~"
						(effects
							(font
								(size 1.27 1.27)
							)
						)
					)
					(number "12"
						(effects
							(font
								(size 1.27 1.27)
							)
						)
					)
				)
				(pin passive line
					(at 10.16 -15.24 180)
					(length 2.54)
					(name "~"
						(effects
							(font
								(size 1.27 1.27)
							)
						)
					)
					(number "14"
						(effects
							(font
								(size 1.27 1.27)
							)
						)
					)
				)
				(pin passive line
					(at 10.16 -17.78 180)
					(length 2.54)
					(name "~"
						(effects
							(font
								(size 1.27 1.27)
							)
						)
					)
					(number "16"
						(effects
							(font
								(size 1.27 1.27)
							)
						)
					)
				)
				(pin passive line
					(at 10.16 -20.32 180)
					(length 2.54)
					(name "~"
						(effects
							(font
								(size 1.27 1.27)
							)
						)
					)
					(number "18"
						(effects
							(font
								(size 1.27 1.27)
							)
						)
					)
				)
				(pin passive line
					(at 10.16 -22.86 180)
					(length 2.54)
					(name "~"
						(effects
							(font
								(size 1.27 1.27)
							)
						)
					)
					(number "20"
						(effects
							(font
								(size 1.27 1.27)
							)
						)
					)
				)
			)
		)
	(symbol "antmicroGenericPinHeaders:PinHeader_2x17_P1.27mm_SMD_Shrouded"
			(exclude_from_sim no)
			(in_bom yes)
			(on_board yes)
			(property "Reference" "J"
				(at 25.4 -6.35 0)
				(effects
					(font
						(size 1.27 1.27)
						(thickness 0.15)
					)
					(justify left bottom)
				)
			)
			(property "Value" "PinHeader_2x17_P1.27mm_SMD_Shrouded"
				(at 25.4 -8.89 0)
				(effects
					(font
						(size 1.27 1.27)
						(thickness 0.15)
					)
					(justify left bottom)
				)
			)
			(property "Footprint" "antmicro-footprints:PinHeader_2x17_P1.27mm_SMD_Shrouded"
				(at 25.4 -11.43 0)
				(effects
					(font
						(size 1.27 1.27)
						(thickness 0.15)
					)
					(justify left bottom)
					(hide yes)
				)
			)
			(property "Datasheet" "https://www.we-online.com/catalog/datasheet/62703420621.pdf"
				(at 25.4 -13.97 0)
				(effects
					(font
						(size 1.27 1.27)
						(thickness 0.15)
					)
					(justify left bottom)
					(hide yes)
				)
			)
			(property "Description" "Pin Header, Wire-to-Board, 1.27 mm, 2 Rows, 34 Contacts, Surface Mount Straight, WR-BHD Series"
				(at 0 0 0)
				(effects
					(font
						(size 1.27 1.27)
					)
					(hide yes)
				)
			)
			(property "MPN" "62703420621"
				(at 25.4 -16.51 0)
				(effects
					(font
						(size 1.27 1.27)
						(thickness 0.15)
					)
					(justify left bottom)
					(hide yes)
				)
			)
			(property "Manufacturer" "Würth Elektronik"
				(at 25.4 -19.05 0)
				(effects
					(font
						(size 1.27 1.27)
						(thickness 0.15)
					)
					(justify left bottom)
					(hide yes)
				)
			)
			(property "Author" "Antmicro"
				(at 25.4 -21.59 0)
				(effects
					(font
						(size 1.27 1.27)
						(thickness 0.15)
					)
					(justify left bottom)
					(hide yes)
				)
			)
			(property "License" "Apache-2.0"
				(at 25.4 -24.13 0)
				(effects
					(font
						(size 1.27 1.27)
						(thickness 0.15)
					)
					(justify left bottom)
					(hide yes)
				)
			)
			(property "ki_keywords" "PINSTRIP, HEADER, SMT"
				(at 0 0 0)
				(effects
					(font
						(size 1.27 1.27)
					)
					(hide yes)
				)
			)
			(symbol "PinHeader_2x17_P1.27mm_SMD_Shrouded_1_1"
				(rectangle
					(start 1.905 -5.08)
					(end 1.905 -5.08)
					(stroke
						(width 0.254)
						(type default)
					)
					(fill
						(type background)
					)
				)
				(rectangle
					(start 2.54 1.27)
					(end 7.62 -41.91)
					(stroke
						(width 0.254)
						(type default)
					)
					(fill
						(type background)
					)
				)
				(rectangle
					(start 3.81 -2.54)
					(end 3.81 -2.54)
					(stroke
						(width 0.254)
						(type default)
					)
					(fill
						(type background)
					)
				)
				(rectangle
					(start 3.81 -40.64)
					(end 3.81 -40.64)
					(stroke
						(width 0.254)
						(type default)
					)
					(fill
						(type background)
					)
				)
				(rectangle
					(start 4.1656 -25.654)
					(end 3.6576 -25.146)
					(stroke
						(width 0.254)
						(type default)
					)
					(fill
						(type background)
					)
				)
				(rectangle
					(start 4.1656 -28.194)
					(end 3.6576 -27.686)
					(stroke
						(width 0.254)
						(type default)
					)
					(fill
						(type background)
					)
				)
				(rectangle
					(start 4.1656 -30.734)
					(end 3.6576 -30.226)
					(stroke
						(width 0.254)
						(type default)
					)
					(fill
						(type background)
					)
				)
				(rectangle
					(start 4.1656 -33.274)
					(end 3.6576 -32.766)
					(stroke
						(width 0.254)
						(type default)
					)
					(fill
						(type background)
					)
				)
				(rectangle
					(start 4.1656 -35.814)
					(end 3.6576 -35.306)
					(stroke
						(width 0.254)
						(type default)
					)
					(fill
						(type background)
					)
				)
				(rectangle
					(start 4.191 -0.254)
					(end 3.683 0.254)
					(stroke
						(width 0.254)
						(type default)
					)
					(fill
						(type background)
					)
				)
				(rectangle
					(start 4.191 -2.794)
					(end 3.683 -2.286)
					(stroke
						(width 0.254)
						(type default)
					)
					(fill
						(type background)
					)
				)
				(rectangle
					(start 4.191 -5.334)
					(end 3.683 -4.826)
					(stroke
						(width 0.254)
						(type default)
					)
					(fill
						(type background)
					)
				)
				(rectangle
					(start 4.191 -7.874)
					(end 3.683 -7.366)
					(stroke
						(width 0.254)
						(type default)
					)
					(fill
						(type background)
					)
				)
				(rectangle
					(start 4.191 -10.414)
					(end 3.683 -9.906)
					(stroke
						(width 0.254)
						(type default)
					)
					(fill
						(type background)
					)
				)
				(rectangle
					(start 4.191 -12.954)
					(end 3.683 -12.446)
					(stroke
						(width 0.254)
						(type default)
					)
					(fill
						(type background)
					)
				)
				(rectangle
					(start 4.191 -15.494)
					(end 3.683 -14.986)
					(stroke
						(width 0.254)
						(type default)
					)
					(fill
						(type background)
					)
				)
				(rectangle
					(start 4.191 -18.034)
					(end 3.683 -17.526)
					(stroke
						(width 0.254)
						(type default)
					)
					(fill
						(type background)
					)
				)
				(rectangle
					(start 4.191 -20.574)
					(end 3.683 -20.066)
					(stroke
						(width 0.254)
						(type default)
					)
					(fill
						(type background)
					)
				)
				(rectangle
					(start 4.191 -23.114)
					(end 3.683 -22.606)
					(stroke
						(width 0.254)
						(type default)
					)
					(fill
						(type background)
					)
				)
				(rectangle
					(start 4.191 -38.354)
					(end 3.683 -37.846)
					(stroke
						(width 0.254)
						(type default)
					)
					(fill
						(type background)
					)
				)
				(rectangle
					(start 4.191 -40.894)
					(end 3.683 -40.386)
					(stroke
						(width 0.254)
						(type default)
					)
					(fill
						(type background)
					)
				)
				(rectangle
					(start 6.7056 -23.114)
					(end 6.1976 -22.606)
					(stroke
						(width 0.254)
						(type default)
					)
					(fill
						(type background)
					)
				)
				(rectangle
					(start 6.7056 -25.654)
					(end 6.1976 -25.146)
					(stroke
						(width 0.254)
						(type default)
					)
					(fill
						(type background)
					)
				)
				(rectangle
					(start 6.7056 -28.194)
					(end 6.1976 -27.686)
					(stroke
						(width 0.254)
						(type default)
					)
					(fill
						(type background)
					)
				)
				(rectangle
					(start 6.7056 -30.734)
					(end 6.1976 -30.226)
					(stroke
						(width 0.254)
						(type default)
					)
					(fill
						(type background)
					)
				)
				(rectangle
					(start 6.7056 -33.274)
					(end 6.1976 -32.766)
					(stroke
						(width 0.254)
						(type default)
					)
					(fill
						(type background)
					)
				)
				(rectangle
					(start 6.7056 -35.814)
					(end 6.1976 -35.306)
					(stroke
						(width 0.254)
						(type default)
					)
					(fill
						(type background)
					)
				)
				(rectangle
					(start 6.731 -0.254)
					(end 6.223 0.254)
					(stroke
						(width 0.254)
						(type default)
					)
					(fill
						(type background)
					)
				)
				(rectangle
					(start 6.731 -2.794)
					(end 6.223 -2.286)
					(stroke
						(width 0.254)
						(type default)
					)
					(fill
						(type background)
					)
				)
				(rectangle
					(start 6.731 -5.334)
					(end 6.223 -4.826)
					(stroke
						(width 0.254)
						(type default)
					)
					(fill
						(type background)
					)
				)
				(rectangle
					(start 6.731 -7.874)
					(end 6.223 -7.366)
					(stroke
						(width 0.254)
						(type default)
					)
					(fill
						(type background)
					)
				)
				(rectangle
					(start 6.731 -10.414)
					(end 6.223 -9.906)
					(stroke
						(width 0.254)
						(type default)
					)
					(fill
						(type background)
					)
				)
				(rectangle
					(start 6.731 -12.954)
					(end 6.223 -12.446)
					(stroke
						(width 0.254)
						(type default)
					)
					(fill
						(type background)
					)
				)
				(rectangle
					(start 6.731 -15.494)
					(end 6.223 -14.986)
					(stroke
						(width 0.254)
						(type default)
					)
					(fill
						(type background)
					)
				)
				(rectangle
					(start 6.731 -18.034)
					(end 6.223 -17.526)
					(stroke
						(width 0.254)
						(type default)
					)
					(fill
						(type background)
					)
				)
				(rectangle
					(start 6.731 -20.574)
					(end 6.223 -20.066)
					(stroke
						(width 0.254)
						(type default)
					)
					(fill
						(type background)
					)
				)
				(rectangle
					(start 6.731 -38.354)
					(end 6.223 -37.846)
					(stroke
						(width 0.254)
						(type default)
					)
					(fill
						(type background)
					)
				)
				(rectangle
					(start 6.731 -40.894)
					(end 6.223 -40.386)
					(stroke
						(width 0.254)
						(type default)
					)
					(fill
						(type background)
					)
				)
				(pin passive line
					(at 0 0 0)
					(length 2.54)
					(name "~"
						(effects
							(font
								(size 1.27 1.27)
							)
						)
					)
					(number "1"
						(effects
							(font
								(size 1.27 1.27)
							)
						)
					)
				)
				(pin passive line
					(at 0 -2.54 0)
					(length 2.54)
					(name "~"
						(effects
							(font
								(size 1.27 1.27)
							)
						)
					)
					(number "3"
						(effects
							(font
								(size 1.27 1.27)
							)
						)
					)
				)
				(pin passive line
					(at 0 -5.08 0)
					(length 2.54)
					(name "~"
						(effects
							(font
								(size 1.27 1.27)
							)
						)
					)
					(number "5"
						(effects
							(font
								(size 1.27 1.27)
							)
						)
					)
				)
				(pin passive line
					(at 0 -7.62 0)
					(length 2.54)
					(name "~"
						(effects
							(font
								(size 1.27 1.27)
							)
						)
					)
					(number "7"
						(effects
							(font
								(size 1.27 1.27)
							)
						)
					)
				)
				(pin passive line
					(at 0 -10.16 0)
					(length 2.54)
					(name "~"
						(effects
							(font
								(size 1.27 1.27)
							)
						)
					)
					(number "9"
						(effects
							(font
								(size 1.27 1.27)
							)
						)
					)
				)
				(pin passive line
					(at 0 -12.7 0)
					(length 2.54)
					(name "~"
						(effects
							(font
								(size 1.27 1.27)
							)
						)
					)
					(number "11"
						(effects
							(font
								(size 1.27 1.27)
							)
						)
					)
				)
				(pin passive line
					(at 0 -15.24 0)
					(length 2.54)
					(name "~"
						(effects
							(font
								(size 1.27 1.27)
							)
						)
					)
					(number "13"
						(effects
							(font
								(size 1.27 1.27)
							)
						)
					)
				)
				(pin passive line
					(at 0 -17.78 0)
					(length 2.54)
					(name "~"
						(effects
							(font
								(size 1.27 1.27)
							)
						)
					)
					(number "15"
						(effects
							(font
								(size 1.27 1.27)
							)
						)
					)
				)
				(pin passive line
					(at 0 -20.32 0)
					(length 2.54)
					(name "~"
						(effects
							(font
								(size 1.27 1.27)
							)
						)
					)
					(number "17"
						(effects
							(font
								(size 1.27 1.27)
							)
						)
					)
				)
				(pin passive line
					(at 0 -22.86 0)
					(length 2.54)
					(name "~"
						(effects
							(font
								(size 1.27 1.27)
							)
						)
					)
					(number "19"
						(effects
							(font
								(size 1.27 1.27)
							)
						)
					)
				)
				(pin passive line
					(at 0 -25.4 0)
					(length 2.54)
					(name "~"
						(effects
							(font
								(size 1.27 1.27)
							)
						)
					)
					(number "21"
						(effects
							(font
								(size 1.27 1.27)
							)
						)
					)
				)
				(pin passive line
					(at 0 -27.94 0)
					(length 2.54)
					(name "~"
						(effects
							(font
								(size 1.27 1.27)
							)
						)
					)
					(number "23"
						(effects
							(font
								(size 1.27 1.27)
							)
						)
					)
				)
				(pin passive line
					(at 0 -30.48 0)
					(length 2.54)
					(name "~"
						(effects
							(font
								(size 1.27 1.27)
							)
						)
					)
					(number "25"
						(effects
							(font
								(size 1.27 1.27)
							)
						)
					)
				)
				(pin passive line
					(at 0 -33.02 0)
					(length 2.54)
					(name "~"
						(effects
							(font
								(size 1.27 1.27)
							)
						)
					)
					(number "27"
						(effects
							(font
								(size 1.27 1.27)
							)
						)
					)
				)
				(pin passive line
					(at 0 -35.56 0)
					(length 2.54)
					(name "~"
						(effects
							(font
								(size 1.27 1.27)
							)
						)
					)
					(number "29"
						(effects
							(font
								(size 1.27 1.27)
							)
						)
					)
				)
				(pin passive line
					(at 0 -38.1 0)
					(length 2.54)
					(name "~"
						(effects
							(font
								(size 1.27 1.27)
							)
						)
					)
					(number "31"
						(effects
							(font
								(size 1.27 1.27)
							)
						)
					)
				)
				(pin passive line
					(at 0 -40.64 0)
					(length 2.54)
					(name "~"
						(effects
							(font
								(size 1.27 1.27)
							)
						)
					)
					(number "33"
						(effects
							(font
								(size 1.27 1.27)
							)
						)
					)
				)
				(pin passive line
					(at 10.16 0 180)
					(length 2.54)
					(name "~"
						(effects
							(font
								(size 1.27 1.27)
							)
						)
					)
					(number "2"
						(effects
							(font
								(size 1.27 1.27)
							)
						)
					)
				)
				(pin passive line
					(at 10.16 -2.54 180)
					(length 2.54)
					(name "~"
						(effects
							(font
								(size 1.27 1.27)
							)
						)
					)
					(number "4"
						(effects
							(font
								(size 1.27 1.27)
							)
						)
					)
				)
				(pin passive line
					(at 10.16 -5.08 180)
					(length 2.54)
					(name "~"
						(effects
							(font
								(size 1.27 1.27)
							)
						)
					)
					(number "6"
						(effects
							(font
								(size 1.27 1.27)
							)
						)
					)
				)
				(pin passive line
					(at 10.16 -7.62 180)
					(length 2.54)
					(name "~"
						(effects
							(font
								(size 1.27 1.27)
							)
						)
					)
					(number "8"
						(effects
							(font
								(size 1.27 1.27)
							)
						)
					)
				)
				(pin passive line
					(at 10.16 -10.16 180)
					(length 2.54)
					(name "~"
						(effects
							(font
								(size 1.27 1.27)
							)
						)
					)
					(number "10"
						(effects
							(font
								(size 1.27 1.27)
							)
						)
					)
				)
				(pin passive line
					(at 10.16 -12.7 180)
					(length 2.54)
					(name "~"
						(effects
							(font
								(size 1.27 1.27)
							)
						)
					)
					(number "12"
						(effects
							(font
								(size 1.27 1.27)
							)
						)
					)
				)
				(pin passive line
					(at 10.16 -15.24 180)
					(length 2.54)
					(name "~"
						(effects
							(font
								(size 1.27 1.27)
							)
						)
					)
					(number "14"
						(effects
							(font
								(size 1.27 1.27)
							)
						)
					)
				)
				(pin passive line
					(at 10.16 -17.78 180)
					(length 2.54)
					(name "~"
						(effects
							(font
								(size 1.27 1.27)
							)
						)
					)
					(number "16"
						(effects
							(font
								(size 1.27 1.27)
							)
						)
					)
				)
				(pin passive line
					(at 10.16 -20.32 180)
					(length 2.54)
					(name "~"
						(effects
							(font
								(size 1.27 1.27)
							)
						)
					)
					(number "18"
						(effects
							(font
								(size 1.27 1.27)
							)
						)
					)
				)
				(pin passive line
					(at 10.16 -22.86 180)
					(length 2.54)
					(name "~"
						(effects
							(font
								(size 1.27 1.27)
							)
						)
					)
					(number "20"
						(effects
							(font
								(size 1.27 1.27)
							)
						)
					)
				)
				(pin passive line
					(at 10.16 -25.4 180)
					(length 2.54)
					(name "~"
						(effects
							(font
								(size 1.27 1.27)
							)
						)
					)
					(number "22"
						(effects
							(font
								(size 1.27 1.27)
							)
						)
					)
				)
				(pin passive line
					(at 10.16 -27.94 180)
					(length 2.54)
					(name "~"
						(effects
							(font
								(size 1.27 1.27)
							)
						)
					)
					(number "24"
						(effects
							(font
								(size 1.27 1.27)
							)
						)
					)
				)
				(pin passive line
					(at 10.16 -30.48 180)
					(length 2.54)
					(name "~"
						(effects
							(font
								(size 1.27 1.27)
							)
						)
					)
					(number "26"
						(effects
							(font
								(size 1.27 1.27)
							)
						)
					)
				)
				(pin passive line
					(at 10.16 -33.02 180)
					(length 2.54)
					(name "~"
						(effects
							(font
								(size 1.27 1.27)
							)
						)
					)
					(number "28"
						(effects
							(font
								(size 1.27 1.27)
							)
						)
					)
				)
				(pin passive line
					(at 10.16 -35.56 180)
					(length 2.54)
					(name "~"
						(effects
							(font
								(size 1.27 1.27)
							)
						)
					)
					(number "30"
						(effects
							(font
								(size 1.27 1.27)
							)
						)
					)
				)
				(pin passive line
					(at 10.16 -38.1 180)
					(length 2.54)
					(name "~"
						(effects
							(font
								(size 1.27 1.27)
							)
						)
					)
					(number "32"
						(effects
							(font
								(size 1.27 1.27)
							)
						)
					)
				)
				(pin passive line
					(at 10.16 -40.64 180)
					(length 2.54)
					(name "~"
						(effects
							(font
								(size 1.27 1.27)
							)
						)
					)
					(number "34"
						(effects
							(font
								(size 1.27 1.27)
							)
						)
					)
				)
			)
		)
	(symbol "antmicroGenericPinHeaders:PinHeader_2x20_P1.27mm_SMD_Shrouded"
			(exclude_from_sim no)
			(in_bom yes)
			(on_board yes)
			(property "Reference" "J"
				(at 25.4 -6.35 0)
				(effects
					(font
						(size 1.27 1.27)
						(thickness 0.15)
					)
					(justify left bottom)
				)
			)
			(property "Value" "PinHeader_2x20_P1.27mm_SMD_Shrouded"
				(at 25.4 -8.89 0)
				(effects
					(font
						(size 1.27 1.27)
						(thickness 0.15)
					)
					(justify left bottom)
				)
			)
			(property "Footprint" "antmicro-footprints:PinHeader_2x20_P1.27mm_SMD_Shrouded"
				(at 25.4 -11.43 0)
				(effects
					(font
						(size 1.27 1.27)
						(thickness 0.15)
					)
					(justify left bottom)
					(hide yes)
				)
			)
			(property "Datasheet" "https://www.we-online.com/catalog/datasheet/62704020621.pdf"
				(at 25.4 -13.97 0)
				(effects
					(font
						(size 1.27 1.27)
						(thickness 0.15)
					)
					(justify left bottom)
					(hide yes)
				)
			)
			(property "Description" "Pin Header, Wire-to-Board, 1.27 mm, 2 Rows, 40 Contacts, Surface Mount Straight, WR-BHD Series"
				(at 0 0 0)
				(effects
					(font
						(size 1.27 1.27)
					)
					(hide yes)
				)
			)
			(property "MPN" "62704020621"
				(at 25.4 -16.51 0)
				(effects
					(font
						(size 1.27 1.27)
						(thickness 0.15)
					)
					(justify left bottom)
					(hide yes)
				)
			)
			(property "Manufacturer" "Würth Elektronik"
				(at 25.4 -19.05 0)
				(effects
					(font
						(size 1.27 1.27)
						(thickness 0.15)
					)
					(justify left bottom)
					(hide yes)
				)
			)
			(property "Author" "Antmicro"
				(at 25.4 -21.59 0)
				(effects
					(font
						(size 1.27 1.27)
						(thickness 0.15)
					)
					(justify left bottom)
					(hide yes)
				)
			)
			(property "License" "Apache-2.0"
				(at 25.4 -24.13 0)
				(effects
					(font
						(size 1.27 1.27)
						(thickness 0.15)
					)
					(justify left bottom)
					(hide yes)
				)
			)
			(property "ki_keywords" "PINSTRIP, HEADER, SMT"
				(at 0 0 0)
				(effects
					(font
						(size 1.27 1.27)
					)
					(hide yes)
				)
			)
			(symbol "PinHeader_2x20_P1.27mm_SMD_Shrouded_1_1"
				(rectangle
					(start 1.905 -5.08)
					(end 1.905 -5.08)
					(stroke
						(width 0.254)
						(type default)
					)
					(fill
						(type background)
					)
				)
				(rectangle
					(start 1.905 -43.18)
					(end 1.905 -43.18)
					(stroke
						(width 0.254)
						(type default)
					)
					(fill
						(type background)
					)
				)
				(rectangle
					(start 2.54 1.27)
					(end 7.62 -50.165)
					(stroke
						(width 0.254)
						(type default)
					)
					(fill
						(type background)
					)
				)
				(rectangle
					(start 3.81 -2.54)
					(end 3.81 -2.54)
					(stroke
						(width 0.254)
						(type default)
					)
					(fill
						(type background)
					)
				)
				(rectangle
					(start 3.81 -40.64)
					(end 3.81 -40.64)
					(stroke
						(width 0.254)
						(type default)
					)
					(fill
						(type background)
					)
				)
				(rectangle
					(start 4.1656 -25.654)
					(end 3.6576 -25.146)
					(stroke
						(width 0.254)
						(type default)
					)
					(fill
						(type background)
					)
				)
				(rectangle
					(start 4.1656 -28.194)
					(end 3.6576 -27.686)
					(stroke
						(width 0.254)
						(type default)
					)
					(fill
						(type background)
					)
				)
				(rectangle
					(start 4.1656 -30.734)
					(end 3.6576 -30.226)
					(stroke
						(width 0.254)
						(type default)
					)
					(fill
						(type background)
					)
				)
				(rectangle
					(start 4.1656 -33.274)
					(end 3.6576 -32.766)
					(stroke
						(width 0.254)
						(type default)
					)
					(fill
						(type background)
					)
				)
				(rectangle
					(start 4.1656 -35.814)
					(end 3.6576 -35.306)
					(stroke
						(width 0.254)
						(type default)
					)
					(fill
						(type background)
					)
				)
				(rectangle
					(start 4.191 -0.254)
					(end 3.683 0.254)
					(stroke
						(width 0.254)
						(type default)
					)
					(fill
						(type background)
					)
				)
				(rectangle
					(start 4.191 -2.794)
					(end 3.683 -2.286)
					(stroke
						(width 0.254)
						(type default)
					)
					(fill
						(type background)
					)
				)
				(rectangle
					(start 4.191 -5.334)
					(end 3.683 -4.826)
					(stroke
						(width 0.254)
						(type default)
					)
					(fill
						(type background)
					)
				)
				(rectangle
					(start 4.191 -7.874)
					(end 3.683 -7.366)
					(stroke
						(width 0.254)
						(type default)
					)
					(fill
						(type background)
					)
				)
				(rectangle
					(start 4.191 -10.414)
					(end 3.683 -9.906)
					(stroke
						(width 0.254)
						(type default)
					)
					(fill
						(type background)
					)
				)
				(rectangle
					(start 4.191 -12.954)
					(end 3.683 -12.446)
					(stroke
						(width 0.254)
						(type default)
					)
					(fill
						(type background)
					)
				)
				(rectangle
					(start 4.191 -15.494)
					(end 3.683 -14.986)
					(stroke
						(width 0.254)
						(type default)
					)
					(fill
						(type background)
					)
				)
				(rectangle
					(start 4.191 -18.034)
					(end 3.683 -17.526)
					(stroke
						(width 0.254)
						(type default)
					)
					(fill
						(type background)
					)
				)
				(rectangle
					(start 4.191 -20.574)
					(end 3.683 -20.066)
					(stroke
						(width 0.254)
						(type default)
					)
					(fill
						(type background)
					)
				)
				(rectangle
					(start 4.191 -23.114)
					(end 3.683 -22.606)
					(stroke
						(width 0.254)
						(type default)
					)
					(fill
						(type background)
					)
				)
				(rectangle
					(start 4.191 -38.354)
					(end 3.683 -37.846)
					(stroke
						(width 0.254)
						(type default)
					)
					(fill
						(type background)
					)
				)
				(rectangle
					(start 4.191 -40.894)
					(end 3.683 -40.386)
					(stroke
						(width 0.254)
						(type default)
					)
					(fill
						(type background)
					)
				)
				(rectangle
					(start 4.191 -43.434)
					(end 3.683 -42.926)
					(stroke
						(width 0.254)
						(type default)
					)
					(fill
						(type background)
					)
				)
				(rectangle
					(start 4.191 -45.974)
					(end 3.683 -45.466)
					(stroke
						(width 0.254)
						(type default)
					)
					(fill
						(type background)
					)
				)
				(rectangle
					(start 4.191 -48.514)
					(end 3.683 -48.006)
					(stroke
						(width 0.254)
						(type default)
					)
					(fill
						(type background)
					)
				)
				(rectangle
					(start 6.7056 -23.114)
					(end 6.1976 -22.606)
					(stroke
						(width 0.254)
						(type default)
					)
					(fill
						(type background)
					)
				)
				(rectangle
					(start 6.7056 -25.654)
					(end 6.1976 -25.146)
					(stroke
						(width 0.254)
						(type default)
					)
					(fill
						(type background)
					)
				)
				(rectangle
					(start 6.7056 -28.194)
					(end 6.1976 -27.686)
					(stroke
						(width 0.254)
						(type default)
					)
					(fill
						(type background)
					)
				)
				(rectangle
					(start 6.7056 -30.734)
					(end 6.1976 -30.226)
					(stroke
						(width 0.254)
						(type default)
					)
					(fill
						(type background)
					)
				)
				(rectangle
					(start 6.7056 -33.274)
					(end 6.1976 -32.766)
					(stroke
						(width 0.254)
						(type default)
					)
					(fill
						(type background)
					)
				)
				(rectangle
					(start 6.7056 -35.814)
					(end 6.1976 -35.306)
					(stroke
						(width 0.254)
						(type default)
					)
					(fill
						(type background)
					)
				)
				(rectangle
					(start 6.731 -0.254)
					(end 6.223 0.254)
					(stroke
						(width 0.254)
						(type default)
					)
					(fill
						(type background)
					)
				)
				(rectangle
					(start 6.731 -2.794)
					(end 6.223 -2.286)
					(stroke
						(width 0.254)
						(type default)
					)
					(fill
						(type background)
					)
				)
				(rectangle
					(start 6.731 -5.334)
					(end 6.223 -4.826)
					(stroke
						(width 0.254)
						(type default)
					)
					(fill
						(type background)
					)
				)
				(rectangle
					(start 6.731 -7.874)
					(end 6.223 -7.366)
					(stroke
						(width 0.254)
						(type default)
					)
					(fill
						(type background)
					)
				)
				(rectangle
					(start 6.731 -10.414)
					(end 6.223 -9.906)
					(stroke
						(width 0.254)
						(type default)
					)
					(fill
						(type background)
					)
				)
				(rectangle
					(start 6.731 -12.954)
					(end 6.223 -12.446)
					(stroke
						(width 0.254)
						(type default)
					)
					(fill
						(type background)
					)
				)
				(rectangle
					(start 6.731 -15.494)
					(end 6.223 -14.986)
					(stroke
						(width 0.254)
						(type default)
					)
					(fill
						(type background)
					)
				)
				(rectangle
					(start 6.731 -18.034)
					(end 6.223 -17.526)
					(stroke
						(width 0.254)
						(type default)
					)
					(fill
						(type background)
					)
				)
				(rectangle
					(start 6.731 -20.574)
					(end 6.223 -20.066)
					(stroke
						(width 0.254)
						(type default)
					)
					(fill
						(type background)
					)
				)
				(rectangle
					(start 6.731 -38.354)
					(end 6.223 -37.846)
					(stroke
						(width 0.254)
						(type default)
					)
					(fill
						(type background)
					)
				)
				(rectangle
					(start 6.731 -40.894)
					(end 6.223 -40.386)
					(stroke
						(width 0.254)
						(type default)
					)
					(fill
						(type background)
					)
				)
				(rectangle
					(start 6.731 -43.434)
					(end 6.223 -42.926)
					(stroke
						(width 0.254)
						(type default)
					)
					(fill
						(type background)
					)
				)
				(rectangle
					(start 6.731 -45.974)
					(end 6.223 -45.466)
					(stroke
						(width 0.254)
						(type default)
					)
					(fill
						(type background)
					)
				)
				(rectangle
					(start 6.731 -48.514)
					(end 6.223 -48.006)
					(stroke
						(width 0.254)
						(type default)
					)
					(fill
						(type background)
					)
				)
				(pin passive line
					(at 0 0 0)
					(length 2.54)
					(name "~"
						(effects
							(font
								(size 1.27 1.27)
							)
						)
					)
					(number "1"
						(effects
							(font
								(size 1.27 1.27)
							)
						)
					)
				)
				(pin passive line
					(at 0 -2.54 0)
					(length 2.54)
					(name "~"
						(effects
							(font
								(size 1.27 1.27)
							)
						)
					)
					(number "3"
						(effects
							(font
								(size 1.27 1.27)
							)
						)
					)
				)
				(pin passive line
					(at 0 -5.08 0)
					(length 2.54)
					(name "~"
						(effects
							(font
								(size 1.27 1.27)
							)
						)
					)
					(number "5"
						(effects
							(font
								(size 1.27 1.27)
							)
						)
					)
				)
				(pin passive line
					(at 0 -7.62 0)
					(length 2.54)
					(name "~"
						(effects
							(font
								(size 1.27 1.27)
							)
						)
					)
					(number "7"
						(effects
							(font
								(size 1.27 1.27)
							)
						)
					)
				)
				(pin passive line
					(at 0 -10.16 0)
					(length 2.54)
					(name "~"
						(effects
							(font
								(size 1.27 1.27)
							)
						)
					)
					(number "9"
						(effects
							(font
								(size 1.27 1.27)
							)
						)
					)
				)
				(pin passive line
					(at 0 -12.7 0)
					(length 2.54)
					(name "~"
						(effects
							(font
								(size 1.27 1.27)
							)
						)
					)
					(number "11"
						(effects
							(font
								(size 1.27 1.27)
							)
						)
					)
				)
				(pin passive line
					(at 0 -15.24 0)
					(length 2.54)
					(name "~"
						(effects
							(font
								(size 1.27 1.27)
							)
						)
					)
					(number "13"
						(effects
							(font
								(size 1.27 1.27)
							)
						)
					)
				)
				(pin passive line
					(at 0 -17.78 0)
					(length 2.54)
					(name "~"
						(effects
							(font
								(size 1.27 1.27)
							)
						)
					)
					(number "15"
						(effects
							(font
								(size 1.27 1.27)
							)
						)
					)
				)
				(pin passive line
					(at 0 -20.32 0)
					(length 2.54)
					(name "~"
						(effects
							(font
								(size 1.27 1.27)
							)
						)
					)
					(number "17"
						(effects
							(font
								(size 1.27 1.27)
							)
						)
					)
				)
				(pin passive line
					(at 0 -22.86 0)
					(length 2.54)
					(name "~"
						(effects
							(font
								(size 1.27 1.27)
							)
						)
					)
					(number "19"
						(effects
							(font
								(size 1.27 1.27)
							)
						)
					)
				)
				(pin passive line
					(at 0 -25.4 0)
					(length 2.54)
					(name "~"
						(effects
							(font
								(size 1.27 1.27)
							)
						)
					)
					(number "21"
						(effects
							(font
								(size 1.27 1.27)
							)
						)
					)
				)
				(pin passive line
					(at 0 -27.94 0)
					(length 2.54)
					(name "~"
						(effects
							(font
								(size 1.27 1.27)
							)
						)
					)
					(number "23"
						(effects
							(font
								(size 1.27 1.27)
							)
						)
					)
				)
				(pin passive line
					(at 0 -30.48 0)
					(length 2.54)
					(name "~"
						(effects
							(font
								(size 1.27 1.27)
							)
						)
					)
					(number "25"
						(effects
							(font
								(size 1.27 1.27)
							)
						)
					)
				)
				(pin passive line
					(at 0 -33.02 0)
					(length 2.54)
					(name "~"
						(effects
							(font
								(size 1.27 1.27)
							)
						)
					)
					(number "27"
						(effects
							(font
								(size 1.27 1.27)
							)
						)
					)
				)
				(pin passive line
					(at 0 -35.56 0)
					(length 2.54)
					(name "~"
						(effects
							(font
								(size 1.27 1.27)
							)
						)
					)
					(number "29"
						(effects
							(font
								(size 1.27 1.27)
							)
						)
					)
				)
				(pin passive line
					(at 0 -38.1 0)
					(length 2.54)
					(name "~"
						(effects
							(font
								(size 1.27 1.27)
							)
						)
					)
					(number "31"
						(effects
							(font
								(size 1.27 1.27)
							)
						)
					)
				)
				(pin passive line
					(at 0 -40.64 0)
					(length 2.54)
					(name "~"
						(effects
							(font
								(size 1.27 1.27)
							)
						)
					)
					(number "33"
						(effects
							(font
								(size 1.27 1.27)
							)
						)
					)
				)
				(pin passive line
					(at 0 -43.18 0)
					(length 2.54)
					(name "~"
						(effects
							(font
								(size 1.27 1.27)
							)
						)
					)
					(number "35"
						(effects
							(font
								(size 1.27 1.27)
							)
						)
					)
				)
				(pin passive line
					(at 0 -45.72 0)
					(length 2.54)
					(name "~"
						(effects
							(font
								(size 1.27 1.27)
							)
						)
					)
					(number "37"
						(effects
							(font
								(size 1.27 1.27)
							)
						)
					)
				)
				(pin passive line
					(at 0 -48.26 0)
					(length 2.54)
					(name "~"
						(effects
							(font
								(size 1.27 1.27)
							)
						)
					)
					(number "39"
						(effects
							(font
								(size 1.27 1.27)
							)
						)
					)
				)
				(pin passive line
					(at 10.16 0 180)
					(length 2.54)
					(name "~"
						(effects
							(font
								(size 1.27 1.27)
							)
						)
					)
					(number "2"
						(effects
							(font
								(size 1.27 1.27)
							)
						)
					)
				)
				(pin passive line
					(at 10.16 -2.54 180)
					(length 2.54)
					(name "~"
						(effects
							(font
								(size 1.27 1.27)
							)
						)
					)
					(number "4"
						(effects
							(font
								(size 1.27 1.27)
							)
						)
					)
				)
				(pin passive line
					(at 10.16 -5.08 180)
					(length 2.54)
					(name "~"
						(effects
							(font
								(size 1.27 1.27)
							)
						)
					)
					(number "6"
						(effects
							(font
								(size 1.27 1.27)
							)
						)
					)
				)
				(pin passive line
					(at 10.16 -7.62 180)
					(length 2.54)
					(name "~"
						(effects
							(font
								(size 1.27 1.27)
							)
						)
					)
					(number "8"
						(effects
							(font
								(size 1.27 1.27)
							)
						)
					)
				)
				(pin passive line
					(at 10.16 -10.16 180)
					(length 2.54)
					(name "~"
						(effects
							(font
								(size 1.27 1.27)
							)
						)
					)
					(number "10"
						(effects
							(font
								(size 1.27 1.27)
							)
						)
					)
				)
				(pin passive line
					(at 10.16 -12.7 180)
					(length 2.54)
					(name "~"
						(effects
							(font
								(size 1.27 1.27)
							)
						)
					)
					(number "12"
						(effects
							(font
								(size 1.27 1.27)
							)
						)
					)
				)
				(pin passive line
					(at 10.16 -15.24 180)
					(length 2.54)
					(name "~"
						(effects
							(font
								(size 1.27 1.27)
							)
						)
					)
					(number "14"
						(effects
							(font
								(size 1.27 1.27)
							)
						)
					)
				)
				(pin passive line
					(at 10.16 -17.78 180)
					(length 2.54)
					(name "~"
						(effects
							(font
								(size 1.27 1.27)
							)
						)
					)
					(number "16"
						(effects
							(font
								(size 1.27 1.27)
							)
						)
					)
				)
				(pin passive line
					(at 10.16 -20.32 180)
					(length 2.54)
					(name "~"
						(effects
							(font
								(size 1.27 1.27)
							)
						)
					)
					(number "18"
						(effects
							(font
								(size 1.27 1.27)
							)
						)
					)
				)
				(pin passive line
					(at 10.16 -22.86 180)
					(length 2.54)
					(name "~"
						(effects
							(font
								(size 1.27 1.27)
							)
						)
					)
					(number "20"
						(effects
							(font
								(size 1.27 1.27)
							)
						)
					)
				)
				(pin passive line
					(at 10.16 -25.4 180)
					(length 2.54)
					(name "~"
						(effects
							(font
								(size 1.27 1.27)
							)
						)
					)
					(number "22"
						(effects
							(font
								(size 1.27 1.27)
							)
						)
					)
				)
				(pin passive line
					(at 10.16 -27.94 180)
					(length 2.54)
					(name "~"
						(effects
							(font
								(size 1.27 1.27)
							)
						)
					)
					(number "24"
						(effects
							(font
								(size 1.27 1.27)
							)
						)
					)
				)
				(pin passive line
					(at 10.16 -30.48 180)
					(length 2.54)
					(name "~"
						(effects
							(font
								(size 1.27 1.27)
							)
						)
					)
					(number "26"
						(effects
							(font
								(size 1.27 1.27)
							)
						)
					)
				)
				(pin passive line
					(at 10.16 -33.02 180)
					(length 2.54)
					(name "~"
						(effects
							(font
								(size 1.27 1.27)
							)
						)
					)
					(number "28"
						(effects
							(font
								(size 1.27 1.27)
							)
						)
					)
				)
				(pin passive line
					(at 10.16 -35.56 180)
					(length 2.54)
					(name "~"
						(effects
							(font
								(size 1.27 1.27)
							)
						)
					)
					(number "30"
						(effects
							(font
								(size 1.27 1.27)
							)
						)
					)
				)
				(pin passive line
					(at 10.16 -38.1 180)
					(length 2.54)
					(name "~"
						(effects
							(font
								(size 1.27 1.27)
							)
						)
					)
					(number "32"
						(effects
							(font
								(size 1.27 1.27)
							)
						)
					)
				)
				(pin passive line
					(at 10.16 -40.64 180)
					(length 2.54)
					(name "~"
						(effects
							(font
								(size 1.27 1.27)
							)
						)
					)
					(number "34"
						(effects
							(font
								(size 1.27 1.27)
							)
						)
					)
				)
				(pin passive line
					(at 10.16 -43.18 180)
					(length 2.54)
					(name "~"
						(effects
							(font
								(size 1.27 1.27)
							)
						)
					)
					(number "36"
						(effects
							(font
								(size 1.27 1.27)
							)
						)
					)
				)
				(pin passive line
					(at 10.16 -45.72 180)
					(length 2.54)
					(name "~"
						(effects
							(font
								(size 1.27 1.27)
							)
						)
					)
					(number "38"
						(effects
							(font
								(size 1.27 1.27)
							)
						)
					)
				)
				(pin passive line
					(at 10.16 -48.26 180)
					(length 2.54)
					(name "~"
						(effects
							(font
								(size 1.27 1.27)
							)
						)
					)
					(number "40"
						(effects
							(font
								(size 1.27 1.27)
							)
						)
					)
				)
			)
		)
	(symbol "antmicroGenericPinHeaders:PinHeader_2x3_P2.54mm_SMD"
			(exclude_from_sim no)
			(in_bom yes)
			(on_board yes)
			(property "Reference" "J"
				(at 25.4 -5.08 0)
				(effects
					(font
						(size 1.27 1.27)
						(thickness 0.15)
					)
					(justify left bottom)
				)
			)
			(property "Value" "PinHeader_2x3_P2.54mm_SMD"
				(at 25.4 -7.62 0)
				(effects
					(font
						(size 1.27 1.27)
						(thickness 0.15)
					)
					(justify left bottom)
				)
			)
			(property "Footprint" "antmicro-footprints:PinHeader_2x3_P2.54mm_SMD"
				(at 25.4 -10.16 0)
				(effects
					(font
						(size 1.27 1.27)
						(thickness 0.15)
					)
					(justify left bottom)
					(hide yes)
				)
			)
			(property "Datasheet" "https://www.molex.com/pdm_docs/sd/015910060_sd.pdf"
				(at 25.4 -12.7 0)
				(effects
					(font
						(size 1.27 1.27)
						(thickness 0.15)
					)
					(justify left bottom)
					(hide yes)
				)
			)
			(property "Description" ""
				(at 0 0 0)
				(effects
					(font
						(size 1.27 1.27)
					)
					(hide yes)
				)
			)
			(property "MPN" "15910060"
				(at 25.4 -15.24 0)
				(effects
					(font
						(size 1.27 1.27)
						(thickness 0.15)
					)
					(justify left bottom)
					(hide yes)
				)
			)
			(property "Manufacturer" "Molex"
				(at 25.4 -17.78 0)
				(effects
					(font
						(size 1.27 1.27)
						(thickness 0.15)
					)
					(justify left bottom)
					(hide yes)
				)
			)
			(property "Author" "Antmicro"
				(at 25.4 -20.32 0)
				(effects
					(font
						(size 1.27 1.27)
						(thickness 0.15)
					)
					(justify left bottom)
					(hide yes)
				)
			)
			(property "License" "Apache-2.0"
				(at 25.4 -22.86 0)
				(effects
					(font
						(size 1.27 1.27)
						(thickness 0.15)
					)
					(justify left bottom)
					(hide yes)
				)
			)
			(symbol "PinHeader_2x3_P2.54mm_SMD_1_1"
				(rectangle
					(start 2.54 1.27)
					(end 7.62 -6.35)
					(stroke
						(width 0.254)
						(type default)
					)
					(fill
						(type background)
					)
				)
				(rectangle
					(start 3.556 0.254)
					(end 4.064 -0.254)
					(stroke
						(width 0.254)
						(type default)
					)
					(fill
						(type background)
					)
				)
				(rectangle
					(start 3.556 -2.286)
					(end 4.064 -2.794)
					(stroke
						(width 0.254)
						(type default)
					)
					(fill
						(type background)
					)
				)
				(rectangle
					(start 3.556 -4.826)
					(end 4.064 -5.334)
					(stroke
						(width 0.254)
						(type default)
					)
					(fill
						(type background)
					)
				)
				(rectangle
					(start 6.096 0.254)
					(end 6.604 -0.254)
					(stroke
						(width 0.254)
						(type default)
					)
					(fill
						(type background)
					)
				)
				(rectangle
					(start 6.096 -2.286)
					(end 6.604 -2.794)
					(stroke
						(width 0.254)
						(type default)
					)
					(fill
						(type background)
					)
				)
				(rectangle
					(start 6.096 -4.826)
					(end 6.604 -5.334)
					(stroke
						(width 0.254)
						(type default)
					)
					(fill
						(type background)
					)
				)
				(pin passive line
					(at 0 0 0)
					(length 2.54)
					(name "~"
						(effects
							(font
								(size 1.27 1.27)
							)
						)
					)
					(number "1"
						(effects
							(font
								(size 1.27 1.27)
							)
						)
					)
				)
				(pin passive line
					(at 0 -2.54 0)
					(length 2.54)
					(name "~"
						(effects
							(font
								(size 1.27 1.27)
							)
						)
					)
					(number "3"
						(effects
							(font
								(size 1.27 1.27)
							)
						)
					)
				)
				(pin passive line
					(at 0 -5.08 0)
					(length 2.54)
					(name "~"
						(effects
							(font
								(size 1.27 1.27)
							)
						)
					)
					(number "5"
						(effects
							(font
								(size 1.27 1.27)
							)
						)
					)
				)
				(pin passive line
					(at 10.16 0 180)
					(length 2.54)
					(name "~"
						(effects
							(font
								(size 1.27 1.27)
							)
						)
					)
					(number "2"
						(effects
							(font
								(size 1.27 1.27)
							)
						)
					)
				)
				(pin passive line
					(at 10.16 -2.54 180)
					(length 2.54)
					(name "~"
						(effects
							(font
								(size 1.27 1.27)
							)
						)
					)
					(number "4"
						(effects
							(font
								(size 1.27 1.27)
							)
						)
					)
				)
				(pin passive line
					(at 10.16 -5.08 180)
					(length 2.54)
					(name "~"
						(effects
							(font
								(size 1.27 1.27)
							)
						)
					)
					(number "6"
						(effects
							(font
								(size 1.27 1.27)
							)
						)
					)
				)
			)
		)
	(symbol "antmicroGenericPinHeaders:PinHeader_2x7_P2mm_SMD_Shrouded_no-locator"
			(exclude_from_sim no)
			(in_bom yes)
			(on_board yes)
			(property "Reference" "J"
				(at 25.4 -2.54 0)
				(effects
					(font
						(size 1.27 1.27)
						(thickness 0.15)
					)
					(justify left bottom)
				)
			)
			(property "Value" "PinHeader_2x7_P2mm_SMD_Shrouded_no-locator"
				(at 25.4 -5.08 0)
				(effects
					(font
						(size 1.27 1.27)
						(thickness 0.15)
					)
					(justify left bottom)
					(hide yes)
				)
			)
			(property "Footprint" "antmicro-footprints:PinHeader_2x7_P2mm_SMD_Shrouded_no-locator"
				(at 25.4 -7.62 0)
				(effects
					(font
						(size 1.27 1.27)
						(thickness 0.15)
					)
					(justify left bottom)
					(hide yes)
				)
			)
			(property "Datasheet" "https://www.molex.com/pdm_docs/ps/PS-87831-027-001.pdf"
				(at 25.4 -10.16 0)
				(effects
					(font
						(size 1.27 1.27)
						(thickness 0.15)
					)
					(justify left bottom)
					(hide yes)
				)
			)
			(property "Description" ""
				(at 0 0 0)
				(effects
					(font
						(size 1.27 1.27)
					)
					(hide yes)
				)
			)
			(property "MPN" "878321412"
				(at 25.4 -12.7 0)
				(effects
					(font
						(size 1.27 1.27)
						(thickness 0.15)
					)
					(justify left bottom)
				)
			)
			(property "Manufacturer" "Molex"
				(at 25.4 -15.24 0)
				(effects
					(font
						(size 1.27 1.27)
						(thickness 0.15)
					)
					(justify left bottom)
					(hide yes)
				)
			)
			(property "Author" "Antmicro"
				(at 25.4 -17.78 0)
				(effects
					(font
						(size 1.27 1.27)
						(thickness 0.15)
					)
					(justify left bottom)
					(hide yes)
				)
			)
			(property "License" "Apache-2.0"
				(at 25.4 -20.32 0)
				(effects
					(font
						(size 1.27 1.27)
						(thickness 0.15)
					)
					(justify left bottom)
					(hide yes)
				)
			)
			(symbol "PinHeader_2x7_P2mm_SMD_Shrouded_no-locator_1_1"
				(rectangle
					(start 2.54 1.27)
					(end 7.62 -16.51)
					(stroke
						(width 0.254)
						(type default)
					)
					(fill
						(type background)
					)
				)
				(rectangle
					(start 3.556 0.254)
					(end 4.064 -0.254)
					(stroke
						(width 0.254)
						(type default)
					)
					(fill
						(type background)
					)
				)
				(rectangle
					(start 3.556 -2.286)
					(end 4.064 -2.794)
					(stroke
						(width 0.254)
						(type default)
					)
					(fill
						(type background)
					)
				)
				(rectangle
					(start 3.556 -4.826)
					(end 4.064 -5.334)
					(stroke
						(width 0.254)
						(type default)
					)
					(fill
						(type background)
					)
				)
				(rectangle
					(start 3.556 -7.366)
					(end 4.064 -7.874)
					(stroke
						(width 0.254)
						(type default)
					)
					(fill
						(type background)
					)
				)
				(rectangle
					(start 3.556 -9.906)
					(end 4.064 -10.414)
					(stroke
						(width 0.254)
						(type default)
					)
					(fill
						(type background)
					)
				)
				(rectangle
					(start 3.556 -12.446)
					(end 4.064 -12.954)
					(stroke
						(width 0.254)
						(type default)
					)
					(fill
						(type background)
					)
				)
				(rectangle
					(start 3.556 -14.986)
					(end 4.064 -15.494)
					(stroke
						(width 0.254)
						(type default)
					)
					(fill
						(type background)
					)
				)
				(rectangle
					(start 6.096 0.254)
					(end 6.604 -0.254)
					(stroke
						(width 0.254)
						(type default)
					)
					(fill
						(type background)
					)
				)
				(rectangle
					(start 6.096 -2.286)
					(end 6.604 -2.794)
					(stroke
						(width 0.254)
						(type default)
					)
					(fill
						(type background)
					)
				)
				(rectangle
					(start 6.096 -4.826)
					(end 6.604 -5.334)
					(stroke
						(width 0.254)
						(type default)
					)
					(fill
						(type background)
					)
				)
				(rectangle
					(start 6.096 -7.366)
					(end 6.604 -7.874)
					(stroke
						(width 0.254)
						(type default)
					)
					(fill
						(type background)
					)
				)
				(rectangle
					(start 6.096 -9.906)
					(end 6.604 -10.414)
					(stroke
						(width 0.254)
						(type default)
					)
					(fill
						(type background)
					)
				)
				(rectangle
					(start 6.096 -12.446)
					(end 6.604 -12.954)
					(stroke
						(width 0.254)
						(type default)
					)
					(fill
						(type background)
					)
				)
				(rectangle
					(start 6.096 -14.986)
					(end 6.604 -15.494)
					(stroke
						(width 0.254)
						(type default)
					)
					(fill
						(type background)
					)
				)
				(pin passive line
					(at 0 0 0)
					(length 2.54)
					(name "~"
						(effects
							(font
								(size 1.27 1.27)
							)
						)
					)
					(number "1"
						(effects
							(font
								(size 1.27 1.27)
							)
						)
					)
				)
				(pin passive line
					(at 0 -2.54 0)
					(length 2.54)
					(name "~"
						(effects
							(font
								(size 1.27 1.27)
							)
						)
					)
					(number "3"
						(effects
							(font
								(size 1.27 1.27)
							)
						)
					)
				)
				(pin passive line
					(at 0 -5.08 0)
					(length 2.54)
					(name "~"
						(effects
							(font
								(size 1.27 1.27)
							)
						)
					)
					(number "5"
						(effects
							(font
								(size 1.27 1.27)
							)
						)
					)
				)
				(pin passive line
					(at 0 -7.62 0)
					(length 2.54)
					(name "~"
						(effects
							(font
								(size 1.27 1.27)
							)
						)
					)
					(number "7"
						(effects
							(font
								(size 1.27 1.27)
							)
						)
					)
				)
				(pin passive line
					(at 0 -10.16 0)
					(length 2.54)
					(name "~"
						(effects
							(font
								(size 1.27 1.27)
							)
						)
					)
					(number "9"
						(effects
							(font
								(size 1.27 1.27)
							)
						)
					)
				)
				(pin passive line
					(at 0 -12.7 0)
					(length 2.54)
					(name "~"
						(effects
							(font
								(size 1.27 1.27)
							)
						)
					)
					(number "11"
						(effects
							(font
								(size 1.27 1.27)
							)
						)
					)
				)
				(pin passive line
					(at 0 -15.24 0)
					(length 2.54)
					(name "~"
						(effects
							(font
								(size 1.27 1.27)
							)
						)
					)
					(number "13"
						(effects
							(font
								(size 1.27 1.27)
							)
						)
					)
				)
				(pin passive line
					(at 10.16 0 180)
					(length 2.54)
					(name "~"
						(effects
							(font
								(size 1.27 1.27)
							)
						)
					)
					(number "2"
						(effects
							(font
								(size 1.27 1.27)
							)
						)
					)
				)
				(pin passive line
					(at 10.16 -2.54 180)
					(length 2.54)
					(name "~"
						(effects
							(font
								(size 1.27 1.27)
							)
						)
					)
					(number "4"
						(effects
							(font
								(size 1.27 1.27)
							)
						)
					)
				)
				(pin passive line
					(at 10.16 -5.08 180)
					(length 2.54)
					(name "~"
						(effects
							(font
								(size 1.27 1.27)
							)
						)
					)
					(number "6"
						(effects
							(font
								(size 1.27 1.27)
							)
						)
					)
				)
				(pin passive line
					(at 10.16 -7.62 180)
					(length 2.54)
					(name "~"
						(effects
							(font
								(size 1.27 1.27)
							)
						)
					)
					(number "8"
						(effects
							(font
								(size 1.27 1.27)
							)
						)
					)
				)
				(pin passive line
					(at 10.16 -10.16 180)
					(length 2.54)
					(name "~"
						(effects
							(font
								(size 1.27 1.27)
							)
						)
					)
					(number "10"
						(effects
							(font
								(size 1.27 1.27)
							)
						)
					)
				)
				(pin passive line
					(at 10.16 -12.7 180)
					(length 2.54)
					(name "~"
						(effects
							(font
								(size 1.27 1.27)
							)
						)
					)
					(number "12"
						(effects
							(font
								(size 1.27 1.27)
							)
						)
					)
				)
				(pin passive line
					(at 10.16 -15.24 180)
					(length 2.54)
					(name "~"
						(effects
							(font
								(size 1.27 1.27)
							)
						)
					)
					(number "14"
						(effects
							(font
								(size 1.27 1.27)
							)
						)
					)
				)
			)
		)
	(symbol "antmicroGenericPinSockets:PinSocket_2x6_P2.54mm_Drill1.04mm_Horizontal"
			(exclude_from_sim no)
			(in_bom yes)
			(on_board yes)
			(property "Reference" "J"
				(at 19.05 0 0)
				(effects
					(font
						(size 1.27 1.27)
						(thickness 0.15)
					)
					(justify left bottom)
				)
			)
			(property "Value" "PinSocket_2x6_P2.54mm_Drill1.04mm_Horizontal"
				(at 19.05 -2.54 0)
				(effects
					(font
						(size 1.27 1.27)
						(thickness 0.15)
					)
					(justify left bottom)
					(hide yes)
				)
			)
			(property "Footprint" "antmicro-footprints:PinSocket_2x6_P2.54mm_Drill1.04mm_Horizontal"
				(at 19.05 -5.08 0)
				(effects
					(font
						(size 1.27 1.27)
						(thickness 0.15)
					)
					(justify left bottom)
					(hide yes)
				)
			)
			(property "Datasheet" "https://suddendocs.samtec.com/prints/ssw-1xx-xx-xxx-x-xx-xxx-xx-mkt.pdf"
				(at 19.05 -7.62 0)
				(effects
					(font
						(size 1.27 1.27)
						(thickness 0.15)
					)
					(justify left bottom)
					(hide yes)
				)
			)
			(property "Description" "PCB Receptacle, Board-to-Board, 2.54 mm, 2 Rows, 12 Contacts, Through Hole Mount Right Angle, SSW"
				(at 0 0 0)
				(effects
					(font
						(size 1.27 1.27)
					)
					(hide yes)
				)
			)
			(property "MPN" "SSW-106-02-G-D-RA"
				(at 19.05 -12.7 0)
				(effects
					(font
						(size 1.27 1.27)
						(thickness 0.15)
					)
					(justify left bottom)
				)
			)
			(property "Manufacturer" "Samtec"
				(at 19.05 -10.16 0)
				(effects
					(font
						(size 1.27 1.27)
						(thickness 0.15)
					)
					(justify left bottom)
					(hide yes)
				)
			)
			(property "Author" "Antmicro"
				(at 19.05 -15.24 0)
				(effects
					(font
						(size 1.27 1.27)
						(thickness 0.15)
					)
					(justify left bottom)
					(hide yes)
				)
			)
			(property "License" "Apache-2.0"
				(at 19.05 -17.78 0)
				(effects
					(font
						(size 1.27 1.27)
						(thickness 0.15)
					)
					(justify left bottom)
					(hide yes)
				)
			)
			(property "ki_keywords" "CONNECTOR, SOCKET, THT, HORIZONTAL"
				(at 0 0 0)
				(effects
					(font
						(size 1.27 1.27)
					)
					(hide yes)
				)
			)
			(symbol "PinSocket_2x6_P2.54mm_Drill1.04mm_Horizontal_1_1"
				(rectangle
					(start 2.54 2.54)
					(end 7.62 -15.24)
					(stroke
						(width 0.254)
						(type default)
					)
					(fill
						(type background)
					)
				)
				(rectangle
					(start 3.556 0.254)
					(end 4.064 -0.254)
					(stroke
						(width 0.254)
						(type default)
					)
					(fill
						(type background)
					)
				)
				(rectangle
					(start 3.556 -2.286)
					(end 4.064 -2.794)
					(stroke
						(width 0.254)
						(type default)
					)
					(fill
						(type background)
					)
				)
				(rectangle
					(start 3.556 -4.826)
					(end 4.064 -5.334)
					(stroke
						(width 0.254)
						(type default)
					)
					(fill
						(type background)
					)
				)
				(rectangle
					(start 3.556 -7.366)
					(end 4.064 -7.874)
					(stroke
						(width 0.254)
						(type default)
					)
					(fill
						(type background)
					)
				)
				(rectangle
					(start 3.556 -9.906)
					(end 4.064 -10.414)
					(stroke
						(width 0.254)
						(type default)
					)
					(fill
						(type background)
					)
				)
				(rectangle
					(start 3.556 -12.446)
					(end 4.064 -12.954)
					(stroke
						(width 0.254)
						(type default)
					)
					(fill
						(type background)
					)
				)
				(rectangle
					(start 6.096 0.254)
					(end 6.604 -0.254)
					(stroke
						(width 0.254)
						(type default)
					)
					(fill
						(type background)
					)
				)
				(rectangle
					(start 6.096 -2.286)
					(end 6.604 -2.794)
					(stroke
						(width 0.254)
						(type default)
					)
					(fill
						(type background)
					)
				)
				(rectangle
					(start 6.096 -4.826)
					(end 6.604 -5.334)
					(stroke
						(width 0.254)
						(type default)
					)
					(fill
						(type background)
					)
				)
				(rectangle
					(start 6.096 -7.366)
					(end 6.604 -7.874)
					(stroke
						(width 0.254)
						(type default)
					)
					(fill
						(type background)
					)
				)
				(rectangle
					(start 6.096 -9.906)
					(end 6.604 -10.414)
					(stroke
						(width 0.254)
						(type default)
					)
					(fill
						(type background)
					)
				)
				(rectangle
					(start 6.096 -12.446)
					(end 6.604 -12.954)
					(stroke
						(width 0.254)
						(type default)
					)
					(fill
						(type background)
					)
				)
				(pin passive line
					(at 0 0 0)
					(length 2.54)
					(name "~"
						(effects
							(font
								(size 1.27 1.27)
							)
						)
					)
					(number "1"
						(effects
							(font
								(size 1.27 1.27)
							)
						)
					)
				)
				(pin passive line
					(at 0 -2.54 0)
					(length 2.54)
					(name "~"
						(effects
							(font
								(size 1.27 1.27)
							)
						)
					)
					(number "3"
						(effects
							(font
								(size 1.27 1.27)
							)
						)
					)
				)
				(pin passive line
					(at 0 -5.08 0)
					(length 2.54)
					(name "~"
						(effects
							(font
								(size 1.27 1.27)
							)
						)
					)
					(number "5"
						(effects
							(font
								(size 1.27 1.27)
							)
						)
					)
				)
				(pin passive line
					(at 0 -7.62 0)
					(length 2.54)
					(name "~"
						(effects
							(font
								(size 1.27 1.27)
							)
						)
					)
					(number "7"
						(effects
							(font
								(size 1.27 1.27)
							)
						)
					)
				)
				(pin passive line
					(at 0 -10.16 0)
					(length 2.54)
					(name "~"
						(effects
							(font
								(size 1.27 1.27)
							)
						)
					)
					(number "9"
						(effects
							(font
								(size 1.27 1.27)
							)
						)
					)
				)
				(pin passive line
					(at 0 -12.7 0)
					(length 2.54)
					(name "~"
						(effects
							(font
								(size 1.27 1.27)
							)
						)
					)
					(number "11"
						(effects
							(font
								(size 1.27 1.27)
							)
						)
					)
				)
				(pin passive line
					(at 10.16 0 180)
					(length 2.54)
					(name "~"
						(effects
							(font
								(size 1.27 1.27)
							)
						)
					)
					(number "2"
						(effects
							(font
								(size 1.27 1.27)
							)
						)
					)
				)
				(pin passive line
					(at 10.16 -2.54 180)
					(length 2.54)
					(name "~"
						(effects
							(font
								(size 1.27 1.27)
							)
						)
					)
					(number "4"
						(effects
							(font
								(size 1.27 1.27)
							)
						)
					)
				)
				(pin passive line
					(at 10.16 -5.08 180)
					(length 2.54)
					(name "~"
						(effects
							(font
								(size 1.27 1.27)
							)
						)
					)
					(number "6"
						(effects
							(font
								(size 1.27 1.27)
							)
						)
					)
				)
				(pin passive line
					(at 10.16 -7.62 180)
					(length 2.54)
					(name "~"
						(effects
							(font
								(size 1.27 1.27)
							)
						)
					)
					(number "8"
						(effects
							(font
								(size 1.27 1.27)
							)
						)
					)
				)
				(pin passive line
					(at 10.16 -10.16 180)
					(length 2.54)
					(name "~"
						(effects
							(font
								(size 1.27 1.27)
							)
						)
					)
					(number "10"
						(effects
							(font
								(size 1.27 1.27)
							)
						)
					)
				)
				(pin passive line
					(at 10.16 -12.7 180)
					(length 2.54)
					(name "~"
						(effects
							(font
								(size 1.27 1.27)
							)
						)
					)
					(number "12"
						(effects
							(font
								(size 1.27 1.27)
							)
						)
					)
				)
			)
		)
	(symbol "antmicroInterfaceControllers:FT4232H_VQFN"
			(exclude_from_sim no)
			(in_bom yes)
			(on_board yes)
			(property "Reference" "U"
				(at 55.88 -2.54 0)
				(effects
					(font
						(size 1.27 1.27)
						(thickness 0.15)
					)
					(justify left bottom)
				)
			)
			(property "Value" "FT4232H_VQFN"
				(at 55.88 -5.08 0)
				(effects
					(font
						(size 1.27 1.27)
						(thickness 0.15)
					)
					(justify left bottom)
				)
			)
			(property "Footprint" "antmicro-footprints:QFN-56-1EP_8x8mm_P0.5mm"
				(at 55.88 -7.62 0)
				(effects
					(font
						(size 1.27 1.27)
						(thickness 0.15)
					)
					(justify left bottom)
					(hide yes)
				)
			)
			(property "Datasheet" "https://www.ftdichip.com/Support/Documents/DataSheets/ICs/DS_FT4232H.pdf"
				(at 55.88 -10.16 0)
				(effects
					(font
						(size 1.27 1.27)
						(thickness 0.15)
					)
					(justify left bottom)
					(hide yes)
				)
			)
			(property "Description" "Interface Bridges, USB to UART, MPSSE, 1.62 V, 1.98 V, VQFN, 56 Pins, -40 °C"
				(at 0 0 0)
				(effects
					(font
						(size 1.27 1.27)
					)
					(hide yes)
				)
			)
			(property "Manufacturer" "FTDI Chip"
				(at 55.88 -12.7 0)
				(effects
					(font
						(size 1.27 1.27)
						(thickness 0.15)
					)
					(justify left bottom)
					(hide yes)
				)
			)
			(property "MPN" "FT4232H-56Q-REEL"
				(at 55.88 -15.24 0)
				(effects
					(font
						(size 1.27 1.27)
						(thickness 0.15)
					)
					(justify left bottom)
					(hide yes)
				)
			)
			(property "Author" "Antmicro"
				(at 55.88 -17.78 0)
				(effects
					(font
						(size 1.27 1.27)
						(thickness 0.15)
					)
					(justify left bottom)
					(hide yes)
				)
			)
			(property "License" "Apache-2.0"
				(at 55.88 -20.32 0)
				(effects
					(font
						(size 1.27 1.27)
						(thickness 0.15)
					)
					(justify left bottom)
					(hide yes)
				)
			)
			(property "ki_keywords" "SMT, INTERFACE, IC, CONTROLLER, USB, UART, I2C, SPI, JTAG"
				(at 0 0 0)
				(effects
					(font
						(size 1.27 1.27)
					)
					(hide yes)
				)
			)
			(symbol "FT4232H_VQFN_1_1"
				(rectangle
					(start 2.54 2.54)
					(end 38.1 -93.98)
					(stroke
						(width 0.254)
						(type default)
					)
					(fill
						(type background)
					)
				)
				(pin power_in line
					(at 0 0 0)
					(length 2.54)
					(name "V_{REGIN}"
						(effects
							(font
								(size 1.27 1.27)
							)
						)
					)
					(number "44"
						(effects
							(font
								(size 1.27 1.27)
							)
						)
					)
				)
				(pin power_in line
					(at 0 -2.54 0)
					(length 2.54)
					(name "V_{CCIO}"
						(effects
							(font
								(size 1.27 1.27)
							)
						)
					)
					(number "16"
						(effects
							(font
								(size 1.27 1.27)
							)
						)
					)
				)
				(pin passive line
					(at 0 -2.54 0)
					(length 2.54)
					(hide yes)
					(name "V_{CCIO}"
						(effects
							(font
								(size 1.27 1.27)
							)
						)
					)
					(number "36"
						(effects
							(font
								(size 1.27 1.27)
							)
						)
					)
				)
				(pin passive line
					(at 0 -2.54 0)
					(length 2.54)
					(hide yes)
					(name "V_{CCIO}"
						(effects
							(font
								(size 1.27 1.27)
							)
						)
					)
					(number "50"
						(effects
							(font
								(size 1.27 1.27)
							)
						)
					)
				)
				(pin power_out line
					(at 0 -6.35 0)
					(length 2.54)
					(name "V_{REGOUT}"
						(effects
							(font
								(size 1.27 1.27)
							)
						)
					)
					(number "43"
						(effects
							(font
								(size 1.27 1.27)
							)
						)
					)
				)
				(pin power_in line
					(at 0 -10.16 0)
					(length 2.54)
					(name "V_{PHY}"
						(effects
							(font
								(size 1.27 1.27)
							)
						)
					)
					(number "5"
						(effects
							(font
								(size 1.27 1.27)
							)
						)
					)
				)
				(pin power_in line
					(at 0 -12.7 0)
					(length 2.54)
					(name "V_{PLL}"
						(effects
							(font
								(size 1.27 1.27)
							)
						)
					)
					(number "9"
						(effects
							(font
								(size 1.27 1.27)
							)
						)
					)
				)
				(pin power_in line
					(at 0 -15.24 0)
					(length 2.54)
					(name "V_{CORE}"
						(effects
							(font
								(size 1.27 1.27)
							)
						)
					)
					(number "2"
						(effects
							(font
								(size 1.27 1.27)
							)
						)
					)
				)
				(pin passive line
					(at 0 -15.24 0)
					(length 2.54)
					(hide yes)
					(name "V_{CORE}"
						(effects
							(font
								(size 1.27 1.27)
							)
						)
					)
					(number "31"
						(effects
							(font
								(size 1.27 1.27)
							)
						)
					)
				)
				(pin bidirectional line
					(at 0 -22.86 0)
					(length 2.54)
					(name "D+"
						(effects
							(font
								(size 1.27 1.27)
							)
						)
					)
					(number "8"
						(effects
							(font
								(size 1.27 1.27)
							)
						)
					)
				)
				(pin bidirectional line
					(at 0 -25.4 0)
					(length 2.54)
					(name "D-"
						(effects
							(font
								(size 1.27 1.27)
							)
						)
					)
					(number "7"
						(effects
							(font
								(size 1.27 1.27)
							)
						)
					)
				)
				(pin input line
					(at 0 -36.83 0)
					(length 2.54)
					(name "~{RESET}"
						(effects
							(font
								(size 1.27 1.27)
							)
						)
					)
					(number "11"
						(effects
							(font
								(size 1.27 1.27)
							)
						)
					)
				)
				(pin bidirectional line
					(at 0 -44.45 0)
					(length 2.54)
					(name "EECS"
						(effects
							(font
								(size 1.27 1.27)
							)
						)
					)
					(number "1"
						(effects
							(font
								(size 1.27 1.27)
							)
						)
					)
				)
				(pin output line
					(at 0 -46.99 0)
					(length 2.54)
					(name "EECLK"
						(effects
							(font
								(size 1.27 1.27)
							)
						)
					)
					(number "56"
						(effects
							(font
								(size 1.27 1.27)
							)
						)
					)
				)
				(pin bidirectional line
					(at 0 -49.53 0)
					(length 2.54)
					(name "EEDATA"
						(effects
							(font
								(size 1.27 1.27)
							)
						)
					)
					(number "55"
						(effects
							(font
								(size 1.27 1.27)
							)
						)
					)
				)
				(pin input line
					(at 0 -54.61 0)
					(length 2.54)
					(name "OSCI"
						(effects
							(font
								(size 1.27 1.27)
							)
						)
					)
					(number "3"
						(effects
							(font
								(size 1.27 1.27)
							)
						)
					)
				)
				(pin output line
					(at 0 -59.69 0)
					(length 2.54)
					(name "OSCO"
						(effects
							(font
								(size 1.27 1.27)
							)
						)
					)
					(number "4"
						(effects
							(font
								(size 1.27 1.27)
							)
						)
					)
				)
				(pin input line
					(at 0 -77.47 0)
					(length 2.54)
					(name "REF"
						(effects
							(font
								(size 1.27 1.27)
							)
						)
					)
					(number "6"
						(effects
							(font
								(size 1.27 1.27)
							)
						)
					)
				)
				(pin input line
					(at 0 -88.9 0)
					(length 2.54)
					(name "TEST"
						(effects
							(font
								(size 1.27 1.27)
							)
						)
					)
					(number "10"
						(effects
							(font
								(size 1.27 1.27)
							)
						)
					)
				)
				(pin power_in line
					(at 0 -91.44 0)
					(length 2.54)
					(name "GND"
						(effects
							(font
								(size 1.27 1.27)
							)
						)
					)
					(number "21"
						(effects
							(font
								(size 1.27 1.27)
							)
						)
					)
				)
				(pin passive line
					(at 0 -91.44 0)
					(length 2.54)
					(hide yes)
					(name "GND"
						(effects
							(font
								(size 1.27 1.27)
							)
						)
					)
					(number "41"
						(effects
							(font
								(size 1.27 1.27)
							)
						)
					)
				)
				(pin passive line
					(at 0 -91.44 0)
					(length 2.54)
					(hide yes)
					(name "GND"
						(effects
							(font
								(size 1.27 1.27)
							)
						)
					)
					(number "45"
						(effects
							(font
								(size 1.27 1.27)
							)
						)
					)
				)
				(pin passive line
					(at 0 -91.44 0)
					(length 2.54)
					(hide yes)
					(name "GND"
						(effects
							(font
								(size 1.27 1.27)
							)
						)
					)
					(number "57"
						(effects
							(font
								(size 1.27 1.27)
							)
						)
					)
				)
				(pin bidirectional line
					(at 40.64 0 180)
					(length 2.54)
					(name "ADBUS0"
						(effects
							(font
								(size 1.27 1.27)
							)
						)
					)
					(number "12"
						(effects
							(font
								(size 1.27 1.27)
							)
						)
					)
				)
				(pin bidirectional line
					(at 40.64 -2.54 180)
					(length 2.54)
					(name "ADBUS1"
						(effects
							(font
								(size 1.27 1.27)
							)
						)
					)
					(number "13"
						(effects
							(font
								(size 1.27 1.27)
							)
						)
					)
				)
				(pin bidirectional line
					(at 40.64 -5.08 180)
					(length 2.54)
					(name "ADBUS2"
						(effects
							(font
								(size 1.27 1.27)
							)
						)
					)
					(number "14"
						(effects
							(font
								(size 1.27 1.27)
							)
						)
					)
				)
				(pin bidirectional line
					(at 40.64 -7.62 180)
					(length 2.54)
					(name "ADBUS3"
						(effects
							(font
								(size 1.27 1.27)
							)
						)
					)
					(number "15"
						(effects
							(font
								(size 1.27 1.27)
							)
						)
					)
				)
				(pin bidirectional line
					(at 40.64 -10.16 180)
					(length 2.54)
					(name "ADBUS4"
						(effects
							(font
								(size 1.27 1.27)
							)
						)
					)
					(number "17"
						(effects
							(font
								(size 1.27 1.27)
							)
						)
					)
				)
				(pin bidirectional line
					(at 40.64 -12.7 180)
					(length 2.54)
					(name "ADBUS5"
						(effects
							(font
								(size 1.27 1.27)
							)
						)
					)
					(number "18"
						(effects
							(font
								(size 1.27 1.27)
							)
						)
					)
				)
				(pin bidirectional line
					(at 40.64 -15.24 180)
					(length 2.54)
					(name "ADBUS6"
						(effects
							(font
								(size 1.27 1.27)
							)
						)
					)
					(number "19"
						(effects
							(font
								(size 1.27 1.27)
							)
						)
					)
				)
				(pin bidirectional line
					(at 40.64 -17.78 180)
					(length 2.54)
					(name "ADBUS7"
						(effects
							(font
								(size 1.27 1.27)
							)
						)
					)
					(number "20"
						(effects
							(font
								(size 1.27 1.27)
							)
						)
					)
				)
				(pin bidirectional line
					(at 40.64 -21.59 180)
					(length 2.54)
					(name "BDBUS0"
						(effects
							(font
								(size 1.27 1.27)
							)
						)
					)
					(number "22"
						(effects
							(font
								(size 1.27 1.27)
							)
						)
					)
				)
				(pin bidirectional line
					(at 40.64 -24.13 180)
					(length 2.54)
					(name "BDBUS1"
						(effects
							(font
								(size 1.27 1.27)
							)
						)
					)
					(number "23"
						(effects
							(font
								(size 1.27 1.27)
							)
						)
					)
				)
				(pin bidirectional line
					(at 40.64 -26.67 180)
					(length 2.54)
					(name "BDBUS2"
						(effects
							(font
								(size 1.27 1.27)
							)
						)
					)
					(number "24"
						(effects
							(font
								(size 1.27 1.27)
							)
						)
					)
				)
				(pin bidirectional line
					(at 40.64 -29.21 180)
					(length 2.54)
					(name "BDBUS3"
						(effects
							(font
								(size 1.27 1.27)
							)
						)
					)
					(number "25"
						(effects
							(font
								(size 1.27 1.27)
							)
						)
					)
				)
				(pin bidirectional line
					(at 40.64 -31.75 180)
					(length 2.54)
					(name "BDBUS4"
						(effects
							(font
								(size 1.27 1.27)
							)
						)
					)
					(number "26"
						(effects
							(font
								(size 1.27 1.27)
							)
						)
					)
				)
				(pin bidirectional line
					(at 40.64 -34.29 180)
					(length 2.54)
					(name "BDBUS5"
						(effects
							(font
								(size 1.27 1.27)
							)
						)
					)
					(number "27"
						(effects
							(font
								(size 1.27 1.27)
							)
						)
					)
				)
				(pin bidirectional line
					(at 40.64 -36.83 180)
					(length 2.54)
					(name "BDBUS6"
						(effects
							(font
								(size 1.27 1.27)
							)
						)
					)
					(number "28"
						(effects
							(font
								(size 1.27 1.27)
							)
						)
					)
				)
				(pin bidirectional line
					(at 40.64 -39.37 180)
					(length 2.54)
					(name "BDBUS7"
						(effects
							(font
								(size 1.27 1.27)
							)
						)
					)
					(number "29"
						(effects
							(font
								(size 1.27 1.27)
							)
						)
					)
				)
				(pin bidirectional line
					(at 40.64 -43.18 180)
					(length 2.54)
					(name "CDBUS0"
						(effects
							(font
								(size 1.27 1.27)
							)
						)
					)
					(number "32"
						(effects
							(font
								(size 1.27 1.27)
							)
						)
					)
				)
				(pin bidirectional line
					(at 40.64 -45.72 180)
					(length 2.54)
					(name "CDBUS1"
						(effects
							(font
								(size 1.27 1.27)
							)
						)
					)
					(number "33"
						(effects
							(font
								(size 1.27 1.27)
							)
						)
					)
				)
				(pin bidirectional line
					(at 40.64 -48.26 180)
					(length 2.54)
					(name "CDBUS2"
						(effects
							(font
								(size 1.27 1.27)
							)
						)
					)
					(number "34"
						(effects
							(font
								(size 1.27 1.27)
							)
						)
					)
				)
				(pin bidirectional line
					(at 40.64 -50.8 180)
					(length 2.54)
					(name "CDBUS3"
						(effects
							(font
								(size 1.27 1.27)
							)
						)
					)
					(number "35"
						(effects
							(font
								(size 1.27 1.27)
							)
						)
					)
				)
				(pin bidirectional line
					(at 40.64 -53.34 180)
					(length 2.54)
					(name "CDBUS4"
						(effects
							(font
								(size 1.27 1.27)
							)
						)
					)
					(number "37"
						(effects
							(font
								(size 1.27 1.27)
							)
						)
					)
				)
				(pin bidirectional line
					(at 40.64 -55.88 180)
					(length 2.54)
					(name "CDBUS5"
						(effects
							(font
								(size 1.27 1.27)
							)
						)
					)
					(number "38"
						(effects
							(font
								(size 1.27 1.27)
							)
						)
					)
				)
				(pin bidirectional line
					(at 40.64 -58.42 180)
					(length 2.54)
					(name "CDBUS6"
						(effects
							(font
								(size 1.27 1.27)
							)
						)
					)
					(number "39"
						(effects
							(font
								(size 1.27 1.27)
							)
						)
					)
				)
				(pin bidirectional line
					(at 40.64 -60.96 180)
					(length 2.54)
					(name "CDBUS7"
						(effects
							(font
								(size 1.27 1.27)
							)
						)
					)
					(number "40"
						(effects
							(font
								(size 1.27 1.27)
							)
						)
					)
				)
				(pin bidirectional line
					(at 40.64 -64.77 180)
					(length 2.54)
					(name "DDBUS0"
						(effects
							(font
								(size 1.27 1.27)
							)
						)
					)
					(number "42"
						(effects
							(font
								(size 1.27 1.27)
							)
						)
					)
				)
				(pin bidirectional line
					(at 40.64 -67.31 180)
					(length 2.54)
					(name "DDBUS1"
						(effects
							(font
								(size 1.27 1.27)
							)
						)
					)
					(number "46"
						(effects
							(font
								(size 1.27 1.27)
							)
						)
					)
				)
				(pin bidirectional line
					(at 40.64 -69.85 180)
					(length 2.54)
					(name "DDBUS2"
						(effects
							(font
								(size 1.27 1.27)
							)
						)
					)
					(number "47"
						(effects
							(font
								(size 1.27 1.27)
							)
						)
					)
				)
				(pin bidirectional line
					(at 40.64 -72.39 180)
					(length 2.54)
					(name "DDBUS3"
						(effects
							(font
								(size 1.27 1.27)
							)
						)
					)
					(number "48"
						(effects
							(font
								(size 1.27 1.27)
							)
						)
					)
				)
				(pin bidirectional line
					(at 40.64 -74.93 180)
					(length 2.54)
					(name "DDBUS4"
						(effects
							(font
								(size 1.27 1.27)
							)
						)
					)
					(number "49"
						(effects
							(font
								(size 1.27 1.27)
							)
						)
					)
				)
				(pin bidirectional line
					(at 40.64 -77.47 180)
					(length 2.54)
					(name "DDBUS5"
						(effects
							(font
								(size 1.27 1.27)
							)
						)
					)
					(number "51"
						(effects
							(font
								(size 1.27 1.27)
							)
						)
					)
				)
				(pin bidirectional line
					(at 40.64 -80.01 180)
					(length 2.54)
					(name "DDBUS6"
						(effects
							(font
								(size 1.27 1.27)
							)
						)
					)
					(number "52"
						(effects
							(font
								(size 1.27 1.27)
							)
						)
					)
				)
				(pin bidirectional line
					(at 40.64 -82.55 180)
					(length 2.54)
					(name "DDBUS7"
						(effects
							(font
								(size 1.27 1.27)
							)
						)
					)
					(number "53"
						(effects
							(font
								(size 1.27 1.27)
							)
						)
					)
				)
				(pin output line
					(at 40.64 -87.63 180)
					(length 2.54)
					(name "~{PWR_{EN}}"
						(effects
							(font
								(size 1.27 1.27)
							)
						)
					)
					(number "54"
						(effects
							(font
								(size 1.27 1.27)
							)
						)
					)
				)
				(pin output line
					(at 40.64 -90.17 180)
					(length 2.54)
					(name "~{SUSPEND}"
						(effects
							(font
								(size 1.27 1.27)
							)
						)
					)
					(number "30"
						(effects
							(font
								(size 1.27 1.27)
							)
						)
					)
				)
			)
		)
	(symbol "antmicroInterfaceControllers:KSZ9131RNXC"
			(exclude_from_sim no)
			(in_bom yes)
			(on_board yes)
			(property "Reference" "U"
				(at 58.42 -2.54 0)
				(effects
					(font
						(size 1.27 1.27)
						(thickness 0.15)
					)
					(justify left bottom)
				)
			)
			(property "Value" "KSZ9131RNXC"
				(at 58.42 -5.08 0)
				(effects
					(font
						(size 1.27 1.27)
						(thickness 0.15)
					)
					(justify left bottom)
				)
			)
			(property "Footprint" "antmicro-footprints:QFN-48-1EP_7x7x0.9mm_P0.5mm_EP5x5mm"
				(at 58.42 -7.62 0)
				(effects
					(font
						(size 1.27 1.27)
						(thickness 0.15)
					)
					(justify left bottom)
					(hide yes)
				)
			)
			(property "Datasheet" "https://ww1.microchip.com/downloads/en/DeviceDoc/00002841B.pdf"
				(at 58.42 -10.16 0)
				(effects
					(font
						(size 1.27 1.27)
						(thickness 0.15)
					)
					(justify left bottom)
					(hide yes)
				)
			)
			(property "Description" "Ethernet ICs Gigabit Ethernet Transceiver with RGMII support"
				(at 0 0 0)
				(effects
					(font
						(size 1.27 1.27)
					)
					(hide yes)
				)
			)
			(property "Manufacturer" "Microchip Technology"
				(at 58.42 -12.7 0)
				(effects
					(font
						(size 1.27 1.27)
						(thickness 0.15)
					)
					(justify left bottom)
					(hide yes)
				)
			)
			(property "MPN" "KSZ9131RNXC"
				(at 58.42 -15.24 0)
				(effects
					(font
						(size 1.27 1.27)
						(thickness 0.15)
					)
					(justify left bottom)
					(hide yes)
				)
			)
			(property "Author" "Antmicro"
				(at 58.42 -17.78 0)
				(effects
					(font
						(size 1.27 1.27)
						(thickness 0.15)
					)
					(justify left bottom)
					(hide yes)
				)
			)
			(property "License" "Apache-2.0"
				(at 58.42 -20.32 0)
				(effects
					(font
						(size 1.27 1.27)
						(thickness 0.15)
					)
					(justify left bottom)
					(hide yes)
				)
			)
			(property "ki_keywords" "SMT, TRANSCEIVER, IC, ETHERNET, PHY"
				(at 0 0 0)
				(effects
					(font
						(size 1.27 1.27)
					)
					(hide yes)
				)
			)
			(symbol "KSZ9131RNXC_1_1"
				(rectangle
					(start 2.54 2.54)
					(end 41.91 -78.74)
					(stroke
						(width 0.254)
						(type default)
					)
					(fill
						(type background)
					)
				)
				(text "10/100/1000"
					(at 16.51 -6.35 0)
					(effects
						(font
							(size 1.27 1.27)
							(thickness 0.15)
						)
						(justify left bottom)
					)
				)
				(text "Ethernet PHY"
					(at 16.51 -8.89 0)
					(effects
						(font
							(size 1.27 1.27)
							(thickness 0.15)
						)
						(justify left bottom)
					)
				)
				(pin power_in line
					(at 0 0 0)
					(length 2.54)
					(name "DVDDH"
						(effects
							(font
								(size 1.27 1.27)
							)
						)
					)
					(number "16"
						(effects
							(font
								(size 1.27 1.27)
							)
						)
					)
				)
				(pin passive line
					(at 0 0 0)
					(length 2.54)
					(hide yes)
					(name "DVDDH"
						(effects
							(font
								(size 1.27 1.27)
							)
						)
					)
					(number "34"
						(effects
							(font
								(size 1.27 1.27)
							)
						)
					)
				)
				(pin passive line
					(at 0 0 0)
					(length 2.54)
					(hide yes)
					(name "DVDDH"
						(effects
							(font
								(size 1.27 1.27)
							)
						)
					)
					(number "40"
						(effects
							(font
								(size 1.27 1.27)
							)
						)
					)
				)
				(pin power_in line
					(at 0 -7.62 0)
					(length 2.54)
					(name "AVDDH"
						(effects
							(font
								(size 1.27 1.27)
							)
						)
					)
					(number "1"
						(effects
							(font
								(size 1.27 1.27)
							)
						)
					)
				)
				(pin passive line
					(at 0 -7.62 0)
					(length 2.54)
					(hide yes)
					(name "AVDDH"
						(effects
							(font
								(size 1.27 1.27)
							)
						)
					)
					(number "12"
						(effects
							(font
								(size 1.27 1.27)
							)
						)
					)
				)
				(pin passive line
					(at 0 -10.16 0)
					(length 2.54)
					(name "NC_(AVDDH)"
						(effects
							(font
								(size 1.27 1.27)
							)
						)
					)
					(number "47"
						(effects
							(font
								(size 1.27 1.27)
							)
						)
					)
				)
				(pin input line
					(at 0 -17.78 0)
					(length 2.54)
					(name "RESET_N"
						(effects
							(font
								(size 1.27 1.27)
							)
						)
					)
					(number "42"
						(effects
							(font
								(size 1.27 1.27)
							)
						)
					)
				)
				(pin input line
					(at 0 -20.32 0)
					(length 2.54)
					(name "INT_N/PME_N2"
						(effects
							(font
								(size 1.27 1.27)
							)
						)
					)
					(number "38"
						(effects
							(font
								(size 1.27 1.27)
							)
						)
					)
				)
				(pin input line
					(at 0 -25.4 0)
					(length 2.54)
					(name "MDC"
						(effects
							(font
								(size 1.27 1.27)
							)
						)
					)
					(number "36"
						(effects
							(font
								(size 1.27 1.27)
							)
						)
					)
				)
				(pin input line
					(at 0 -27.94 0)
					(length 2.54)
					(name "MDIO"
						(effects
							(font
								(size 1.27 1.27)
							)
						)
					)
					(number "37"
						(effects
							(font
								(size 1.27 1.27)
							)
						)
					)
				)
				(pin input line
					(at 0 -33.02 0)
					(length 2.54)
					(name "TX_EN"
						(effects
							(font
								(size 1.27 1.27)
							)
						)
					)
					(number "25"
						(effects
							(font
								(size 1.27 1.27)
							)
						)
					)
				)
				(pin input line
					(at 0 -35.56 0)
					(length 2.54)
					(name "TXD0"
						(effects
							(font
								(size 1.27 1.27)
							)
						)
					)
					(number "19"
						(effects
							(font
								(size 1.27 1.27)
							)
						)
					)
				)
				(pin input line
					(at 0 -38.1 0)
					(length 2.54)
					(name "TXD1"
						(effects
							(font
								(size 1.27 1.27)
							)
						)
					)
					(number "20"
						(effects
							(font
								(size 1.27 1.27)
							)
						)
					)
				)
				(pin input line
					(at 0 -40.64 0)
					(length 2.54)
					(name "TXD2"
						(effects
							(font
								(size 1.27 1.27)
							)
						)
					)
					(number "21"
						(effects
							(font
								(size 1.27 1.27)
							)
						)
					)
				)
				(pin input line
					(at 0 -43.18 0)
					(length 2.54)
					(name "TXD3"
						(effects
							(font
								(size 1.27 1.27)
							)
						)
					)
					(number "22"
						(effects
							(font
								(size 1.27 1.27)
							)
						)
					)
				)
				(pin input line
					(at 0 -45.72 0)
					(length 2.54)
					(name "GTX_CLK"
						(effects
							(font
								(size 1.27 1.27)
							)
						)
					)
					(number "24"
						(effects
							(font
								(size 1.27 1.27)
							)
						)
					)
				)
				(pin input line
					(at 0 -50.8 0)
					(length 2.54)
					(name "RX_DV/CLK125_EN"
						(effects
							(font
								(size 1.27 1.27)
							)
						)
					)
					(number "33"
						(effects
							(font
								(size 1.27 1.27)
							)
						)
					)
				)
				(pin input line
					(at 0 -53.34 0)
					(length 2.54)
					(name "RXD0/MODE0"
						(effects
							(font
								(size 1.27 1.27)
							)
						)
					)
					(number "32"
						(effects
							(font
								(size 1.27 1.27)
							)
						)
					)
				)
				(pin input line
					(at 0 -55.88 0)
					(length 2.54)
					(name "RXD1/MODE1"
						(effects
							(font
								(size 1.27 1.27)
							)
						)
					)
					(number "31"
						(effects
							(font
								(size 1.27 1.27)
							)
						)
					)
				)
				(pin input line
					(at 0 -58.42 0)
					(length 2.54)
					(name "RXD2/MODE2"
						(effects
							(font
								(size 1.27 1.27)
							)
						)
					)
					(number "28"
						(effects
							(font
								(size 1.27 1.27)
							)
						)
					)
				)
				(pin input line
					(at 0 -60.96 0)
					(length 2.54)
					(name "RXD3/MODE3"
						(effects
							(font
								(size 1.27 1.27)
							)
						)
					)
					(number "27"
						(effects
							(font
								(size 1.27 1.27)
							)
						)
					)
				)
				(pin input line
					(at 0 -63.5 0)
					(length 2.54)
					(name "RX_CLK/PHYAD2"
						(effects
							(font
								(size 1.27 1.27)
							)
						)
					)
					(number "35"
						(effects
							(font
								(size 1.27 1.27)
							)
						)
					)
				)
				(pin input line
					(at 0 -68.58 0)
					(length 2.54)
					(name "CLK125_NDO/LED_MODE"
						(effects
							(font
								(size 1.27 1.27)
							)
						)
					)
					(number "41"
						(effects
							(font
								(size 1.27 1.27)
							)
						)
					)
				)
				(pin input line
					(at 0 -73.66 0)
					(length 2.54)
					(name "XI"
						(effects
							(font
								(size 1.27 1.27)
							)
						)
					)
					(number "46"
						(effects
							(font
								(size 1.27 1.27)
							)
						)
					)
				)
				(pin input line
					(at 0 -76.2 0)
					(length 2.54)
					(name "XO"
						(effects
							(font
								(size 1.27 1.27)
							)
						)
					)
					(number "45"
						(effects
							(font
								(size 1.27 1.27)
							)
						)
					)
				)
				(pin power_in line
					(at 44.45 0 180)
					(length 2.54)
					(name "DVDDL"
						(effects
							(font
								(size 1.27 1.27)
							)
						)
					)
					(number "18"
						(effects
							(font
								(size 1.27 1.27)
							)
						)
					)
				)
				(pin passive line
					(at 44.45 0 180)
					(length 2.54)
					(hide yes)
					(name "DVDDL"
						(effects
							(font
								(size 1.27 1.27)
							)
						)
					)
					(number "23"
						(effects
							(font
								(size 1.27 1.27)
							)
						)
					)
				)
				(pin passive line
					(at 44.45 0 180)
					(length 2.54)
					(hide yes)
					(name "DVDDL"
						(effects
							(font
								(size 1.27 1.27)
							)
						)
					)
					(number "26"
						(effects
							(font
								(size 1.27 1.27)
							)
						)
					)
				)
				(pin passive line
					(at 44.45 0 180)
					(length 2.54)
					(hide yes)
					(name "DVDDL"
						(effects
							(font
								(size 1.27 1.27)
							)
						)
					)
					(number "30"
						(effects
							(font
								(size 1.27 1.27)
							)
						)
					)
				)
				(pin passive line
					(at 44.45 0 180)
					(length 2.54)
					(hide yes)
					(name "DVDDL"
						(effects
							(font
								(size 1.27 1.27)
							)
						)
					)
					(number "39"
						(effects
							(font
								(size 1.27 1.27)
							)
						)
					)
				)
				(pin passive line
					(at 44.45 -2.54 180)
					(length 2.54)
					(name "NC_(DVDDL)"
						(effects
							(font
								(size 1.27 1.27)
							)
						)
					)
					(number "14"
						(effects
							(font
								(size 1.27 1.27)
							)
						)
					)
				)
				(pin power_in line
					(at 44.45 -7.62 180)
					(length 2.54)
					(name "AVDDL"
						(effects
							(font
								(size 1.27 1.27)
							)
						)
					)
					(number "4"
						(effects
							(font
								(size 1.27 1.27)
							)
						)
					)
				)
				(pin passive line
					(at 44.45 -7.62 180)
					(length 2.54)
					(hide yes)
					(name "AVDDL"
						(effects
							(font
								(size 1.27 1.27)
							)
						)
					)
					(number "9"
						(effects
							(font
								(size 1.27 1.27)
							)
						)
					)
				)
				(pin power_in line
					(at 44.45 -10.16 180)
					(length 2.54)
					(name "AVDDL_PLL"
						(effects
							(font
								(size 1.27 1.27)
							)
						)
					)
					(number "44"
						(effects
							(font
								(size 1.27 1.27)
							)
						)
					)
				)
				(pin input line
					(at 44.45 -15.24 180)
					(length 2.54)
					(name "LDO_O"
						(effects
							(font
								(size 1.27 1.27)
							)
						)
					)
					(number "43"
						(effects
							(font
								(size 1.27 1.27)
							)
						)
					)
				)
				(pin input line
					(at 44.45 -22.86 180)
					(length 2.54)
					(name "TXRXM_D"
						(effects
							(font
								(size 1.27 1.27)
							)
						)
					)
					(number "11"
						(effects
							(font
								(size 1.27 1.27)
							)
						)
					)
				)
				(pin input line
					(at 44.45 -25.4 180)
					(length 2.54)
					(name "TXRXP_D"
						(effects
							(font
								(size 1.27 1.27)
							)
						)
					)
					(number "10"
						(effects
							(font
								(size 1.27 1.27)
							)
						)
					)
				)
				(pin input line
					(at 44.45 -30.48 180)
					(length 2.54)
					(name "TXRXM_C"
						(effects
							(font
								(size 1.27 1.27)
							)
						)
					)
					(number "8"
						(effects
							(font
								(size 1.27 1.27)
							)
						)
					)
				)
				(pin input line
					(at 44.45 -33.02 180)
					(length 2.54)
					(name "TXRXP_C"
						(effects
							(font
								(size 1.27 1.27)
							)
						)
					)
					(number "7"
						(effects
							(font
								(size 1.27 1.27)
							)
						)
					)
				)
				(pin input line
					(at 44.45 -38.1 180)
					(length 2.54)
					(name "TXRXM_B"
						(effects
							(font
								(size 1.27 1.27)
							)
						)
					)
					(number "6"
						(effects
							(font
								(size 1.27 1.27)
							)
						)
					)
				)
				(pin input line
					(at 44.45 -40.64 180)
					(length 2.54)
					(name "TXRXP_B"
						(effects
							(font
								(size 1.27 1.27)
							)
						)
					)
					(number "5"
						(effects
							(font
								(size 1.27 1.27)
							)
						)
					)
				)
				(pin input line
					(at 44.45 -45.72 180)
					(length 2.54)
					(name "TXRXM_A"
						(effects
							(font
								(size 1.27 1.27)
							)
						)
					)
					(number "3"
						(effects
							(font
								(size 1.27 1.27)
							)
						)
					)
				)
				(pin input line
					(at 44.45 -48.26 180)
					(length 2.54)
					(name "TXRXP_A"
						(effects
							(font
								(size 1.27 1.27)
							)
						)
					)
					(number "2"
						(effects
							(font
								(size 1.27 1.27)
							)
						)
					)
				)
				(pin bidirectional line
					(at 44.45 -55.88 180)
					(length 2.54)
					(name "LED2/PHYAD1"
						(effects
							(font
								(size 1.27 1.27)
							)
						)
					)
					(number "15"
						(effects
							(font
								(size 1.27 1.27)
							)
						)
					)
				)
				(pin bidirectional line
					(at 44.45 -58.42 180)
					(length 2.54)
					(name "LED1/PHAD0/PME_N1"
						(effects
							(font
								(size 1.27 1.27)
							)
						)
					)
					(number "17"
						(effects
							(font
								(size 1.27 1.27)
							)
						)
					)
				)
				(pin output line
					(at 44.45 -71.12 180)
					(length 2.54)
					(name "ISET"
						(effects
							(font
								(size 1.27 1.27)
							)
						)
					)
					(number "48"
						(effects
							(font
								(size 1.27 1.27)
							)
						)
					)
				)
				(pin power_out line
					(at 44.45 -73.66 180)
					(length 2.54)
					(name "GND"
						(effects
							(font
								(size 1.27 1.27)
							)
						)
					)
					(number "29"
						(effects
							(font
								(size 1.27 1.27)
							)
						)
					)
				)
				(pin passive line
					(at 44.45 -73.66 180)
					(length 2.54)
					(hide yes)
					(name "GND"
						(effects
							(font
								(size 1.27 1.27)
							)
						)
					)
					(number "49"
						(effects
							(font
								(size 1.27 1.27)
							)
						)
					)
				)
				(pin passive line
					(at 44.45 -76.2 180)
					(length 2.54)
					(name "NC_(GND)"
						(effects
							(font
								(size 1.27 1.27)
							)
						)
					)
					(number "13"
						(effects
							(font
								(size 1.27 1.27)
							)
						)
					)
				)
			)
		)
	(symbol "antmicroInterfaceControllers:LAN8720A-CP-TR-ABC"
			(exclude_from_sim no)
			(in_bom yes)
			(on_board yes)
			(property "Reference" "U"
				(at 53.34 -2.54 0)
				(effects
					(font
						(size 1.27 1.27)
						(thickness 0.15)
					)
					(justify left bottom)
				)
			)
			(property "Value" "LAN8720A-CP-TR-ABC"
				(at 53.34 -5.08 0)
				(effects
					(font
						(size 1.27 1.27)
						(thickness 0.15)
					)
					(justify left bottom)
				)
			)
			(property "Footprint" "antmicro-footprints:QFN-24-1EP_4x4mm_P0.5mm_EP2.6x2.6mm"
				(at 53.34 -7.62 0)
				(effects
					(font
						(size 1.27 1.27)
						(thickness 0.15)
					)
					(justify left bottom)
					(hide yes)
				)
			)
			(property "Datasheet" "http://ww1.microchip.com/downloads/en/DeviceDoc/8720a.pdf"
				(at 53.34 -10.16 0)
				(effects
					(font
						(size 1.27 1.27)
						(thickness 0.15)
					)
					(justify left bottom)
					(hide yes)
				)
			)
			(property "Description" "Ethernet Controller, 100 Mbps, IEEE 802.3, IEEE 802.3u, 3 V, 3.6 V, SQFN, 24 Pins"
				(at 0 0 0)
				(effects
					(font
						(size 1.27 1.27)
					)
					(hide yes)
				)
			)
			(property "MPN" "LAN8720A-CP-TR-ABC"
				(at 53.34 -12.7 0)
				(effects
					(font
						(size 1.27 1.27)
						(thickness 0.15)
					)
					(justify left bottom)
					(hide yes)
				)
			)
			(property "Manufacturer" "Microchip Technology"
				(at 53.34 -15.24 0)
				(effects
					(font
						(size 1.27 1.27)
						(thickness 0.15)
					)
					(justify left bottom)
					(hide yes)
				)
			)
			(property "Author" "Antmicro"
				(at 53.34 -17.78 0)
				(effects
					(font
						(size 1.27 1.27)
						(thickness 0.15)
					)
					(justify left bottom)
					(hide yes)
				)
			)
			(property "License" "Apache-2.0"
				(at 53.34 -20.32 0)
				(effects
					(font
						(size 1.27 1.27)
						(thickness 0.15)
					)
					(justify left bottom)
					(hide yes)
				)
			)
			(property "ki_keywords" "SMT, TRANSCEIVER, IC, ETHERNET, PHY"
				(at 0 0 0)
				(effects
					(font
						(size 1.27 1.27)
					)
					(hide yes)
				)
			)
			(property "ki_fp_filters" "QFN*1EP*4x4mm*P0.5mm*"
				(at 0 0 0)
				(effects
					(font
						(size 1.27 1.27)
					)
					(hide yes)
				)
			)
			(symbol "LAN8720A-CP-TR-ABC_1_1"
				(rectangle
					(start 2.54 2.54)
					(end 35.56 -50.8)
					(stroke
						(width 0.254)
						(type default)
					)
					(fill
						(type background)
					)
				)
				(polyline
					(pts
						(xy 2.54 -40.64) (xy 19.05 -40.64) (xy 19.05 -10.16) (xy 2.54 -10.16)
					)
					(stroke
						(width 0.254)
						(type default)
					)
					(fill
						(type background)
					)
				)
				(text "RMII"
					(at 14.605 -12.7 0)
					(effects
						(font
							(size 1.27 1.27)
							(thickness 0.15)
						)
						(justify left bottom)
					)
				)
				(pin power_in line
					(at 0 0 0)
					(length 2.54)
					(name "VDDIO"
						(effects
							(font
								(size 1.27 1.27)
							)
						)
					)
					(number "9"
						(effects
							(font
								(size 1.27 1.27)
							)
						)
					)
				)
				(pin input line
					(at 0 -5.08 0)
					(length 2.54)
					(name "RST"
						(effects
							(font
								(size 1.27 1.27)
							)
						)
					)
					(number "15"
						(effects
							(font
								(size 1.27 1.27)
							)
						)
					)
				)
				(pin output line
					(at 0 -7.62 0)
					(length 2.54)
					(name "INT/REFCLKO"
						(effects
							(font
								(size 1.27 1.27)
							)
						)
					)
					(number "14"
						(effects
							(font
								(size 1.27 1.27)
							)
						)
					)
				)
				(pin bidirectional line
					(at 0 -12.7 0)
					(length 2.54)
					(name "MDIO"
						(effects
							(font
								(size 1.27 1.27)
							)
						)
					)
					(number "12"
						(effects
							(font
								(size 1.27 1.27)
							)
						)
					)
				)
				(pin input line
					(at 0 -15.24 0)
					(length 2.54)
					(name "MDC"
						(effects
							(font
								(size 1.27 1.27)
							)
						)
					)
					(number "13"
						(effects
							(font
								(size 1.27 1.27)
							)
						)
					)
				)
				(pin input line
					(at 0 -20.32 0)
					(length 2.54)
					(name "TXEN"
						(effects
							(font
								(size 1.27 1.27)
							)
						)
					)
					(number "16"
						(effects
							(font
								(size 1.27 1.27)
							)
						)
					)
				)
				(pin input line
					(at 0 -22.86 0)
					(length 2.54)
					(name "TXD0"
						(effects
							(font
								(size 1.27 1.27)
							)
						)
					)
					(number "17"
						(effects
							(font
								(size 1.27 1.27)
							)
						)
					)
				)
				(pin input line
					(at 0 -25.4 0)
					(length 2.54)
					(name "TXD1"
						(effects
							(font
								(size 1.27 1.27)
							)
						)
					)
					(number "18"
						(effects
							(font
								(size 1.27 1.27)
							)
						)
					)
				)
				(pin output line
					(at 0 -30.48 0)
					(length 2.54)
					(name "CRS_DV/MODE2"
						(effects
							(font
								(size 1.27 1.27)
							)
						)
					)
					(number "11"
						(effects
							(font
								(size 1.27 1.27)
							)
						)
					)
				)
				(pin output line
					(at 0 -33.02 0)
					(length 2.54)
					(name "RXD0/MODE0"
						(effects
							(font
								(size 1.27 1.27)
							)
						)
					)
					(number "8"
						(effects
							(font
								(size 1.27 1.27)
							)
						)
					)
				)
				(pin output line
					(at 0 -35.56 0)
					(length 2.54)
					(name "RXD1/MODE1"
						(effects
							(font
								(size 1.27 1.27)
							)
						)
					)
					(number "7"
						(effects
							(font
								(size 1.27 1.27)
							)
						)
					)
				)
				(pin output line
					(at 0 -38.1 0)
					(length 2.54)
					(name "RXER/PHYAD0"
						(effects
							(font
								(size 1.27 1.27)
							)
						)
					)
					(number "10"
						(effects
							(font
								(size 1.27 1.27)
							)
						)
					)
				)
				(pin passive line
					(at 0 -45.72 0)
					(length 2.54)
					(name "XTAL1/CLKIN"
						(effects
							(font
								(size 1.27 1.27)
							)
						)
					)
					(number "5"
						(effects
							(font
								(size 1.27 1.27)
							)
						)
					)
				)
				(pin passive line
					(at 0 -48.26 0)
					(length 2.54)
					(name "XTAL2"
						(effects
							(font
								(size 1.27 1.27)
							)
						)
					)
					(number "4"
						(effects
							(font
								(size 1.27 1.27)
							)
						)
					)
				)
				(pin power_in line
					(at 38.1 0 180)
					(length 2.54)
					(name "VDD1A"
						(effects
							(font
								(size 1.27 1.27)
							)
						)
					)
					(number "19"
						(effects
							(font
								(size 1.27 1.27)
							)
						)
					)
				)
				(pin power_in line
					(at 38.1 -2.54 180)
					(length 2.54)
					(name "VDD2A"
						(effects
							(font
								(size 1.27 1.27)
							)
						)
					)
					(number "1"
						(effects
							(font
								(size 1.27 1.27)
							)
						)
					)
				)
				(pin power_in line
					(at 38.1 -5.08 180)
					(length 2.54)
					(name "VDDCR"
						(effects
							(font
								(size 1.27 1.27)
							)
						)
					)
					(number "6"
						(effects
							(font
								(size 1.27 1.27)
							)
						)
					)
				)
				(pin output line
					(at 38.1 -22.86 180)
					(length 2.54)
					(name "TXP"
						(effects
							(font
								(size 1.27 1.27)
							)
						)
					)
					(number "21"
						(effects
							(font
								(size 1.27 1.27)
							)
						)
					)
				)
				(pin output line
					(at 38.1 -25.4 180)
					(length 2.54)
					(name "TXN"
						(effects
							(font
								(size 1.27 1.27)
							)
						)
					)
					(number "20"
						(effects
							(font
								(size 1.27 1.27)
							)
						)
					)
				)
				(pin output line
					(at 38.1 -27.94 180)
					(length 2.54)
					(name "RXP"
						(effects
							(font
								(size 1.27 1.27)
							)
						)
					)
					(number "23"
						(effects
							(font
								(size 1.27 1.27)
							)
						)
					)
				)
				(pin output line
					(at 38.1 -30.48 180)
					(length 2.54)
					(name "RXN"
						(effects
							(font
								(size 1.27 1.27)
							)
						)
					)
					(number "22"
						(effects
							(font
								(size 1.27 1.27)
							)
						)
					)
				)
				(pin bidirectional line
					(at 38.1 -38.1 180)
					(length 2.54)
					(name "LED1/REGOFF"
						(effects
							(font
								(size 1.27 1.27)
							)
						)
					)
					(number "3"
						(effects
							(font
								(size 1.27 1.27)
							)
						)
					)
				)
				(pin bidirectional line
					(at 38.1 -40.64 180)
					(length 2.54)
					(name "LED2/NINTSEL"
						(effects
							(font
								(size 1.27 1.27)
							)
						)
					)
					(number "2"
						(effects
							(font
								(size 1.27 1.27)
							)
						)
					)
				)
				(pin input line
					(at 38.1 -45.72 180)
					(length 2.54)
					(name "RBIAS"
						(effects
							(font
								(size 1.27 1.27)
							)
						)
					)
					(number "24"
						(effects
							(font
								(size 1.27 1.27)
							)
						)
					)
				)
				(pin power_in line
					(at 38.1 -48.26 180)
					(length 2.54)
					(name "VSS"
						(effects
							(font
								(size 1.27 1.27)
							)
						)
					)
					(number "25"
						(effects
							(font
								(size 1.27 1.27)
							)
						)
					)
				)
			)
		)
	(symbol "antmicroInterfaceControllers:MAX3421EETJ+"
			(exclude_from_sim no)
			(in_bom yes)
			(on_board yes)
			(property "Reference" "U"
				(at 40.64 -5.08 0)
				(effects
					(font
						(size 1.27 1.27)
						(thickness 0.15)
					)
					(justify left bottom)
				)
			)
			(property "Value" "MAX3421EETJ+"
				(at 40.64 -7.62 0)
				(effects
					(font
						(size 1.27 1.27)
						(thickness 0.15)
					)
					(justify left bottom)
				)
			)
			(property "Footprint" "antmicro-footprints:QFN-32-1EP_5x5mm"
				(at 40.64 -10.16 0)
				(effects
					(font
						(size 1.27 1.27)
						(thickness 0.15)
					)
					(justify left bottom)
					(hide yes)
				)
			)
			(property "Datasheet" "https://www.analog.com/media/en/technical-documentation/data-sheets/max3421e.pdf"
				(at 40.64 -12.7 0)
				(effects
					(font
						(size 1.27 1.27)
						(thickness 0.15)
					)
					(justify left bottom)
					(hide yes)
				)
			)
			(property "Description" "USB Interface, ESD-Protected USB Peripheral/Host Controller, USB 2.0, 3 V, 3.6 V, TQFN, 32 Pins"
				(at 0 0 0)
				(effects
					(font
						(size 1.27 1.27)
					)
					(hide yes)
				)
			)
			(property "MPN" "MAX3421EETJ+"
				(at 40.64 -15.24 0)
				(effects
					(font
						(size 1.27 1.27)
						(thickness 0.15)
					)
					(justify left bottom)
					(hide yes)
				)
			)
			(property "Manufacturer" "Maxim Integrated Products"
				(at 40.64 -17.78 0)
				(effects
					(font
						(size 1.27 1.27)
						(thickness 0.15)
					)
					(justify left bottom)
					(hide yes)
				)
			)
			(property "Author" "Antmicro"
				(at 40.64 -20.32 0)
				(effects
					(font
						(size 1.27 1.27)
						(thickness 0.15)
					)
					(justify left bottom)
					(hide yes)
				)
			)
			(property "License" "Apache-2.0"
				(at 40.64 -22.86 0)
				(effects
					(font
						(size 1.27 1.27)
						(thickness 0.15)
					)
					(justify left bottom)
					(hide yes)
				)
			)
			(property "ki_keywords" "SMT, INTERFACE, IC, TRANSCEIVER"
				(at 0 0 0)
				(effects
					(font
						(size 1.27 1.27)
					)
					(hide yes)
				)
			)
			(symbol "MAX3421EETJ+_1_1"
				(rectangle
					(start 2.54 2.54)
					(end 25.4 -48.26)
					(stroke
						(width 0.254)
						(type default)
					)
					(fill
						(type background)
					)
				)
				(pin power_in line
					(at 0 0 0)
					(length 2.54)
					(name "VCC"
						(effects
							(font
								(size 1.27 1.27)
							)
						)
					)
					(number "23"
						(effects
							(font
								(size 1.27 1.27)
							)
						)
					)
				)
				(pin power_in line
					(at 0 -2.54 0)
					(length 2.54)
					(name "VL"
						(effects
							(font
								(size 1.27 1.27)
							)
						)
					)
					(number "2"
						(effects
							(font
								(size 1.27 1.27)
							)
						)
					)
				)
				(pin bidirectional line
					(at 0 -7.62 0)
					(length 2.54)
					(name "D-"
						(effects
							(font
								(size 1.27 1.27)
							)
						)
					)
					(number "20"
						(effects
							(font
								(size 1.27 1.27)
							)
						)
					)
				)
				(pin bidirectional line
					(at 0 -10.16 0)
					(length 2.54)
					(name "D+"
						(effects
							(font
								(size 1.27 1.27)
							)
						)
					)
					(number "21"
						(effects
							(font
								(size 1.27 1.27)
							)
						)
					)
				)
				(pin output line
					(at 0 -15.24 0)
					(length 2.54)
					(name "INT"
						(effects
							(font
								(size 1.27 1.27)
							)
						)
					)
					(number "18"
						(effects
							(font
								(size 1.27 1.27)
							)
						)
					)
				)
				(pin input line
					(at 0 -17.78 0)
					(length 2.54)
					(name "~{RES}"
						(effects
							(font
								(size 1.27 1.27)
							)
						)
					)
					(number "12"
						(effects
							(font
								(size 1.27 1.27)
							)
						)
					)
				)
				(pin input line
					(at 0 -20.32 0)
					(length 2.54)
					(name "SCLK"
						(effects
							(font
								(size 1.27 1.27)
							)
						)
					)
					(number "13"
						(effects
							(font
								(size 1.27 1.27)
							)
						)
					)
				)
				(pin input line
					(at 0 -22.86 0)
					(length 2.54)
					(name "~{SS}"
						(effects
							(font
								(size 1.27 1.27)
							)
						)
					)
					(number "14"
						(effects
							(font
								(size 1.27 1.27)
							)
						)
					)
				)
				(pin output line
					(at 0 -25.4 0)
					(length 2.54)
					(name "MISO"
						(effects
							(font
								(size 1.27 1.27)
							)
						)
					)
					(number "15"
						(effects
							(font
								(size 1.27 1.27)
							)
						)
					)
				)
				(pin input line
					(at 0 -27.94 0)
					(length 2.54)
					(name "MOSI"
						(effects
							(font
								(size 1.27 1.27)
							)
						)
					)
					(number "16"
						(effects
							(font
								(size 1.27 1.27)
							)
						)
					)
				)
				(pin output line
					(at 0 -30.48 0)
					(length 2.54)
					(name "GPX"
						(effects
							(font
								(size 1.27 1.27)
							)
						)
					)
					(number "17"
						(effects
							(font
								(size 1.27 1.27)
							)
						)
					)
				)
				(pin input line
					(at 0 -35.56 0)
					(length 2.54)
					(name "XI"
						(effects
							(font
								(size 1.27 1.27)
							)
						)
					)
					(number "24"
						(effects
							(font
								(size 1.27 1.27)
							)
						)
					)
				)
				(pin output line
					(at 0 -38.1 0)
					(length 2.54)
					(name "XO"
						(effects
							(font
								(size 1.27 1.27)
							)
						)
					)
					(number "25"
						(effects
							(font
								(size 1.27 1.27)
							)
						)
					)
				)
				(pin input line
					(at 0 -43.18 0)
					(length 2.54)
					(name "VBCOMP"
						(effects
							(font
								(size 1.27 1.27)
							)
						)
					)
					(number "22"
						(effects
							(font
								(size 1.27 1.27)
							)
						)
					)
				)
				(pin passive line
					(at 0 -45.72 0)
					(length 2.54)
					(name "GND"
						(effects
							(font
								(size 1.27 1.27)
							)
						)
					)
					(number "19"
						(effects
							(font
								(size 1.27 1.27)
							)
						)
					)
				)
				(pin passive line
					(at 0 -45.72 0)
					(length 2.54)
					(hide yes)
					(name "GND"
						(effects
							(font
								(size 1.27 1.27)
							)
						)
					)
					(number "3"
						(effects
							(font
								(size 1.27 1.27)
							)
						)
					)
				)
				(pin passive line
					(at 0 -45.72 0)
					(length 2.54)
					(hide yes)
					(name "EP"
						(effects
							(font
								(size 1.27 1.27)
							)
						)
					)
					(number "33"
						(effects
							(font
								(size 1.27 1.27)
							)
						)
					)
				)
				(pin output line
					(at 27.94 0 180)
					(length 2.54)
					(name "GPOUT0"
						(effects
							(font
								(size 1.27 1.27)
							)
						)
					)
					(number "4"
						(effects
							(font
								(size 1.27 1.27)
							)
						)
					)
				)
				(pin output line
					(at 27.94 -2.54 180)
					(length 2.54)
					(name "GPOUT1"
						(effects
							(font
								(size 1.27 1.27)
							)
						)
					)
					(number "5"
						(effects
							(font
								(size 1.27 1.27)
							)
						)
					)
				)
				(pin output line
					(at 27.94 -5.08 180)
					(length 2.54)
					(name "GPOUT2"
						(effects
							(font
								(size 1.27 1.27)
							)
						)
					)
					(number "6"
						(effects
							(font
								(size 1.27 1.27)
							)
						)
					)
				)
				(pin output line
					(at 27.94 -7.62 180)
					(length 2.54)
					(name "GPOUT3"
						(effects
							(font
								(size 1.27 1.27)
							)
						)
					)
					(number "7"
						(effects
							(font
								(size 1.27 1.27)
							)
						)
					)
				)
				(pin output line
					(at 27.94 -10.16 180)
					(length 2.54)
					(name "GPOUT4"
						(effects
							(font
								(size 1.27 1.27)
							)
						)
					)
					(number "8"
						(effects
							(font
								(size 1.27 1.27)
							)
						)
					)
				)
				(pin output line
					(at 27.94 -12.7 180)
					(length 2.54)
					(name "GPOUT5"
						(effects
							(font
								(size 1.27 1.27)
							)
						)
					)
					(number "9"
						(effects
							(font
								(size 1.27 1.27)
							)
						)
					)
				)
				(pin output line
					(at 27.94 -15.24 180)
					(length 2.54)
					(name "GPOUT6"
						(effects
							(font
								(size 1.27 1.27)
							)
						)
					)
					(number "10"
						(effects
							(font
								(size 1.27 1.27)
							)
						)
					)
				)
				(pin output line
					(at 27.94 -17.78 180)
					(length 2.54)
					(name "GPOUT7"
						(effects
							(font
								(size 1.27 1.27)
							)
						)
					)
					(number "11"
						(effects
							(font
								(size 1.27 1.27)
							)
						)
					)
				)
				(pin input line
					(at 27.94 -20.32 180)
					(length 2.54)
					(name "GPIN0"
						(effects
							(font
								(size 1.27 1.27)
							)
						)
					)
					(number "26"
						(effects
							(font
								(size 1.27 1.27)
							)
						)
					)
				)
				(pin input line
					(at 27.94 -22.86 180)
					(length 2.54)
					(name "GPIN1"
						(effects
							(font
								(size 1.27 1.27)
							)
						)
					)
					(number "27"
						(effects
							(font
								(size 1.27 1.27)
							)
						)
					)
				)
				(pin input line
					(at 27.94 -25.4 180)
					(length 2.54)
					(name "GPIN2"
						(effects
							(font
								(size 1.27 1.27)
							)
						)
					)
					(number "28"
						(effects
							(font
								(size 1.27 1.27)
							)
						)
					)
				)
				(pin input line
					(at 27.94 -27.94 180)
					(length 2.54)
					(name "GPIN3"
						(effects
							(font
								(size 1.27 1.27)
							)
						)
					)
					(number "29"
						(effects
							(font
								(size 1.27 1.27)
							)
						)
					)
				)
				(pin input line
					(at 27.94 -30.48 180)
					(length 2.54)
					(name "GPIN4"
						(effects
							(font
								(size 1.27 1.27)
							)
						)
					)
					(number "30"
						(effects
							(font
								(size 1.27 1.27)
							)
						)
					)
				)
				(pin input line
					(at 27.94 -33.02 180)
					(length 2.54)
					(name "GPIN5"
						(effects
							(font
								(size 1.27 1.27)
							)
						)
					)
					(number "31"
						(effects
							(font
								(size 1.27 1.27)
							)
						)
					)
				)
				(pin input line
					(at 27.94 -35.56 180)
					(length 2.54)
					(name "GPIN6"
						(effects
							(font
								(size 1.27 1.27)
							)
						)
					)
					(number "32"
						(effects
							(font
								(size 1.27 1.27)
							)
						)
					)
				)
				(pin input line
					(at 27.94 -38.1 180)
					(length 2.54)
					(name "GPIN7"
						(effects
							(font
								(size 1.27 1.27)
							)
						)
					)
					(number "1"
						(effects
							(font
								(size 1.27 1.27)
							)
						)
					)
				)
			)
		)
	(symbol "antmicroInterfaceControllers:TUSB1106RSVR"
			(exclude_from_sim no)
			(in_bom yes)
			(on_board yes)
			(property "Reference" "U"
				(at 36.83 -3.81 0)
				(effects
					(font
						(size 1.27 1.27)
						(thickness 0.15)
					)
					(justify left bottom)
				)
			)
			(property "Value" "TUSB1106RSVR"
				(at 36.83 -6.35 0)
				(effects
					(font
						(size 1.27 1.27)
						(thickness 0.15)
					)
					(justify left bottom)
				)
			)
			(property "Footprint" "antmicro-footprints:UQFN-16-1.8x2.6mm_P0.4mm_Texas_RSV0016A"
				(at 36.83 -8.89 0)
				(effects
					(font
						(size 1.27 1.27)
						(thickness 0.15)
					)
					(justify left bottom)
					(hide yes)
				)
			)
			(property "Datasheet" "https://www.ti.com/lit/ds/symlink/tusb1106.pdf?ts=1672125307635&ref_url=https%253A%252F%252Fwww.ti.com%252Fproduct%252FTUSB1106%252Fpart-details%252FTUSB1106RTZR"
				(at 36.83 -11.43 0)
				(effects
					(font
						(size 1.27 1.27)
						(thickness 0.15)
					)
					(justify left bottom)
					(hide yes)
				)
			)
			(property "Description" "1/1 Transceiver Half USB 2.0 16-UQFN"
				(at 0 0 0)
				(effects
					(font
						(size 1.27 1.27)
					)
					(hide yes)
				)
			)
			(property "MPN" "TUSB1106RSVR"
				(at 36.83 -13.97 0)
				(effects
					(font
						(size 1.27 1.27)
						(thickness 0.15)
					)
					(justify left bottom)
					(hide yes)
				)
			)
			(property "Manufacturer" "Texas Instruments"
				(at 36.83 -16.51 0)
				(effects
					(font
						(size 1.27 1.27)
						(thickness 0.15)
					)
					(justify left bottom)
					(hide yes)
				)
			)
			(property "Author" "Antmicro"
				(at 36.83 -19.05 0)
				(effects
					(font
						(size 1.27 1.27)
						(thickness 0.15)
					)
					(justify left bottom)
					(hide yes)
				)
			)
			(property "License" "Apache-2.0"
				(at 36.83 -21.59 0)
				(effects
					(font
						(size 1.27 1.27)
						(thickness 0.15)
					)
					(justify left bottom)
					(hide yes)
				)
			)
			(property "ki_keywords" "IC"
				(at 0 0 0)
				(effects
					(font
						(size 1.27 1.27)
					)
					(hide yes)
				)
			)
			(symbol "TUSB1106RSVR_1_1"
				(rectangle
					(start 2.54 2.54)
					(end 20.32 -27.94)
					(stroke
						(width 0.254)
						(type default)
					)
					(fill
						(type background)
					)
				)
				(pin power_out line
					(at 0 0 0)
					(length 2.54)
					(name "VREG"
						(effects
							(font
								(size 1.27 1.27)
							)
						)
					)
					(number "13"
						(effects
							(font
								(size 1.27 1.27)
							)
						)
					)
				)
				(pin power_in line
					(at 0 -2.54 0)
					(length 2.54)
					(name "VCC"
						(effects
							(font
								(size 1.27 1.27)
							)
						)
					)
					(number "14"
						(effects
							(font
								(size 1.27 1.27)
							)
						)
					)
				)
				(pin input line
					(at 0 -10.16 0)
					(length 2.54)
					(name "VPU"
						(effects
							(font
								(size 1.27 1.27)
							)
						)
					)
					(number "15"
						(effects
							(font
								(size 1.27 1.27)
							)
						)
					)
				)
				(pin bidirectional line
					(at 0 -17.78 0)
					(length 2.54)
					(name "D-"
						(effects
							(font
								(size 1.27 1.27)
							)
						)
					)
					(number "9"
						(effects
							(font
								(size 1.27 1.27)
							)
						)
					)
				)
				(pin bidirectional line
					(at 0 -20.32 0)
					(length 2.54)
					(name "D+"
						(effects
							(font
								(size 1.27 1.27)
							)
						)
					)
					(number "10"
						(effects
							(font
								(size 1.27 1.27)
							)
						)
					)
				)
				(pin power_in line
					(at 0 -25.4 0)
					(length 2.54)
					(name "GND"
						(effects
							(font
								(size 1.27 1.27)
							)
						)
					)
					(number "6"
						(effects
							(font
								(size 1.27 1.27)
							)
						)
					)
				)
				(pin power_in line
					(at 22.86 0 180)
					(length 2.54)
					(name "VCCIO"
						(effects
							(font
								(size 1.27 1.27)
							)
						)
					)
					(number "7"
						(effects
							(font
								(size 1.27 1.27)
							)
						)
					)
				)
				(pin input line
					(at 22.86 -5.08 180)
					(length 2.54)
					(name "~{OE}"
						(effects
							(font
								(size 1.27 1.27)
							)
						)
					)
					(number "1"
						(effects
							(font
								(size 1.27 1.27)
							)
						)
					)
				)
				(pin input line
					(at 22.86 -7.62 180)
					(length 2.54)
					(name "SUSPND"
						(effects
							(font
								(size 1.27 1.27)
							)
						)
					)
					(number "5"
						(effects
							(font
								(size 1.27 1.27)
							)
						)
					)
				)
				(pin input line
					(at 22.86 -10.16 180)
					(length 2.54)
					(name "SPEEED"
						(effects
							(font
								(size 1.27 1.27)
							)
						)
					)
					(number "8"
						(effects
							(font
								(size 1.27 1.27)
							)
						)
					)
				)
				(pin output line
					(at 22.86 -12.7 180)
					(length 2.54)
					(name "VM"
						(effects
							(font
								(size 1.27 1.27)
							)
						)
					)
					(number "4"
						(effects
							(font
								(size 1.27 1.27)
							)
						)
					)
				)
				(pin output line
					(at 22.86 -15.24 180)
					(length 2.54)
					(name "VP"
						(effects
							(font
								(size 1.27 1.27)
							)
						)
					)
					(number "3"
						(effects
							(font
								(size 1.27 1.27)
							)
						)
					)
				)
				(pin input line
					(at 22.86 -17.78 180)
					(length 2.54)
					(name "VPO"
						(effects
							(font
								(size 1.27 1.27)
							)
						)
					)
					(number "11"
						(effects
							(font
								(size 1.27 1.27)
							)
						)
					)
				)
				(pin input line
					(at 22.86 -20.32 180)
					(length 2.54)
					(name "VMO"
						(effects
							(font
								(size 1.27 1.27)
							)
						)
					)
					(number "12"
						(effects
							(font
								(size 1.27 1.27)
							)
						)
					)
				)
				(pin output line
					(at 22.86 -22.86 180)
					(length 2.54)
					(name "RCV"
						(effects
							(font
								(size 1.27 1.27)
							)
						)
					)
					(number "2"
						(effects
							(font
								(size 1.27 1.27)
							)
						)
					)
				)
				(pin input line
					(at 22.86 -25.4 180)
					(length 2.54)
					(name "SOFTCON"
						(effects
							(font
								(size 1.27 1.27)
							)
						)
					)
					(number "16"
						(effects
							(font
								(size 1.27 1.27)
							)
						)
					)
				)
			)
		)
	(symbol "antmicroLEDIndicationDiscrete:LED_B_0603_KP-1608QBC-D"
			(pin_numbers
				(hide yes)
			)
			(pin_names
				(hide yes)
			)
			(exclude_from_sim no)
			(in_bom yes)
			(on_board yes)
			(property "Reference" "D"
				(at 22.86 -2.54 0)
				(effects
					(font
						(size 1.27 1.27)
						(thickness 0.15)
					)
					(justify left bottom)
				)
			)
			(property "Value" "LED_B_0603_KP-1608QBC-D"
				(at 22.86 -7.62 0)
				(effects
					(font
						(size 1.27 1.27)
						(thickness 0.15)
					)
					(justify left bottom)
					(hide yes)
				)
			)
			(property "Footprint" "antmicro-footprints:LED_0603_1608Metric_B"
				(at 22.86 -10.16 0)
				(effects
					(font
						(size 1.27 1.27)
						(thickness 0.15)
					)
					(justify left bottom)
					(hide yes)
				)
			)
			(property "Datasheet" "https://www.kingbright.com/attachments/file/psearch/000/00/00/KP-1608QBC-D(Ver.24B).pdf"
				(at 22.86 -12.7 0)
				(effects
					(font
						(size 1.27 1.27)
						(thickness 0.15)
					)
					(justify left bottom)
					(hide yes)
				)
			)
			(property "Description" "LED, Blue, SMD, 0603, 20 mA, 3.3 V, 465 nm"
				(at 0 0 0)
				(effects
					(font
						(size 1.27 1.27)
					)
					(hide yes)
				)
			)
			(property "MPN" "KP-1608QBC-D"
				(at 22.86 -15.24 0)
				(effects
					(font
						(size 1.27 1.27)
						(thickness 0.15)
					)
					(justify left bottom)
					(hide yes)
				)
			)
			(property "Manufacturer" "Kingbright"
				(at 22.86 -17.78 0)
				(effects
					(font
						(size 1.27 1.27)
						(thickness 0.15)
					)
					(justify left bottom)
					(hide yes)
				)
			)
			(property "Color" "Blue"
				(at 22.86 -5.08 0)
				(effects
					(font
						(size 1.27 1.27)
						(thickness 0.15)
					)
					(justify left bottom)
				)
			)
			(property "Public" "False"
				(at 20.32 -17.78 0)
				(effects
					(font
						(size 1.27 1.27)
					)
					(justify left bottom)
					(hide yes)
				)
			)
			(property "Author" "Antmicro"
				(at 22.86 -20.32 0)
				(effects
					(font
						(size 1.27 1.27)
						(thickness 0.15)
					)
					(justify left bottom)
					(hide yes)
				)
			)
			(property "License" "Apache-2.0"
				(at 22.86 -22.86 0)
				(effects
					(font
						(size 1.27 1.27)
						(thickness 0.15)
					)
					(justify left bottom)
					(hide yes)
				)
			)
			(property "ki_keywords" "SMT, DIODE, SEMICONDUCTOR, LED"
				(at 0 0 0)
				(effects
					(font
						(size 1.27 1.27)
					)
					(hide yes)
				)
			)
			(symbol "LED_B_0603_KP-1608QBC-D_0_1"
				(polyline
					(pts
						(xy 1.905 0) (xy 0.635 0)
					)
					(stroke
						(width 0)
						(type default)
					)
					(fill
						(type none)
					)
				)
				(polyline
					(pts
						(xy 4.445 0) (xy 3.175 0)
					)
					(stroke
						(width 0)
						(type default)
					)
					(fill
						(type none)
					)
				)
			)
			(symbol "LED_B_0603_KP-1608QBC-D_1_1"
				(polyline
					(pts
						(xy 1.143 2.286) (xy 1.143 1.778) (xy 1.143 2.286) (xy 1.651 2.286) (xy 1.143 2.286) (xy 2.159 1.27)
					)
					(stroke
						(width 0.254)
						(type default)
					)
					(fill
						(type none)
					)
				)
				(polyline
					(pts
						(xy 1.778 1.016) (xy 1.778 -1.016)
					)
					(stroke
						(width 0.254)
						(type default)
					)
					(fill
						(type none)
					)
				)
				(polyline
					(pts
						(xy 2.159 2.54) (xy 2.159 2.032) (xy 2.159 2.54) (xy 2.667 2.54) (xy 2.159 2.54) (xy 3.048 1.651)
					)
					(stroke
						(width 0.254)
						(type default)
					)
					(fill
						(type none)
					)
				)
				(polyline
					(pts
						(xy 3.302 1.016) (xy 3.302 -1.016) (xy 1.778 0) (xy 3.302 1.016)
					)
					(stroke
						(width 0.254)
						(type default)
					)
					(fill
						(type outline)
					)
				)
				(pin passive line
					(at 0 0 0)
					(length 0.635)
					(name "C"
						(effects
							(font
								(size 1.27 1.27)
							)
						)
					)
					(number "1"
						(effects
							(font
								(size 1.27 1.27)
							)
						)
					)
				)
				(pin passive line
					(at 5.08 0 180)
					(length 0.635)
					(name "A"
						(effects
							(font
								(size 1.27 1.27)
							)
						)
					)
					(number "2"
						(effects
							(font
								(size 1.27 1.27)
							)
						)
					)
				)
			)
		)
	(symbol "antmicroLEDIndicationDiscrete:LED_G_0603_KP-1608CGCK"
			(pin_numbers
				(hide yes)
			)
			(pin_names
				(hide yes)
			)
			(exclude_from_sim no)
			(in_bom yes)
			(on_board yes)
			(property "Reference" "D"
				(at 22.86 -2.54 0)
				(effects
					(font
						(size 1.27 1.27)
						(thickness 0.15)
					)
					(justify left bottom)
				)
			)
			(property "Value" "LED_G_0603_KP-1608CGCK"
				(at 22.86 -7.62 0)
				(effects
					(font
						(size 1.27 1.27)
						(thickness 0.15)
					)
					(justify left bottom)
					(hide yes)
				)
			)
			(property "Footprint" "antmicro-footprints:LED_0603_1608Metric_G"
				(at 22.86 -10.16 0)
				(effects
					(font
						(size 1.27 1.27)
						(thickness 0.15)
					)
					(justify left bottom)
					(hide yes)
				)
			)
			(property "Datasheet" "http://www.kingbright.com/attachments/file/psearch//000/00/00/KP-1608CGCK(Ver.23B).pdf"
				(at 22.86 -12.7 0)
				(effects
					(font
						(size 1.27 1.27)
						(thickness 0.15)
					)
					(justify left bottom)
					(hide yes)
				)
			)
			(property "Description" "LED, Green, SMD, 0603, 20 mA, 2.1 V, 570 nm"
				(at 0 0 0)
				(effects
					(font
						(size 1.27 1.27)
					)
					(hide yes)
				)
			)
			(property "MPN" "KP-1608CGCK"
				(at 22.86 -15.24 0)
				(effects
					(font
						(size 1.27 1.27)
						(thickness 0.15)
					)
					(justify left bottom)
					(hide yes)
				)
			)
			(property "Manufacturer" "Kingbright"
				(at 22.86 -17.78 0)
				(effects
					(font
						(size 1.27 1.27)
						(thickness 0.15)
					)
					(justify left bottom)
					(hide yes)
				)
			)
			(property "Color" "Green"
				(at 22.86 -5.08 0)
				(effects
					(font
						(size 1.27 1.27)
					)
					(justify left bottom)
				)
			)
			(property "Author" "Antmicro"
				(at 22.86 -20.32 0)
				(effects
					(font
						(size 1.27 1.27)
						(thickness 0.15)
					)
					(justify left bottom)
					(hide yes)
				)
			)
			(property "License" "Apache-2.0"
				(at 22.86 -22.86 0)
				(effects
					(font
						(size 1.27 1.27)
						(thickness 0.15)
					)
					(justify left bottom)
					(hide yes)
				)
			)
			(property "ki_keywords" "SMT, DIODE, SEMICONDUCTOR, LED"
				(at 0 0 0)
				(effects
					(font
						(size 1.27 1.27)
					)
					(hide yes)
				)
			)
			(symbol "LED_G_0603_KP-1608CGCK_0_1"
				(polyline
					(pts
						(xy 1.905 0) (xy 0.635 0)
					)
					(stroke
						(width 0)
						(type default)
					)
					(fill
						(type none)
					)
				)
				(polyline
					(pts
						(xy 4.445 0) (xy 3.175 0)
					)
					(stroke
						(width 0)
						(type default)
					)
					(fill
						(type none)
					)
				)
			)
			(symbol "LED_G_0603_KP-1608CGCK_1_1"
				(polyline
					(pts
						(xy 1.143 2.286) (xy 1.143 1.778) (xy 1.143 2.286) (xy 1.651 2.286) (xy 1.143 2.286) (xy 2.159 1.27)
					)
					(stroke
						(width 0.254)
						(type default)
					)
					(fill
						(type none)
					)
				)
				(polyline
					(pts
						(xy 1.778 1.016) (xy 1.778 -1.016)
					)
					(stroke
						(width 0.254)
						(type default)
					)
					(fill
						(type none)
					)
				)
				(polyline
					(pts
						(xy 2.159 2.54) (xy 2.159 2.032) (xy 2.159 2.54) (xy 2.667 2.54) (xy 2.159 2.54) (xy 3.048 1.651)
					)
					(stroke
						(width 0.254)
						(type default)
					)
					(fill
						(type none)
					)
				)
				(polyline
					(pts
						(xy 3.302 1.016) (xy 3.302 -1.016) (xy 1.778 0) (xy 3.302 1.016)
					)
					(stroke
						(width 0.254)
						(type default)
					)
					(fill
						(type outline)
					)
				)
				(pin passive line
					(at 0 0 0)
					(length 0.635)
					(name "C"
						(effects
							(font
								(size 1.27 1.27)
							)
						)
					)
					(number "1"
						(effects
							(font
								(size 1.27 1.27)
							)
						)
					)
				)
				(pin passive line
					(at 5.08 0 180)
					(length 0.635)
					(name "A"
						(effects
							(font
								(size 1.27 1.27)
							)
						)
					)
					(number "2"
						(effects
							(font
								(size 1.27 1.27)
							)
						)
					)
				)
			)
		)
	(symbol "antmicroLEDIndicationDiscrete:LED_R_0603_KP-1608EC"
			(pin_numbers
				(hide yes)
			)
			(pin_names
				(hide yes)
			)
			(exclude_from_sim no)
			(in_bom yes)
			(on_board yes)
			(property "Reference" "D"
				(at 22.86 -2.54 0)
				(effects
					(font
						(size 1.27 1.27)
						(thickness 0.15)
					)
					(justify left bottom)
				)
			)
			(property "Value" "LED_R_0603_KP-1608EC"
				(at 22.86 -7.62 0)
				(effects
					(font
						(size 1.27 1.27)
						(thickness 0.15)
					)
					(justify left bottom)
					(hide yes)
				)
			)
			(property "Footprint" "antmicro-footprints:LED_0603_1608Metric_R"
				(at 22.86 -10.16 0)
				(effects
					(font
						(size 1.27 1.27)
						(thickness 0.15)
					)
					(justify left bottom)
					(hide yes)
				)
			)
			(property "Datasheet" "http://www.kingbright.com/attachments/file/psearch/000/00/20131112/KP-1608EC(Ver.14A).pdf"
				(at 22.86 -12.7 0)
				(effects
					(font
						(size 1.27 1.27)
						(thickness 0.15)
					)
					(justify left bottom)
					(hide yes)
				)
			)
			(property "Description" "LED, Red, SMD, 0603, 30 mA, 2 V, 617 nm"
				(at 0 0 0)
				(effects
					(font
						(size 1.27 1.27)
					)
					(hide yes)
				)
			)
			(property "MPN" "KP-1608EC"
				(at 22.86 -15.24 0)
				(effects
					(font
						(size 1.27 1.27)
						(thickness 0.15)
					)
					(justify left bottom)
					(hide yes)
				)
			)
			(property "Manufacturer" "Kingbright"
				(at 22.86 -17.78 0)
				(effects
					(font
						(size 1.27 1.27)
						(thickness 0.15)
					)
					(justify left bottom)
					(hide yes)
				)
			)
			(property "Public" "False"
				(at 20.32 -17.78 0)
				(effects
					(font
						(size 1.27 1.27)
					)
					(justify left bottom)
					(hide yes)
				)
			)
			(property "Color" "Red"
				(at 22.86 -5.08 0)
				(effects
					(font
						(size 1.27 1.27)
					)
					(justify left bottom)
				)
			)
			(property "Author" "Antmicro"
				(at 22.86 -20.32 0)
				(effects
					(font
						(size 1.27 1.27)
						(thickness 0.15)
					)
					(justify left bottom)
					(hide yes)
				)
			)
			(property "License" "Apache-2.0"
				(at 22.86 -22.86 0)
				(effects
					(font
						(size 1.27 1.27)
						(thickness 0.15)
					)
					(justify left bottom)
					(hide yes)
				)
			)
			(property "ki_keywords" "SMT, DIODE, SEMICONDUCTOR, LED"
				(at 0 0 0)
				(effects
					(font
						(size 1.27 1.27)
					)
					(hide yes)
				)
			)
			(symbol "LED_R_0603_KP-1608EC_0_1"
				(polyline
					(pts
						(xy 1.905 0) (xy 0.635 0)
					)
					(stroke
						(width 0)
						(type default)
					)
					(fill
						(type none)
					)
				)
				(polyline
					(pts
						(xy 4.445 0) (xy 3.175 0)
					)
					(stroke
						(width 0)
						(type default)
					)
					(fill
						(type none)
					)
				)
			)
			(symbol "LED_R_0603_KP-1608EC_1_1"
				(polyline
					(pts
						(xy 1.143 2.286) (xy 1.143 1.778) (xy 1.143 2.286) (xy 1.651 2.286) (xy 1.143 2.286) (xy 2.159 1.27)
					)
					(stroke
						(width 0.254)
						(type default)
					)
					(fill
						(type none)
					)
				)
				(polyline
					(pts
						(xy 1.778 1.016) (xy 1.778 -1.016)
					)
					(stroke
						(width 0.254)
						(type default)
					)
					(fill
						(type none)
					)
				)
				(polyline
					(pts
						(xy 2.159 2.54) (xy 2.159 2.032) (xy 2.159 2.54) (xy 2.667 2.54) (xy 2.159 2.54) (xy 3.048 1.651)
					)
					(stroke
						(width 0.254)
						(type default)
					)
					(fill
						(type none)
					)
				)
				(polyline
					(pts
						(xy 3.302 1.016) (xy 3.302 -1.016) (xy 1.778 0) (xy 3.302 1.016)
					)
					(stroke
						(width 0.254)
						(type default)
					)
					(fill
						(type outline)
					)
				)
				(pin passive line
					(at 0 0 0)
					(length 0.635)
					(name "C"
						(effects
							(font
								(size 1.27 1.27)
							)
						)
					)
					(number "1"
						(effects
							(font
								(size 1.27 1.27)
							)
						)
					)
				)
				(pin passive line
					(at 5.08 0 180)
					(length 0.635)
					(name "A"
						(effects
							(font
								(size 1.27 1.27)
							)
						)
					)
					(number "2"
						(effects
							(font
								(size 1.27 1.27)
							)
						)
					)
				)
			)
		)
	(symbol "antmicroLogicBuffersDriversReceiversTransceivers:SN74LVC1G125_SOT"
			(exclude_from_sim no)
			(in_bom yes)
			(on_board yes)
			(property "Reference" "U"
				(at 31.75 -5.08 0)
				(effects
					(font
						(size 1.27 1.27)
						(thickness 0.15)
					)
					(justify left bottom)
				)
			)
			(property "Value" "SN74LVC1G125_SOT"
				(at 31.75 -7.62 0)
				(effects
					(font
						(size 1.27 1.27)
						(thickness 0.15)
					)
					(justify left bottom)
				)
			)
			(property "Footprint" "antmicro-footprints:SOT-753"
				(at 31.75 -10.16 0)
				(effects
					(font
						(size 1.27 1.27)
						(thickness 0.15)
					)
					(justify left bottom)
					(hide yes)
				)
			)
			(property "Datasheet" "http://www.ti.com/general/docs/suppproductinfo.tsp?distId=10&gotoUrl=http%3A%2F%2Fwww.ti.com%2Flit%2Fgpn%2Fsn74lvc1g125"
				(at 31.75 -12.7 0)
				(effects
					(font
						(size 1.27 1.27)
						(thickness 0.15)
					)
					(justify left bottom)
					(hide yes)
				)
			)
			(property "Description" "Buffer, 74LVC1G125, 1.65 V to 5.5 V, SOT-23-5"
				(at 0 0 0)
				(effects
					(font
						(size 1.27 1.27)
					)
					(hide yes)
				)
			)
			(property "MPN" "SN74LVC1G125DBVR"
				(at 31.75 -15.24 0)
				(effects
					(font
						(size 1.27 1.27)
						(thickness 0.15)
					)
					(justify left bottom)
					(hide yes)
				)
			)
			(property "Manufacturer" "Texas Instruments"
				(at 31.75 -17.78 0)
				(effects
					(font
						(size 1.27 1.27)
						(thickness 0.15)
					)
					(justify left bottom)
					(hide yes)
				)
			)
			(property "Author" "Antmicro"
				(at 31.75 -20.32 0)
				(effects
					(font
						(size 1.27 1.27)
						(thickness 0.15)
					)
					(justify left bottom)
					(hide yes)
				)
			)
			(property "License" "Apache-2.0"
				(at 31.75 -22.86 0)
				(effects
					(font
						(size 1.27 1.27)
						(thickness 0.15)
					)
					(justify left bottom)
					(hide yes)
				)
			)
			(property "ki_keywords" "SMT, LOGIC, IC, BUFFER, TRANSCEIVER, DRIVER"
				(at 0 0 0)
				(effects
					(font
						(size 1.27 1.27)
					)
					(hide yes)
				)
			)
			(symbol "SN74LVC1G125_SOT_1_1"
				(rectangle
					(start 2.54 2.54)
					(end 15.24 -10.16)
					(stroke
						(width 0.254)
						(type default)
					)
					(fill
						(type background)
					)
				)
				(polyline
					(pts
						(xy 5.715 -7.62) (xy 7.62 -7.62) (xy 7.62 -6.35)
					)
					(stroke
						(width 0.254)
						(type default)
					)
					(fill
						(type background)
					)
				)
				(polyline
					(pts
						(xy 6.35 -1.27) (xy 11.43 -3.81) (xy 6.35 -6.35) (xy 6.35 -1.27)
					)
					(stroke
						(width 0.254)
						(type default)
					)
					(fill
						(type background)
					)
				)
				(polyline
					(pts
						(xy 6.35 -3.81) (xy 4.445 -3.81)
					)
					(stroke
						(width 0.254)
						(type default)
					)
					(fill
						(type background)
					)
				)
				(circle
					(center 7.62 -6.096)
					(radius 0.284)
					(stroke
						(width 0.254)
						(type default)
					)
					(fill
						(type background)
					)
				)
				(polyline
					(pts
						(xy 11.43 -3.81) (xy 13.335 -3.81)
					)
					(stroke
						(width 0.254)
						(type default)
					)
					(fill
						(type background)
					)
				)
				(pin power_in line
					(at 0 0 0)
					(length 2.54)
					(name "V_{CC}"
						(effects
							(font
								(size 1.27 1.27)
							)
						)
					)
					(number "5"
						(effects
							(font
								(size 1.27 1.27)
							)
						)
					)
				)
				(pin input line
					(at 0 -3.81 0)
					(length 2.54)
					(name "A"
						(effects
							(font
								(size 1.27 1.27)
							)
						)
					)
					(number "2"
						(effects
							(font
								(size 1.27 1.27)
							)
						)
					)
				)
				(pin input line
					(at 0 -7.62 0)
					(length 2.54)
					(name "~{OE}"
						(effects
							(font
								(size 1.27 1.27)
							)
						)
					)
					(number "1"
						(effects
							(font
								(size 1.27 1.27)
							)
						)
					)
				)
				(pin output line
					(at 17.78 -3.81 180)
					(length 2.54)
					(name "Y"
						(effects
							(font
								(size 1.27 1.27)
							)
						)
					)
					(number "4"
						(effects
							(font
								(size 1.27 1.27)
							)
						)
					)
				)
				(pin power_in line
					(at 17.78 -7.62 180)
					(length 2.54)
					(name "GND"
						(effects
							(font
								(size 1.27 1.27)
							)
						)
					)
					(number "3"
						(effects
							(font
								(size 1.27 1.27)
							)
						)
					)
				)
			)
		)
	(symbol "antmicroLogicShiftRegisters:SN74HC595B"
			(exclude_from_sim no)
			(in_bom yes)
			(on_board yes)
			(property "Reference" "U"
				(at 35.56 -5.08 0)
				(effects
					(font
						(size 1.27 1.27)
						(thickness 0.15)
					)
					(justify left bottom)
				)
			)
			(property "Value" "SN74HC595B"
				(at 35.56 -7.62 0)
				(effects
					(font
						(size 1.27 1.27)
						(thickness 0.15)
					)
					(justify left bottom)
				)
			)
			(property "Footprint" "antmicro-footprints:X1QFN-16-1EP_2.5x2.5mm"
				(at 35.56 -10.16 0)
				(effects
					(font
						(size 1.27 1.27)
						(thickness 0.15)
					)
					(justify left bottom)
					(hide yes)
				)
			)
			(property "Datasheet" "https://www.ti.com/general/docs/suppproductinfo.tsp?distId=26&gotoUrl=https://www.ti.com/lit/gpn/sn74hc595b"
				(at 35.56 -12.7 0)
				(effects
					(font
						(size 1.27 1.27)
						(thickness 0.15)
					)
					(justify left bottom)
					(hide yes)
				)
			)
			(property "Description" "Shift Register, 74HC595, Serial to Parallel, 1 Element, 8 bit, X1QFN, 16 Pins"
				(at 0 0 0)
				(effects
					(font
						(size 1.27 1.27)
					)
					(hide yes)
				)
			)
			(property "Manufacturer" "Texas Instruments"
				(at 35.56 -15.24 0)
				(effects
					(font
						(size 1.27 1.27)
						(thickness 0.15)
					)
					(justify left bottom)
					(hide yes)
				)
			)
			(property "MPN" "SN74HC595BRWNR"
				(at 35.56 -17.78 0)
				(effects
					(font
						(size 1.27 1.27)
						(thickness 0.15)
					)
					(justify left bottom)
					(hide yes)
				)
			)
			(property "Author" "Antmicro"
				(at 35.56 -20.32 0)
				(effects
					(font
						(size 1.27 1.27)
						(thickness 0.15)
					)
					(justify left bottom)
					(hide yes)
				)
			)
			(property "License" "Apache-2.0"
				(at 35.56 -22.86 0)
				(effects
					(font
						(size 1.27 1.27)
						(thickness 0.15)
					)
					(justify left bottom)
					(hide yes)
				)
			)
			(property "ki_keywords" "SMT, LOGIC, IC, LEVEL-SHIFTER, VOLTAGE"
				(at 0 0 0)
				(effects
					(font
						(size 1.27 1.27)
					)
					(hide yes)
				)
			)
			(symbol "SN74HC595B_1_1"
				(rectangle
					(start 2.54 2.54)
					(end 17.78 -22.86)
					(stroke
						(width 0.254)
						(type default)
					)
					(fill
						(type background)
					)
				)
				(pin power_in line
					(at 0 0 0)
					(length 2.54)
					(name "VCC"
						(effects
							(font
								(size 1.27 1.27)
							)
						)
					)
					(number "16"
						(effects
							(font
								(size 1.27 1.27)
							)
						)
					)
				)
				(pin input line
					(at 0 -5.08 0)
					(length 2.54)
					(name "~{OE}"
						(effects
							(font
								(size 1.27 1.27)
							)
						)
					)
					(number "13"
						(effects
							(font
								(size 1.27 1.27)
							)
						)
					)
				)
				(pin input line
					(at 0 -7.62 0)
					(length 2.54)
					(name "~{SRCLR}"
						(effects
							(font
								(size 1.27 1.27)
							)
						)
					)
					(number "10"
						(effects
							(font
								(size 1.27 1.27)
							)
						)
					)
				)
				(pin input line
					(at 0 -10.16 0)
					(length 2.54)
					(name "SRCLK"
						(effects
							(font
								(size 1.27 1.27)
							)
						)
					)
					(number "11"
						(effects
							(font
								(size 1.27 1.27)
							)
						)
					)
				)
				(pin input line
					(at 0 -12.7 0)
					(length 2.54)
					(name "RCLK"
						(effects
							(font
								(size 1.27 1.27)
							)
						)
					)
					(number "12"
						(effects
							(font
								(size 1.27 1.27)
							)
						)
					)
				)
				(pin input line
					(at 0 -15.24 0)
					(length 2.54)
					(name "SER"
						(effects
							(font
								(size 1.27 1.27)
							)
						)
					)
					(number "14"
						(effects
							(font
								(size 1.27 1.27)
							)
						)
					)
				)
				(pin power_in line
					(at 0 -20.32 0)
					(length 2.54)
					(name "GND"
						(effects
							(font
								(size 1.27 1.27)
							)
						)
					)
					(number "8"
						(effects
							(font
								(size 1.27 1.27)
							)
						)
					)
				)
				(pin no_connect line
					(at 10.16 -22.86 90)
					(length 2.54)
					(hide yes)
					(name "EP"
						(effects
							(font
								(size 1.27 1.27)
							)
						)
					)
					(number "17"
						(effects
							(font
								(size 1.27 1.27)
							)
						)
					)
				)
				(pin output line
					(at 20.32 0 180)
					(length 2.54)
					(name "QA"
						(effects
							(font
								(size 1.27 1.27)
							)
						)
					)
					(number "15"
						(effects
							(font
								(size 1.27 1.27)
							)
						)
					)
				)
				(pin output line
					(at 20.32 -2.54 180)
					(length 2.54)
					(name "QB"
						(effects
							(font
								(size 1.27 1.27)
							)
						)
					)
					(number "1"
						(effects
							(font
								(size 1.27 1.27)
							)
						)
					)
				)
				(pin output line
					(at 20.32 -5.08 180)
					(length 2.54)
					(name "QC"
						(effects
							(font
								(size 1.27 1.27)
							)
						)
					)
					(number "2"
						(effects
							(font
								(size 1.27 1.27)
							)
						)
					)
				)
				(pin output line
					(at 20.32 -7.62 180)
					(length 2.54)
					(name "QD"
						(effects
							(font
								(size 1.27 1.27)
							)
						)
					)
					(number "3"
						(effects
							(font
								(size 1.27 1.27)
							)
						)
					)
				)
				(pin output line
					(at 20.32 -10.16 180)
					(length 2.54)
					(name "QE"
						(effects
							(font
								(size 1.27 1.27)
							)
						)
					)
					(number "4"
						(effects
							(font
								(size 1.27 1.27)
							)
						)
					)
				)
				(pin output line
					(at 20.32 -12.7 180)
					(length 2.54)
					(name "QF"
						(effects
							(font
								(size 1.27 1.27)
							)
						)
					)
					(number "5"
						(effects
							(font
								(size 1.27 1.27)
							)
						)
					)
				)
				(pin output line
					(at 20.32 -15.24 180)
					(length 2.54)
					(name "QG"
						(effects
							(font
								(size 1.27 1.27)
							)
						)
					)
					(number "6"
						(effects
							(font
								(size 1.27 1.27)
							)
						)
					)
				)
				(pin output line
					(at 20.32 -17.78 180)
					(length 2.54)
					(name "QH"
						(effects
							(font
								(size 1.27 1.27)
							)
						)
					)
					(number "7"
						(effects
							(font
								(size 1.27 1.27)
							)
						)
					)
				)
				(pin output line
					(at 20.32 -20.32 180)
					(length 2.54)
					(name "QH'"
						(effects
							(font
								(size 1.27 1.27)
							)
						)
					)
					(number "9"
						(effects
							(font
								(size 1.27 1.27)
							)
						)
					)
				)
			)
		)
	(symbol "antmicroLogicTranslatorsLevelShifters:74LVC1T45GM"
			(exclude_from_sim no)
			(in_bom yes)
			(on_board yes)
			(property "Reference" "U"
				(at 30.48 -5.08 0)
				(effects
					(font
						(size 1.27 1.27)
						(thickness 0.15)
					)
					(justify left bottom)
				)
			)
			(property "Value" "74LVC1T45GM"
				(at 30.48 -7.62 0)
				(effects
					(font
						(size 1.27 1.27)
						(thickness 0.15)
					)
					(justify left bottom)
				)
			)
			(property "Footprint" "antmicro-footprints:SOT-886"
				(at 30.48 -10.16 0)
				(effects
					(font
						(size 1.27 1.27)
						(thickness 0.15)
					)
					(justify left bottom)
					(hide yes)
				)
			)
			(property "Datasheet" "http://www.ti.com/general/docs/suppproductinfo.tsp?distId=10&gotoUrl=http%3A%2F%2Fwww.ti.com%2Flit%2Fgpn%2Fsn74lvc1t45"
				(at 30.48 -12.7 0)
				(effects
					(font
						(size 1.27 1.27)
						(thickness 0.15)
					)
					(justify left bottom)
					(hide yes)
				)
			)
			(property "Description" "Transceiver, Translating, 74LVC1T45, 74LVC Family, 1.2V to 5.5V Supply, XSON-6"
				(at 0 0 0)
				(effects
					(font
						(size 1.27 1.27)
					)
					(hide yes)
				)
			)
			(property "MPN" "74LVC1T45GM-Q100X"
				(at 30.48 -15.24 0)
				(effects
					(font
						(size 1.27 1.27)
						(thickness 0.15)
					)
					(justify left bottom)
					(hide yes)
				)
			)
			(property "Manufacturer" "Nexperia"
				(at 30.48 -17.78 0)
				(effects
					(font
						(size 1.27 1.27)
						(thickness 0.15)
					)
					(justify left bottom)
					(hide yes)
				)
			)
			(property "Author" "Antmicro"
				(at 30.48 -20.32 0)
				(effects
					(font
						(size 1.27 1.27)
						(thickness 0.15)
					)
					(justify left bottom)
					(hide yes)
				)
			)
			(property "License" "Apache-2.0"
				(at 30.48 -22.86 0)
				(effects
					(font
						(size 1.27 1.27)
						(thickness 0.15)
					)
					(justify left bottom)
					(hide yes)
				)
			)
			(property "ki_keywords" "SMT, LOGIC, IC"
				(at 0 0 0)
				(effects
					(font
						(size 1.27 1.27)
					)
					(hide yes)
				)
			)
			(symbol "74LVC1T45GM_1_1"
				(rectangle
					(start 2.54 1.27)
					(end 13.97 -6.35)
					(stroke
						(width 0.254)
						(type default)
					)
					(fill
						(type background)
					)
				)
				(polyline
					(pts
						(xy 5.08 -2.54) (xy 6.35 -2.54)
					)
					(stroke
						(width 0.254)
						(type default)
					)
					(fill
						(type background)
					)
				)
				(polyline
					(pts
						(xy 6.35 -2.54) (xy 6.35 -1.905) (xy 7.62 -1.905)
					)
					(stroke
						(width 0.254)
						(type default)
					)
					(fill
						(type background)
					)
				)
				(polyline
					(pts
						(xy 6.35 -2.54) (xy 6.35 -3.175) (xy 7.747 -3.175)
					)
					(stroke
						(width 0.254)
						(type default)
					)
					(fill
						(type background)
					)
				)
				(polyline
					(pts
						(xy 7.62 -1.27) (xy 7.62 -2.54) (xy 8.89 -1.905) (xy 7.62 -1.27)
					)
					(stroke
						(width 0.254)
						(type default)
					)
					(fill
						(type background)
					)
				)
				(polyline
					(pts
						(xy 8.89 -2.54) (xy 8.89 -3.81) (xy 7.62 -3.175) (xy 8.89 -2.54)
					)
					(stroke
						(width 0.254)
						(type default)
					)
					(fill
						(type background)
					)
				)
				(polyline
					(pts
						(xy 10.16 -2.54) (xy 10.16 -1.905) (xy 8.89 -1.905)
					)
					(stroke
						(width 0.254)
						(type default)
					)
					(fill
						(type background)
					)
				)
				(polyline
					(pts
						(xy 10.16 -2.54) (xy 10.16 -3.175) (xy 8.89 -3.175)
					)
					(stroke
						(width 0.254)
						(type default)
					)
					(fill
						(type background)
					)
				)
				(polyline
					(pts
						(xy 11.43 -2.54) (xy 10.16 -2.54)
					)
					(stroke
						(width 0.254)
						(type default)
					)
					(fill
						(type background)
					)
				)
				(pin power_in line
					(at 0 0 0)
					(length 2.54)
					(name "VCCA"
						(effects
							(font
								(size 1.27 1.27)
							)
						)
					)
					(number "1"
						(effects
							(font
								(size 1.27 1.27)
							)
						)
					)
				)
				(pin bidirectional line
					(at 0 -2.54 0)
					(length 2.54)
					(name "A"
						(effects
							(font
								(size 1.27 1.27)
							)
						)
					)
					(number "3"
						(effects
							(font
								(size 1.27 1.27)
							)
						)
					)
				)
				(pin input line
					(at 0 -5.08 0)
					(length 2.54)
					(name "DIR"
						(effects
							(font
								(size 1.27 1.27)
							)
						)
					)
					(number "5"
						(effects
							(font
								(size 1.27 1.27)
							)
						)
					)
				)
				(pin power_in line
					(at 16.51 0 180)
					(length 2.54)
					(name "VCCB"
						(effects
							(font
								(size 1.27 1.27)
							)
						)
					)
					(number "6"
						(effects
							(font
								(size 1.27 1.27)
							)
						)
					)
				)
				(pin bidirectional line
					(at 16.51 -2.54 180)
					(length 2.54)
					(name "B"
						(effects
							(font
								(size 1.27 1.27)
							)
						)
					)
					(number "4"
						(effects
							(font
								(size 1.27 1.27)
							)
						)
					)
				)
				(pin power_in line
					(at 16.51 -5.08 180)
					(length 2.54)
					(name "GND"
						(effects
							(font
								(size 1.27 1.27)
							)
						)
					)
					(number "2"
						(effects
							(font
								(size 1.27 1.27)
							)
						)
					)
				)
			)
		)
	(symbol "antmicroLogicTranslatorsLevelShifters:TXU0304BQAR"
			(exclude_from_sim no)
			(in_bom yes)
			(on_board yes)
			(property "Reference" "U"
				(at 31.75 0 0)
				(effects
					(font
						(size 1.27 1.27)
						(thickness 0.15)
					)
					(justify left bottom)
				)
			)
			(property "Value" "TXU0304BQAR"
				(at 31.75 -2.54 0)
				(effects
					(font
						(size 1.27 1.27)
						(thickness 0.15)
					)
					(justify left bottom)
				)
			)
			(property "Footprint" "antmicro-footprints:DHVQFN-14-1EP_2.5x3mm"
				(at 31.75 -5.08 0)
				(effects
					(font
						(size 1.27 1.27)
						(thickness 0.15)
					)
					(justify left bottom)
					(hide yes)
				)
			)
			(property "Datasheet" "https://www.ti.com/lit/ds/symlink/txu0304.pdf?ts=1637748643258&ref_url=https%253A%252F%252Fwww.ti.com%252Fproduct%252FTXU0304"
				(at 31.75 -7.62 0)
				(effects
					(font
						(size 1.27 1.27)
						(thickness 0.15)
					)
					(justify left bottom)
					(hide yes)
				)
			)
			(property "Description" "Logic translator/level shifter"
				(at 0 0 0)
				(effects
					(font
						(size 1.27 1.27)
					)
					(hide yes)
				)
			)
			(property "MPN" "TXU0304BQAR"
				(at 31.75 -10.16 0)
				(effects
					(font
						(size 1.27 1.27)
						(thickness 0.15)
					)
					(justify left bottom)
					(hide yes)
				)
			)
			(property "Manufacturer" "Texas Instruments"
				(at 31.75 -12.7 0)
				(effects
					(font
						(size 1.27 1.27)
						(thickness 0.15)
					)
					(justify left bottom)
					(hide yes)
				)
			)
			(property "Author" "Antmicro"
				(at 31.75 -15.24 0)
				(effects
					(font
						(size 1.27 1.27)
						(thickness 0.15)
					)
					(justify left bottom)
					(hide yes)
				)
			)
			(property "License" "Apache-2.0"
				(at 31.75 -17.78 0)
				(effects
					(font
						(size 1.27 1.27)
						(thickness 0.15)
					)
					(justify left bottom)
					(hide yes)
				)
			)
			(property "ki_keywords" "SMT, LOGIC, IC, LEVEL-SHIFTER"
				(at 0 0 0)
				(effects
					(font
						(size 1.27 1.27)
					)
					(hide yes)
				)
			)
			(symbol "TXU0304BQAR_1_1"
				(rectangle
					(start 2.54 2.54)
					(end 15.24 -17.78)
					(stroke
						(width 0.254)
						(type default)
					)
					(fill
						(type background)
					)
				)
				(polyline
					(pts
						(xy 6.35 -7.62) (xy 10.16 -7.62)
					)
					(stroke
						(width 0.254)
						(type default)
					)
					(fill
						(type background)
					)
				)
				(polyline
					(pts
						(xy 6.35 -12.7) (xy 10.16 -12.7)
					)
					(stroke
						(width 0.254)
						(type default)
					)
					(fill
						(type background)
					)
				)
				(polyline
					(pts
						(xy 7.62 -4.445) (xy 7.62 -5.715) (xy 8.89 -5.08) (xy 7.62 -4.445)
					)
					(stroke
						(width 0.254)
						(type default)
					)
					(fill
						(type outline)
					)
				)
				(polyline
					(pts
						(xy 7.62 -6.985) (xy 7.62 -8.255) (xy 8.89 -7.62) (xy 7.62 -6.985)
					)
					(stroke
						(width 0.254)
						(type default)
					)
					(fill
						(type outline)
					)
				)
				(polyline
					(pts
						(xy 7.62 -12.7) (xy 8.89 -12.065) (xy 8.89 -13.335) (xy 7.62 -12.7)
					)
					(stroke
						(width 0.254)
						(type default)
					)
					(fill
						(type outline)
					)
				)
				(polyline
					(pts
						(xy 8.89 -10.16) (xy 7.62 -10.795) (xy 7.62 -9.525) (xy 8.89 -10.16)
					)
					(stroke
						(width 0.254)
						(type default)
					)
					(fill
						(type outline)
					)
				)
				(polyline
					(pts
						(xy 10.16 -5.08) (xy 6.35 -5.08)
					)
					(stroke
						(width 0.254)
						(type default)
					)
					(fill
						(type background)
					)
				)
				(polyline
					(pts
						(xy 10.16 -10.16) (xy 6.35 -10.16)
					)
					(stroke
						(width 0.254)
						(type default)
					)
					(fill
						(type background)
					)
				)
				(pin power_in line
					(at 0 0 0)
					(length 2.54)
					(name "VCCA"
						(effects
							(font
								(size 1.27 1.27)
							)
						)
					)
					(number "1"
						(effects
							(font
								(size 1.27 1.27)
							)
						)
					)
				)
				(pin input line
					(at 0 -5.08 0)
					(length 2.54)
					(name "A1"
						(effects
							(font
								(size 1.27 1.27)
							)
						)
					)
					(number "2"
						(effects
							(font
								(size 1.27 1.27)
							)
						)
					)
				)
				(pin input line
					(at 0 -7.62 0)
					(length 2.54)
					(name "A2"
						(effects
							(font
								(size 1.27 1.27)
							)
						)
					)
					(number "3"
						(effects
							(font
								(size 1.27 1.27)
							)
						)
					)
				)
				(pin input line
					(at 0 -10.16 0)
					(length 2.54)
					(name "A3"
						(effects
							(font
								(size 1.27 1.27)
							)
						)
					)
					(number "4"
						(effects
							(font
								(size 1.27 1.27)
							)
						)
					)
				)
				(pin output line
					(at 0 -12.7 0)
					(length 2.54)
					(name "A4Y"
						(effects
							(font
								(size 1.27 1.27)
							)
						)
					)
					(number "5"
						(effects
							(font
								(size 1.27 1.27)
							)
						)
					)
				)
				(pin power_in line
					(at 0 -15.24 0)
					(length 2.54)
					(name "GND"
						(effects
							(font
								(size 1.27 1.27)
							)
						)
					)
					(number "15"
						(effects
							(font
								(size 1.27 1.27)
							)
						)
					)
				)
				(pin passive line
					(at 0 -15.24 0)
					(length 2.54)
					(hide yes)
					(name "GND"
						(effects
							(font
								(size 1.27 1.27)
							)
						)
					)
					(number "7"
						(effects
							(font
								(size 1.27 1.27)
							)
						)
					)
				)
				(pin no_connect line
					(at 2.54 -2.54 0)
					(length 2.54)
					(hide yes)
					(name "NC"
						(effects
							(font
								(size 1.27 1.27)
							)
						)
					)
					(number "6"
						(effects
							(font
								(size 1.27 1.27)
							)
						)
					)
				)
				(pin no_connect line
					(at 15.24 -15.24 180)
					(length 2.54)
					(hide yes)
					(name "NC"
						(effects
							(font
								(size 1.27 1.27)
							)
						)
					)
					(number "9"
						(effects
							(font
								(size 1.27 1.27)
							)
						)
					)
				)
				(pin power_in line
					(at 17.78 0 180)
					(length 2.54)
					(name "VCCB"
						(effects
							(font
								(size 1.27 1.27)
							)
						)
					)
					(number "14"
						(effects
							(font
								(size 1.27 1.27)
							)
						)
					)
				)
				(pin tri_state line
					(at 17.78 -2.54 180)
					(length 2.54)
					(name "OE"
						(effects
							(font
								(size 1.27 1.27)
							)
						)
					)
					(number "8"
						(effects
							(font
								(size 1.27 1.27)
							)
						)
					)
				)
				(pin output line
					(at 17.78 -5.08 180)
					(length 2.54)
					(name "B1Y"
						(effects
							(font
								(size 1.27 1.27)
							)
						)
					)
					(number "13"
						(effects
							(font
								(size 1.27 1.27)
							)
						)
					)
				)
				(pin output line
					(at 17.78 -7.62 180)
					(length 2.54)
					(name "B2Y"
						(effects
							(font
								(size 1.27 1.27)
							)
						)
					)
					(number "12"
						(effects
							(font
								(size 1.27 1.27)
							)
						)
					)
				)
				(pin output line
					(at 17.78 -10.16 180)
					(length 2.54)
					(name "B3Y"
						(effects
							(font
								(size 1.27 1.27)
							)
						)
					)
					(number "11"
						(effects
							(font
								(size 1.27 1.27)
							)
						)
					)
				)
				(pin input line
					(at 17.78 -12.7 180)
					(length 2.54)
					(name "B4"
						(effects
							(font
								(size 1.27 1.27)
							)
						)
					)
					(number "10"
						(effects
							(font
								(size 1.27 1.27)
							)
						)
					)
				)
			)
		)
	(symbol "antmicroMechanicalParts:Heatsink_960-31-18-S-AB-0"
			(pin_names
				(hide yes)
			)
			(exclude_from_sim no)
			(in_bom yes)
			(on_board yes)
			(property "Reference" "H"
				(at 17.78 -2.54 0)
				(effects
					(font
						(size 1.27 1.27)
						(thickness 0.15)
					)
					(justify left bottom)
				)
			)
			(property "Value" "Heatsink_960-31-18-S-AB-0"
				(at 17.78 -5.08 0)
				(effects
					(font
						(size 1.27 1.27)
						(thickness 0.15)
					)
					(justify left bottom)
				)
			)
			(property "Footprint" "antmicro-footprints:Heatsink_960-31-18-S-AB-0"
				(at 17.78 -7.62 0)
				(effects
					(font
						(size 1.27 1.27)
						(thickness 0.15)
					)
					(justify left bottom)
					(hide yes)
				)
			)
			(property "Datasheet" "https://media.digikey.com/pdf/Data%20Sheets/Wakefield%20Thermal%20PDFs/960_Series.pdf"
				(at 17.78 -10.16 0)
				(effects
					(font
						(size 1.27 1.27)
						(thickness 0.15)
					)
					(justify left bottom)
					(hide yes)
				)
			)
			(property "Description" "Heat Sink BGA Aluminum Top Mount"
				(at 0 0 0)
				(effects
					(font
						(size 1.27 1.27)
					)
					(hide yes)
				)
			)
			(property "MPN" "960-31-18-S-AB-0"
				(at 17.78 -12.7 0)
				(effects
					(font
						(size 1.27 1.27)
						(thickness 0.15)
					)
					(justify left bottom)
					(hide yes)
				)
			)
			(property "Manufacturer" "Wakefield-Vette"
				(at 17.78 -15.24 0)
				(effects
					(font
						(size 1.27 1.27)
						(thickness 0.15)
					)
					(justify left bottom)
					(hide yes)
				)
			)
			(property "Author" "Antmicro"
				(at 17.78 -17.78 0)
				(effects
					(font
						(size 1.27 1.27)
						(thickness 0.15)
					)
					(justify left bottom)
					(hide yes)
				)
			)
			(property "License" "Apache-2.0"
				(at 17.78 -20.32 0)
				(effects
					(font
						(size 1.27 1.27)
						(thickness 0.15)
					)
					(justify left bottom)
					(hide yes)
				)
			)
			(property "ki_keywords" "HEATSINK"
				(at 0 0 0)
				(effects
					(font
						(size 1.27 1.27)
					)
					(hide yes)
				)
			)
			(property "ki_fp_filters" "Heatsink_*"
				(at 0 0 0)
				(effects
					(font
						(size 1.27 1.27)
					)
					(hide yes)
				)
			)
			(symbol "Heatsink_960-31-18-S-AB-0_1_1"
				(polyline
					(pts
						(xy -0.3302 1.27) (xy -0.9652 1.27) (xy -0.9652 3.81) (xy -1.6002 3.81) (xy -1.6002 1.27) (xy -2.2352 1.27)
						(xy -2.2352 3.81) (xy -2.8702 3.81) (xy -2.8702 0) (xy -0.9652 0)
					)
					(stroke
						(width 0.254)
						(type default)
					)
					(fill
						(type none)
					)
				)
				(polyline
					(pts
						(xy -0.3302 1.27) (xy -0.3302 3.81) (xy 0.3048 3.81) (xy 0.3048 1.27) (xy 0.9398 1.27) (xy 0.9398 3.81)
						(xy 1.5748 3.81) (xy 1.5748 1.27) (xy 2.2098 1.27) (xy 2.2098 3.81) (xy 2.8448 3.81) (xy 2.8448 0)
						(xy -0.9652 0)
					)
					(stroke
						(width 0.254)
						(type default)
					)
					(fill
						(type none)
					)
				)
			)
		)
	(symbol "antmicroMechanicalParts:MP_Pad6mm_Drill3mm"
			(pin_names
				(hide yes)
			)
			(exclude_from_sim no)
			(in_bom no)
			(on_board yes)
			(property "Reference" "MP"
				(at 20.32 -2.54 0)
				(effects
					(font
						(size 1.27 1.27)
						(thickness 0.15)
					)
					(justify left bottom)
				)
			)
			(property "Value" "MP_Pad6mm_Drill3mm"
				(at 20.32 -5.08 0)
				(effects
					(font
						(size 1.27 1.27)
						(thickness 0.15)
					)
					(justify left bottom)
				)
			)
			(property "Footprint" "antmicro-footprints:MP_Pad6mm_Drill3mm"
				(at 20.32 -7.62 0)
				(effects
					(font
						(size 1.27 1.27)
						(thickness 0.15)
					)
					(justify left bottom)
					(hide yes)
				)
			)
			(property "Datasheet" ""
				(at 16.84 -15.57 0)
				(effects
					(font
						(size 1.27 1.27)
						(thickness 0.15)
					)
					(justify left bottom)
					(hide yes)
				)
			)
			(property "Description" "Mechanical part"
				(at 0 0 0)
				(effects
					(font
						(size 1.27 1.27)
					)
					(hide yes)
				)
			)
			(property "Author" "Antmicro"
				(at 20.32 -10.16 0)
				(effects
					(font
						(size 1.27 1.27)
						(thickness 0.15)
					)
					(justify left bottom)
					(hide yes)
				)
			)
			(property "License" "Apache-2.0"
				(at 20.32 -12.7 0)
				(effects
					(font
						(size 1.27 1.27)
						(thickness 0.15)
					)
					(justify left bottom)
					(hide yes)
				)
			)
			(property "ki_keywords" "MECHANICAL"
				(at 0 0 0)
				(effects
					(font
						(size 1.27 1.27)
					)
					(hide yes)
				)
			)
			(symbol "MP_Pad6mm_Drill3mm_1_1"
				(circle
					(center 5.08 0)
					(radius 1.27)
					(stroke
						(width 0.254)
						(type default)
					)
					(fill
						(type background)
					)
				)
				(circle
					(center 5.08 0)
					(radius 2.54)
					(stroke
						(width 0.254)
						(type default)
					)
					(fill
						(type background)
					)
				)
				(pin passive line
					(at 0 0 0)
					(length 2.54)
					(name "~"
						(effects
							(font
								(size 1.27 1.27)
							)
						)
					)
					(number "1"
						(effects
							(font
								(size 1.27 1.27)
							)
						)
					)
				)
			)
		)
	(symbol "antmicroMemory:AS6C8008-55BIN"
			(exclude_from_sim no)
			(in_bom yes)
			(on_board yes)
			(property "Reference" "U"
				(at 40.64 -2.54 0)
				(effects
					(font
						(size 1.27 1.27)
						(thickness 0.15)
					)
					(justify left bottom)
				)
			)
			(property "Value" "AS6C8008-55BIN"
				(at 40.64 -5.08 0)
				(effects
					(font
						(size 1.27 1.27)
						(thickness 0.15)
					)
					(justify left bottom)
				)
			)
			(property "Footprint" "antmicro-footprints:Alliance_TFBGA-48"
				(at 40.64 -7.62 0)
				(effects
					(font
						(size 1.27 1.27)
						(thickness 0.15)
					)
					(justify left bottom)
					(hide yes)
				)
			)
			(property "Datasheet" "https://www.alliancememory.com/wp-content/uploads/pdf/lp_sram/AllianceMemory_8M_LPSRAM_AS6C8008_v1.1_May%202021.pdf"
				(at 40.64 -10.16 0)
				(effects
					(font
						(size 1.27 1.27)
						(thickness 0.15)
					)
					(justify left bottom)
					(hide yes)
				)
			)
			(property "Description" "SRAM, Asynchronous SRAM, 8 Mbit, TFBGA, 48 Pins, 2.7 V"
				(at 0 0 0)
				(effects
					(font
						(size 1.27 1.27)
					)
					(hide yes)
				)
			)
			(property "MPN" "AS6C8008-55BIN"
				(at 40.64 -12.7 0)
				(effects
					(font
						(size 1.27 1.27)
						(thickness 0.15)
					)
					(justify left bottom)
					(hide yes)
				)
			)
			(property "Manufacturer" "Alliance Memory"
				(at 40.64 -15.24 0)
				(effects
					(font
						(size 1.27 1.27)
						(thickness 0.15)
					)
					(justify left bottom)
					(hide yes)
				)
			)
			(property "Author" "Antmicro"
				(at 40.64 -17.78 0)
				(effects
					(font
						(size 1.27 1.27)
						(thickness 0.15)
					)
					(justify left bottom)
					(hide yes)
				)
			)
			(property "License" "Apache-2.0"
				(at 40.64 -20.32 0)
				(effects
					(font
						(size 1.27 1.27)
						(thickness 0.15)
					)
					(justify left bottom)
					(hide yes)
				)
			)
			(property "ki_keywords" "SMT, IC, ASYNCHRONOUS"
				(at 0 0 0)
				(effects
					(font
						(size 1.27 1.27)
					)
					(hide yes)
				)
			)
			(property "ki_fp_filters" "TSOP?I*18.4x12mm*P0.5mm*"
				(at 0 0 0)
				(effects
					(font
						(size 1.27 1.27)
					)
					(hide yes)
				)
			)
			(symbol "AS6C8008-55BIN_1_1"
				(rectangle
					(start 2.54 2.54)
					(end 22.86 -50.8)
					(stroke
						(width 0.254)
						(type default)
					)
					(fill
						(type background)
					)
				)
				(pin input line
					(at 0 0 0)
					(length 2.54)
					(name "A0"
						(effects
							(font
								(size 1.27 1.27)
							)
						)
					)
					(number "A3"
						(effects
							(font
								(size 1.27 1.27)
							)
						)
					)
				)
				(pin input line
					(at 0 -2.54 0)
					(length 2.54)
					(name "A1"
						(effects
							(font
								(size 1.27 1.27)
							)
						)
					)
					(number "A4"
						(effects
							(font
								(size 1.27 1.27)
							)
						)
					)
				)
				(pin input line
					(at 0 -5.08 0)
					(length 2.54)
					(name "A2"
						(effects
							(font
								(size 1.27 1.27)
							)
						)
					)
					(number "A5"
						(effects
							(font
								(size 1.27 1.27)
							)
						)
					)
				)
				(pin input line
					(at 0 -7.62 0)
					(length 2.54)
					(name "A3"
						(effects
							(font
								(size 1.27 1.27)
							)
						)
					)
					(number "B3"
						(effects
							(font
								(size 1.27 1.27)
							)
						)
					)
				)
				(pin input line
					(at 0 -10.16 0)
					(length 2.54)
					(name "A4"
						(effects
							(font
								(size 1.27 1.27)
							)
						)
					)
					(number "B4"
						(effects
							(font
								(size 1.27 1.27)
							)
						)
					)
				)
				(pin input line
					(at 0 -12.7 0)
					(length 2.54)
					(name "A5"
						(effects
							(font
								(size 1.27 1.27)
							)
						)
					)
					(number "C3"
						(effects
							(font
								(size 1.27 1.27)
							)
						)
					)
				)
				(pin input line
					(at 0 -15.24 0)
					(length 2.54)
					(name "A6"
						(effects
							(font
								(size 1.27 1.27)
							)
						)
					)
					(number "C4"
						(effects
							(font
								(size 1.27 1.27)
							)
						)
					)
				)
				(pin input line
					(at 0 -17.78 0)
					(length 2.54)
					(name "A7"
						(effects
							(font
								(size 1.27 1.27)
							)
						)
					)
					(number "D4"
						(effects
							(font
								(size 1.27 1.27)
							)
						)
					)
				)
				(pin input line
					(at 0 -20.32 0)
					(length 2.54)
					(name "A8"
						(effects
							(font
								(size 1.27 1.27)
							)
						)
					)
					(number "H2"
						(effects
							(font
								(size 1.27 1.27)
							)
						)
					)
				)
				(pin input line
					(at 0 -22.86 0)
					(length 2.54)
					(name "A9"
						(effects
							(font
								(size 1.27 1.27)
							)
						)
					)
					(number "H3"
						(effects
							(font
								(size 1.27 1.27)
							)
						)
					)
				)
				(pin input line
					(at 0 -25.4 0)
					(length 2.54)
					(name "A10"
						(effects
							(font
								(size 1.27 1.27)
							)
						)
					)
					(number "H4"
						(effects
							(font
								(size 1.27 1.27)
							)
						)
					)
				)
				(pin input line
					(at 0 -27.94 0)
					(length 2.54)
					(name "A11"
						(effects
							(font
								(size 1.27 1.27)
							)
						)
					)
					(number "H5"
						(effects
							(font
								(size 1.27 1.27)
							)
						)
					)
				)
				(pin input line
					(at 0 -30.48 0)
					(length 2.54)
					(name "A12"
						(effects
							(font
								(size 1.27 1.27)
							)
						)
					)
					(number "G3"
						(effects
							(font
								(size 1.27 1.27)
							)
						)
					)
				)
				(pin input line
					(at 0 -33.02 0)
					(length 2.54)
					(name "A13"
						(effects
							(font
								(size 1.27 1.27)
							)
						)
					)
					(number "G4"
						(effects
							(font
								(size 1.27 1.27)
							)
						)
					)
				)
				(pin input line
					(at 0 -35.56 0)
					(length 2.54)
					(name "A14"
						(effects
							(font
								(size 1.27 1.27)
							)
						)
					)
					(number "F3"
						(effects
							(font
								(size 1.27 1.27)
							)
						)
					)
				)
				(pin input line
					(at 0 -38.1 0)
					(length 2.54)
					(name "A15"
						(effects
							(font
								(size 1.27 1.27)
							)
						)
					)
					(number "F4"
						(effects
							(font
								(size 1.27 1.27)
							)
						)
					)
				)
				(pin input line
					(at 0 -40.64 0)
					(length 2.54)
					(name "A16"
						(effects
							(font
								(size 1.27 1.27)
							)
						)
					)
					(number "E4"
						(effects
							(font
								(size 1.27 1.27)
							)
						)
					)
				)
				(pin input line
					(at 0 -43.18 0)
					(length 2.54)
					(name "A17"
						(effects
							(font
								(size 1.27 1.27)
							)
						)
					)
					(number "D3"
						(effects
							(font
								(size 1.27 1.27)
							)
						)
					)
				)
				(pin input line
					(at 0 -45.72 0)
					(length 2.54)
					(name "A18"
						(effects
							(font
								(size 1.27 1.27)
							)
						)
					)
					(number "H1"
						(effects
							(font
								(size 1.27 1.27)
							)
						)
					)
				)
				(pin input line
					(at 0 -48.26 0)
					(length 2.54)
					(name "A19"
						(effects
							(font
								(size 1.27 1.27)
							)
						)
					)
					(number "H6"
						(effects
							(font
								(size 1.27 1.27)
							)
						)
					)
				)
				(pin no_connect line
					(at 6.35 -50.8 90)
					(length 2.54)
					(hide yes)
					(name "NC"
						(effects
							(font
								(size 1.27 1.27)
							)
						)
					)
					(number "A1"
						(effects
							(font
								(size 1.27 1.27)
							)
						)
					)
				)
				(pin no_connect line
					(at 7.62 -50.8 90)
					(length 2.54)
					(hide yes)
					(name "NC"
						(effects
							(font
								(size 1.27 1.27)
							)
						)
					)
					(number "B2"
						(effects
							(font
								(size 1.27 1.27)
							)
						)
					)
				)
				(pin no_connect line
					(at 8.89 -50.8 90)
					(length 2.54)
					(hide yes)
					(name "NC"
						(effects
							(font
								(size 1.27 1.27)
							)
						)
					)
					(number "B1"
						(effects
							(font
								(size 1.27 1.27)
							)
						)
					)
				)
				(pin no_connect line
					(at 10.16 -50.8 90)
					(length 2.54)
					(hide yes)
					(name "NC"
						(effects
							(font
								(size 1.27 1.27)
							)
						)
					)
					(number "C2"
						(effects
							(font
								(size 1.27 1.27)
							)
						)
					)
				)
				(pin no_connect line
					(at 11.43 -50.8 90)
					(length 2.54)
					(hide yes)
					(name "NC"
						(effects
							(font
								(size 1.27 1.27)
							)
						)
					)
					(number "B6"
						(effects
							(font
								(size 1.27 1.27)
							)
						)
					)
				)
				(pin no_connect line
					(at 12.7 -50.8 90)
					(length 2.54)
					(hide yes)
					(name "NC"
						(effects
							(font
								(size 1.27 1.27)
							)
						)
					)
					(number "C5"
						(effects
							(font
								(size 1.27 1.27)
							)
						)
					)
				)
				(pin no_connect line
					(at 13.97 -50.8 90)
					(length 2.54)
					(hide yes)
					(name "NC"
						(effects
							(font
								(size 1.27 1.27)
							)
						)
					)
					(number "E3"
						(effects
							(font
								(size 1.27 1.27)
							)
						)
					)
				)
				(pin no_connect line
					(at 15.24 -50.8 90)
					(length 2.54)
					(hide yes)
					(name "NC"
						(effects
							(font
								(size 1.27 1.27)
							)
						)
					)
					(number "F2"
						(effects
							(font
								(size 1.27 1.27)
							)
						)
					)
				)
				(pin no_connect line
					(at 16.51 -50.8 90)
					(length 2.54)
					(hide yes)
					(name "NC"
						(effects
							(font
								(size 1.27 1.27)
							)
						)
					)
					(number "F5"
						(effects
							(font
								(size 1.27 1.27)
							)
						)
					)
				)
				(pin no_connect line
					(at 17.78 -50.8 90)
					(length 2.54)
					(hide yes)
					(name "NC"
						(effects
							(font
								(size 1.27 1.27)
							)
						)
					)
					(number "G1"
						(effects
							(font
								(size 1.27 1.27)
							)
						)
					)
				)
				(pin no_connect line
					(at 19.05 -50.8 90)
					(length 2.54)
					(hide yes)
					(name "NC"
						(effects
							(font
								(size 1.27 1.27)
							)
						)
					)
					(number "G2"
						(effects
							(font
								(size 1.27 1.27)
							)
						)
					)
				)
				(pin no_connect line
					(at 20.32 -50.8 90)
					(length 2.54)
					(hide yes)
					(name "NC"
						(effects
							(font
								(size 1.27 1.27)
							)
						)
					)
					(number "G6"
						(effects
							(font
								(size 1.27 1.27)
							)
						)
					)
				)
				(pin power_in line
					(at 25.4 0 180)
					(length 2.54)
					(name "VCC"
						(effects
							(font
								(size 1.27 1.27)
							)
						)
					)
					(number "D6"
						(effects
							(font
								(size 1.27 1.27)
							)
						)
					)
				)
				(pin passive line
					(at 25.4 0 180)
					(length 2.54)
					(hide yes)
					(name "VCC"
						(effects
							(font
								(size 1.27 1.27)
							)
						)
					)
					(number "E1"
						(effects
							(font
								(size 1.27 1.27)
							)
						)
					)
				)
				(pin bidirectional line
					(at 25.4 -7.62 180)
					(length 2.54)
					(name "DQ0"
						(effects
							(font
								(size 1.27 1.27)
							)
						)
					)
					(number "C1"
						(effects
							(font
								(size 1.27 1.27)
							)
						)
					)
				)
				(pin bidirectional line
					(at 25.4 -10.16 180)
					(length 2.54)
					(name "DQ1"
						(effects
							(font
								(size 1.27 1.27)
							)
						)
					)
					(number "D2"
						(effects
							(font
								(size 1.27 1.27)
							)
						)
					)
				)
				(pin bidirectional line
					(at 25.4 -12.7 180)
					(length 2.54)
					(name "DQ2"
						(effects
							(font
								(size 1.27 1.27)
							)
						)
					)
					(number "E2"
						(effects
							(font
								(size 1.27 1.27)
							)
						)
					)
				)
				(pin bidirectional line
					(at 25.4 -15.24 180)
					(length 2.54)
					(name "DQ3"
						(effects
							(font
								(size 1.27 1.27)
							)
						)
					)
					(number "F1"
						(effects
							(font
								(size 1.27 1.27)
							)
						)
					)
				)
				(pin bidirectional line
					(at 25.4 -17.78 180)
					(length 2.54)
					(name "DQ4"
						(effects
							(font
								(size 1.27 1.27)
							)
						)
					)
					(number "C6"
						(effects
							(font
								(size 1.27 1.27)
							)
						)
					)
				)
				(pin bidirectional line
					(at 25.4 -20.32 180)
					(length 2.54)
					(name "DQ5"
						(effects
							(font
								(size 1.27 1.27)
							)
						)
					)
					(number "D5"
						(effects
							(font
								(size 1.27 1.27)
							)
						)
					)
				)
				(pin bidirectional line
					(at 25.4 -22.86 180)
					(length 2.54)
					(name "DQ6"
						(effects
							(font
								(size 1.27 1.27)
							)
						)
					)
					(number "E5"
						(effects
							(font
								(size 1.27 1.27)
							)
						)
					)
				)
				(pin bidirectional line
					(at 25.4 -25.4 180)
					(length 2.54)
					(name "DQ7"
						(effects
							(font
								(size 1.27 1.27)
							)
						)
					)
					(number "F6"
						(effects
							(font
								(size 1.27 1.27)
							)
						)
					)
				)
				(pin input line
					(at 25.4 -30.48 180)
					(length 2.54)
					(name "CE#"
						(effects
							(font
								(size 1.27 1.27)
							)
						)
					)
					(number "B5"
						(effects
							(font
								(size 1.27 1.27)
							)
						)
					)
				)
				(pin input line
					(at 25.4 -33.02 180)
					(length 2.54)
					(name "CE2"
						(effects
							(font
								(size 1.27 1.27)
							)
						)
					)
					(number "A6"
						(effects
							(font
								(size 1.27 1.27)
							)
						)
					)
				)
				(pin input line
					(at 25.4 -35.56 180)
					(length 2.54)
					(name "OE#"
						(effects
							(font
								(size 1.27 1.27)
							)
						)
					)
					(number "A2"
						(effects
							(font
								(size 1.27 1.27)
							)
						)
					)
				)
				(pin input line
					(at 25.4 -38.1 180)
					(length 2.54)
					(name "WE#"
						(effects
							(font
								(size 1.27 1.27)
							)
						)
					)
					(number "G5"
						(effects
							(font
								(size 1.27 1.27)
							)
						)
					)
				)
				(pin passive line
					(at 25.4 -45.72 180)
					(length 2.54)
					(name "VSS"
						(effects
							(font
								(size 1.27 1.27)
							)
						)
					)
					(number "D1"
						(effects
							(font
								(size 1.27 1.27)
							)
						)
					)
				)
				(pin passive line
					(at 25.4 -45.72 180)
					(length 2.54)
					(hide yes)
					(name "VSS"
						(effects
							(font
								(size 1.27 1.27)
							)
						)
					)
					(number "E6"
						(effects
							(font
								(size 1.27 1.27)
							)
						)
					)
				)
			)
		)
	(symbol "antmicroMemory:MT25QL256ABA1EW7-0SIT"
			(exclude_from_sim no)
			(in_bom yes)
			(on_board yes)
			(property "Reference" "U"
				(at 41.91 -2.54 0)
				(effects
					(font
						(size 1.27 1.27)
						(thickness 0.15)
					)
					(justify left bottom)
				)
			)
			(property "Value" "MT25QL256ABA1EW7-0SIT"
				(at 41.91 -5.08 0)
				(effects
					(font
						(size 1.27 1.27)
						(thickness 0.15)
					)
					(justify left bottom)
				)
			)
			(property "Footprint" "antmicro-footprints:WDFN-8-1EP_6x5mm_P1.27mm_EP3.4x4mm"
				(at 41.91 -7.62 0)
				(effects
					(font
						(size 1.27 1.27)
						(thickness 0.15)
					)
					(justify left bottom)
					(hide yes)
				)
			)
			(property "Datasheet" "https://www.micron.com/products/nor-flash/serial-nor-flash/part-catalog/mt25ql256aba1ew7-0sit"
				(at 41.91 -10.16 0)
				(effects
					(font
						(size 1.27 1.27)
						(thickness 0.15)
					)
					(justify left bottom)
					(hide yes)
				)
			)
			(property "Description" "Flash Memory, Serial NOR, 256 Mbit, 32M x 8bit, SPI, MLP, 8 Pins"
				(at 0 0 0)
				(effects
					(font
						(size 1.27 1.27)
					)
					(hide yes)
				)
			)
			(property "MPN" "MT25QL256ABA1EW7-0SIT"
				(at 41.91 -12.7 0)
				(effects
					(font
						(size 1.27 1.27)
						(thickness 0.15)
					)
					(justify left bottom)
					(hide yes)
				)
			)
			(property "Manufacturer" "Micron Technology"
				(at 41.91 -15.24 0)
				(effects
					(font
						(size 1.27 1.27)
						(thickness 0.15)
					)
					(justify left bottom)
					(hide yes)
				)
			)
			(property "Author" "Antmicro"
				(at 41.91 -17.78 0)
				(effects
					(font
						(size 1.27 1.27)
						(thickness 0.15)
					)
					(justify left bottom)
					(hide yes)
				)
			)
			(property "License" "Apache-2.0"
				(at 41.91 -20.32 0)
				(effects
					(font
						(size 1.27 1.27)
						(thickness 0.15)
					)
					(justify left bottom)
					(hide yes)
				)
			)
			(property "ki_keywords" "SMT, FLASH, IC"
				(at 0 0 0)
				(effects
					(font
						(size 1.27 1.27)
					)
					(hide yes)
				)
			)
			(symbol "MT25QL256ABA1EW7-0SIT_1_1"
				(rectangle
					(start 2.54 2.54)
					(end 25.4 -14.605)
					(stroke
						(width 0.254)
						(type default)
					)
					(fill
						(type background)
					)
				)
				(pin passive line
					(at 0 0 0)
					(length 2.54)
					(name "~{CS}"
						(effects
							(font
								(size 1.27 1.27)
							)
						)
					)
					(number "1"
						(effects
							(font
								(size 1.27 1.27)
							)
						)
					)
				)
				(pin passive line
					(at 0 -2.54 0)
					(length 2.54)
					(name "CLK"
						(effects
							(font
								(size 1.27 1.27)
							)
						)
					)
					(number "6"
						(effects
							(font
								(size 1.27 1.27)
							)
						)
					)
				)
				(pin passive line
					(at 0 -5.08 0)
					(length 2.54)
					(name "DQ0"
						(effects
							(font
								(size 1.27 1.27)
							)
						)
					)
					(number "5"
						(effects
							(font
								(size 1.27 1.27)
							)
						)
					)
				)
				(pin passive line
					(at 0 -7.62 0)
					(length 2.54)
					(name "DQ1"
						(effects
							(font
								(size 1.27 1.27)
							)
						)
					)
					(number "2"
						(effects
							(font
								(size 1.27 1.27)
							)
						)
					)
				)
				(pin passive line
					(at 0 -10.16 0)
					(length 2.54)
					(name "DQ2/~{W}"
						(effects
							(font
								(size 1.27 1.27)
							)
						)
					)
					(number "3"
						(effects
							(font
								(size 1.27 1.27)
							)
						)
					)
				)
				(pin passive line
					(at 0 -12.7 0)
					(length 2.54)
					(name "DQ3/~{HOLD}"
						(effects
							(font
								(size 1.27 1.27)
							)
						)
					)
					(number "7"
						(effects
							(font
								(size 1.27 1.27)
							)
						)
					)
				)
				(pin passive line
					(at 27.94 0 180)
					(length 2.54)
					(name "VCC"
						(effects
							(font
								(size 1.27 1.27)
							)
						)
					)
					(number "8"
						(effects
							(font
								(size 1.27 1.27)
							)
						)
					)
				)
				(pin passive line
					(at 27.94 -10.16 180)
					(length 2.54)
					(name "EP"
						(effects
							(font
								(size 1.27 1.27)
							)
						)
					)
					(number "9"
						(effects
							(font
								(size 1.27 1.27)
							)
						)
					)
				)
				(pin passive line
					(at 27.94 -12.7 180)
					(length 2.54)
					(name "GND"
						(effects
							(font
								(size 1.27 1.27)
							)
						)
					)
					(number "4"
						(effects
							(font
								(size 1.27 1.27)
							)
						)
					)
				)
			)
		)
	(symbol "antmicroMemory:MT41K512M8DA"
			(exclude_from_sim no)
			(in_bom yes)
			(on_board yes)
			(property "Reference" "U"
				(at 45.72 -2.54 0)
				(effects
					(font
						(size 1.27 1.27)
						(thickness 0.15)
					)
					(justify left bottom)
				)
			)
			(property "Value" "MT41K512M8DA"
				(at 45.72 -5.08 0)
				(effects
					(font
						(size 1.27 1.27)
						(thickness 0.15)
					)
					(justify left bottom)
				)
			)
			(property "Footprint" "antmicro-footprints:Micron_FBGA-78"
				(at 45.72 -7.62 0)
				(effects
					(font
						(size 1.27 1.27)
						(thickness 0.15)
					)
					(justify left bottom)
					(hide yes)
				)
			)
			(property "Datasheet" "https://media-www.micron.com/-/media/client/global/documents/products/data-sheet/dram/ddr3/4gb_1_35v_ddr3l_xit_addendum.pdf?rev=7a72ef4abde14a46b61107e1a0bb1af6"
				(at 45.72 -10.16 0)
				(effects
					(font
						(size 1.27 1.27)
						(thickness 0.15)
					)
					(justify left bottom)
					(hide yes)
				)
			)
			(property "Description" "SDRAM - DDR3L Memory IC 4Gbit Parallel 933 MHz 20 ns 78-FBGA (8x10.5)"
				(at 0 0 0)
				(effects
					(font
						(size 1.27 1.27)
					)
					(hide yes)
				)
			)
			(property "Manufacturer" "Micron Technology"
				(at 45.72 -12.7 0)
				(effects
					(font
						(size 1.27 1.27)
						(thickness 0.15)
					)
					(justify left bottom)
					(hide yes)
				)
			)
			(property "MPN" "MT41K512M8DA-107 XIT:P TR"
				(at 45.72 -15.24 0)
				(effects
					(font
						(size 1.27 1.27)
						(thickness 0.15)
					)
					(justify left bottom)
					(hide yes)
				)
			)
			(property "Author" "Antmicro"
				(at 45.72 -17.78 0)
				(effects
					(font
						(size 1.27 1.27)
						(thickness 0.15)
					)
					(justify left bottom)
					(hide yes)
				)
			)
			(property "License" "Apache-2.0"
				(at 45.72 -20.32 0)
				(effects
					(font
						(size 1.27 1.27)
						(thickness 0.15)
					)
					(justify left bottom)
					(hide yes)
				)
			)
			(property "ki_keywords" "SMT, DRAM, IC"
				(at 0 0 0)
				(effects
					(font
						(size 1.27 1.27)
					)
					(hide yes)
				)
			)
			(symbol "MT41K512M8DA_1_1"
				(rectangle
					(start 2.54 3.81)
					(end 27.94 -66.04)
					(stroke
						(width 0.254)
						(type default)
					)
					(fill
						(type background)
					)
				)
				(pin input line
					(at 0 0 0)
					(length 2.54)
					(name "RESET#"
						(effects
							(font
								(size 1.27 1.27)
							)
						)
					)
					(number "N2"
						(effects
							(font
								(size 1.27 1.27)
							)
						)
					)
				)
				(pin input line
					(at 0 -2.54 0)
					(length 2.54)
					(name "A0"
						(effects
							(font
								(size 1.27 1.27)
							)
						)
					)
					(number "K3"
						(effects
							(font
								(size 1.27 1.27)
							)
						)
					)
				)
				(pin input line
					(at 0 -5.08 0)
					(length 2.54)
					(name "A1"
						(effects
							(font
								(size 1.27 1.27)
							)
						)
					)
					(number "L7"
						(effects
							(font
								(size 1.27 1.27)
							)
						)
					)
				)
				(pin input line
					(at 0 -7.62 0)
					(length 2.54)
					(name "A2"
						(effects
							(font
								(size 1.27 1.27)
							)
						)
					)
					(number "L3"
						(effects
							(font
								(size 1.27 1.27)
							)
						)
					)
				)
				(pin input line
					(at 0 -10.16 0)
					(length 2.54)
					(name "A3"
						(effects
							(font
								(size 1.27 1.27)
							)
						)
					)
					(number "K2"
						(effects
							(font
								(size 1.27 1.27)
							)
						)
					)
				)
				(pin input line
					(at 0 -12.7 0)
					(length 2.54)
					(name "A4"
						(effects
							(font
								(size 1.27 1.27)
							)
						)
					)
					(number "L8"
						(effects
							(font
								(size 1.27 1.27)
							)
						)
					)
				)
				(pin input line
					(at 0 -15.24 0)
					(length 2.54)
					(name "A5"
						(effects
							(font
								(size 1.27 1.27)
							)
						)
					)
					(number "L2"
						(effects
							(font
								(size 1.27 1.27)
							)
						)
					)
				)
				(pin input line
					(at 0 -17.78 0)
					(length 2.54)
					(name "A6"
						(effects
							(font
								(size 1.27 1.27)
							)
						)
					)
					(number "M8"
						(effects
							(font
								(size 1.27 1.27)
							)
						)
					)
				)
				(pin input line
					(at 0 -20.32 0)
					(length 2.54)
					(name "A7"
						(effects
							(font
								(size 1.27 1.27)
							)
						)
					)
					(number "M2"
						(effects
							(font
								(size 1.27 1.27)
							)
						)
					)
				)
				(pin input line
					(at 0 -22.86 0)
					(length 2.54)
					(name "A8"
						(effects
							(font
								(size 1.27 1.27)
							)
						)
					)
					(number "N8"
						(effects
							(font
								(size 1.27 1.27)
							)
						)
					)
				)
				(pin input line
					(at 0 -25.4 0)
					(length 2.54)
					(name "A9"
						(effects
							(font
								(size 1.27 1.27)
							)
						)
					)
					(number "M3"
						(effects
							(font
								(size 1.27 1.27)
							)
						)
					)
				)
				(pin input line
					(at 0 -27.94 0)
					(length 2.54)
					(name "A10/AP"
						(effects
							(font
								(size 1.27 1.27)
							)
						)
					)
					(number "H7"
						(effects
							(font
								(size 1.27 1.27)
							)
						)
					)
				)
				(pin input line
					(at 0 -30.48 0)
					(length 2.54)
					(name "A11"
						(effects
							(font
								(size 1.27 1.27)
							)
						)
					)
					(number "M7"
						(effects
							(font
								(size 1.27 1.27)
							)
						)
					)
				)
				(pin input line
					(at 0 -33.02 0)
					(length 2.54)
					(name "A12/BC#"
						(effects
							(font
								(size 1.27 1.27)
							)
						)
					)
					(number "K7"
						(effects
							(font
								(size 1.27 1.27)
							)
						)
					)
				)
				(pin input line
					(at 0 -35.56 0)
					(length 2.54)
					(name "A13"
						(effects
							(font
								(size 1.27 1.27)
							)
						)
					)
					(number "N3"
						(effects
							(font
								(size 1.27 1.27)
							)
						)
					)
				)
				(pin input line
					(at 0 -38.1 0)
					(length 2.54)
					(name "A14"
						(effects
							(font
								(size 1.27 1.27)
							)
						)
					)
					(number "N7"
						(effects
							(font
								(size 1.27 1.27)
							)
						)
					)
				)
				(pin input line
					(at 0 -40.64 0)
					(length 2.54)
					(name "A15"
						(effects
							(font
								(size 1.27 1.27)
							)
						)
					)
					(number "J7"
						(effects
							(font
								(size 1.27 1.27)
							)
						)
					)
				)
				(pin input line
					(at 0 -43.18 0)
					(length 2.54)
					(name "BA0"
						(effects
							(font
								(size 1.27 1.27)
							)
						)
					)
					(number "J2"
						(effects
							(font
								(size 1.27 1.27)
							)
						)
					)
				)
				(pin input line
					(at 0 -45.72 0)
					(length 2.54)
					(name "BA1"
						(effects
							(font
								(size 1.27 1.27)
							)
						)
					)
					(number "K8"
						(effects
							(font
								(size 1.27 1.27)
							)
						)
					)
				)
				(pin input line
					(at 0 -48.26 0)
					(length 2.54)
					(name "BA2"
						(effects
							(font
								(size 1.27 1.27)
							)
						)
					)
					(number "J3"
						(effects
							(font
								(size 1.27 1.27)
							)
						)
					)
				)
				(pin input clock
					(at 0 -53.34 0)
					(length 2.54)
					(name "CKE"
						(effects
							(font
								(size 1.27 1.27)
							)
						)
					)
					(number "G9"
						(effects
							(font
								(size 1.27 1.27)
							)
						)
					)
				)
				(pin input clock
					(at 0 -55.88 0)
					(length 2.54)
					(name "CK"
						(effects
							(font
								(size 1.27 1.27)
							)
						)
					)
					(number "F7"
						(effects
							(font
								(size 1.27 1.27)
							)
						)
					)
				)
				(pin input clock
					(at 0 -58.42 0)
					(length 2.54)
					(name "CK#"
						(effects
							(font
								(size 1.27 1.27)
							)
						)
					)
					(number "G7"
						(effects
							(font
								(size 1.27 1.27)
							)
						)
					)
				)
				(pin input line
					(at 0 -63.5 0)
					(length 2.54)
					(name "ODT"
						(effects
							(font
								(size 1.27 1.27)
							)
						)
					)
					(number "G1"
						(effects
							(font
								(size 1.27 1.27)
							)
						)
					)
				)
				(pin no_connect line
					(at 10.16 -66.04 90)
					(length 2.54)
					(hide yes)
					(name "NC"
						(effects
							(font
								(size 1.27 1.27)
							)
						)
					)
					(number "A3"
						(effects
							(font
								(size 1.27 1.27)
							)
						)
					)
				)
				(pin no_connect line
					(at 12.7 -66.04 90)
					(length 2.54)
					(hide yes)
					(name "NC"
						(effects
							(font
								(size 1.27 1.27)
							)
						)
					)
					(number "F1"
						(effects
							(font
								(size 1.27 1.27)
							)
						)
					)
				)
				(pin no_connect line
					(at 15.24 -66.04 90)
					(length 2.54)
					(hide yes)
					(name "NC"
						(effects
							(font
								(size 1.27 1.27)
							)
						)
					)
					(number "F9"
						(effects
							(font
								(size 1.27 1.27)
							)
						)
					)
				)
				(pin no_connect line
					(at 17.78 -66.04 90)
					(length 2.54)
					(hide yes)
					(name "NC"
						(effects
							(font
								(size 1.27 1.27)
							)
						)
					)
					(number "H1"
						(effects
							(font
								(size 1.27 1.27)
							)
						)
					)
				)
				(pin no_connect line
					(at 20.32 -66.04 90)
					(length 2.54)
					(hide yes)
					(name "NC"
						(effects
							(font
								(size 1.27 1.27)
							)
						)
					)
					(number "H9"
						(effects
							(font
								(size 1.27 1.27)
							)
						)
					)
				)
				(pin power_in line
					(at 30.48 0 180)
					(length 2.54)
					(name "VDD"
						(effects
							(font
								(size 1.27 1.27)
							)
						)
					)
					(number "A2"
						(effects
							(font
								(size 1.27 1.27)
							)
						)
					)
				)
				(pin passive line
					(at 30.48 0 180)
					(length 2.54)
					(hide yes)
					(name "VDD"
						(effects
							(font
								(size 1.27 1.27)
							)
						)
					)
					(number "A9"
						(effects
							(font
								(size 1.27 1.27)
							)
						)
					)
				)
				(pin passive line
					(at 30.48 0 180)
					(length 2.54)
					(hide yes)
					(name "VDD"
						(effects
							(font
								(size 1.27 1.27)
							)
						)
					)
					(number "D7"
						(effects
							(font
								(size 1.27 1.27)
							)
						)
					)
				)
				(pin passive line
					(at 30.48 0 180)
					(length 2.54)
					(hide yes)
					(name "VDD"
						(effects
							(font
								(size 1.27 1.27)
							)
						)
					)
					(number "G2"
						(effects
							(font
								(size 1.27 1.27)
							)
						)
					)
				)
				(pin passive line
					(at 30.48 0 180)
					(length 2.54)
					(hide yes)
					(name "VDD"
						(effects
							(font
								(size 1.27 1.27)
							)
						)
					)
					(number "G8"
						(effects
							(font
								(size 1.27 1.27)
							)
						)
					)
				)
				(pin passive line
					(at 30.48 0 180)
					(length 2.54)
					(hide yes)
					(name "VDD"
						(effects
							(font
								(size 1.27 1.27)
							)
						)
					)
					(number "K1"
						(effects
							(font
								(size 1.27 1.27)
							)
						)
					)
				)
				(pin passive line
					(at 30.48 0 180)
					(length 2.54)
					(hide yes)
					(name "VDD"
						(effects
							(font
								(size 1.27 1.27)
							)
						)
					)
					(number "K9"
						(effects
							(font
								(size 1.27 1.27)
							)
						)
					)
				)
				(pin passive line
					(at 30.48 0 180)
					(length 2.54)
					(hide yes)
					(name "VDD"
						(effects
							(font
								(size 1.27 1.27)
							)
						)
					)
					(number "M1"
						(effects
							(font
								(size 1.27 1.27)
							)
						)
					)
				)
				(pin passive line
					(at 30.48 0 180)
					(length 2.54)
					(hide yes)
					(name "VDD"
						(effects
							(font
								(size 1.27 1.27)
							)
						)
					)
					(number "M9"
						(effects
							(font
								(size 1.27 1.27)
							)
						)
					)
				)
				(pin power_in line
					(at 30.48 -2.54 180)
					(length 2.54)
					(name "VDDQ"
						(effects
							(font
								(size 1.27 1.27)
							)
						)
					)
					(number "B9"
						(effects
							(font
								(size 1.27 1.27)
							)
						)
					)
				)
				(pin passive line
					(at 30.48 -2.54 180)
					(length 2.54)
					(hide yes)
					(name "VDDQ"
						(effects
							(font
								(size 1.27 1.27)
							)
						)
					)
					(number "C1"
						(effects
							(font
								(size 1.27 1.27)
							)
						)
					)
				)
				(pin passive line
					(at 30.48 -2.54 180)
					(length 2.54)
					(hide yes)
					(name "VDDQ"
						(effects
							(font
								(size 1.27 1.27)
							)
						)
					)
					(number "E2"
						(effects
							(font
								(size 1.27 1.27)
							)
						)
					)
				)
				(pin passive line
					(at 30.48 -2.54 180)
					(length 2.54)
					(hide yes)
					(name "VDDQ"
						(effects
							(font
								(size 1.27 1.27)
							)
						)
					)
					(number "E9"
						(effects
							(font
								(size 1.27 1.27)
							)
						)
					)
				)
				(pin power_in line
					(at 30.48 -5.08 180)
					(length 2.54)
					(name "VREFCA"
						(effects
							(font
								(size 1.27 1.27)
							)
						)
					)
					(number "J8"
						(effects
							(font
								(size 1.27 1.27)
							)
						)
					)
				)
				(pin power_in line
					(at 30.48 -7.62 180)
					(length 2.54)
					(name "VREFDQ"
						(effects
							(font
								(size 1.27 1.27)
							)
						)
					)
					(number "E1"
						(effects
							(font
								(size 1.27 1.27)
							)
						)
					)
				)
				(pin bidirectional line
					(at 30.48 -12.7 180)
					(length 2.54)
					(name "DQ0"
						(effects
							(font
								(size 1.27 1.27)
							)
						)
					)
					(number "B3"
						(effects
							(font
								(size 1.27 1.27)
							)
						)
					)
				)
				(pin bidirectional line
					(at 30.48 -15.24 180)
					(length 2.54)
					(name "DQ1"
						(effects
							(font
								(size 1.27 1.27)
							)
						)
					)
					(number "C7"
						(effects
							(font
								(size 1.27 1.27)
							)
						)
					)
				)
				(pin bidirectional line
					(at 30.48 -17.78 180)
					(length 2.54)
					(name "DQ2"
						(effects
							(font
								(size 1.27 1.27)
							)
						)
					)
					(number "C2"
						(effects
							(font
								(size 1.27 1.27)
							)
						)
					)
				)
				(pin bidirectional line
					(at 30.48 -20.32 180)
					(length 2.54)
					(name "DQ3"
						(effects
							(font
								(size 1.27 1.27)
							)
						)
					)
					(number "C8"
						(effects
							(font
								(size 1.27 1.27)
							)
						)
					)
				)
				(pin bidirectional line
					(at 30.48 -22.86 180)
					(length 2.54)
					(name "NF/DQ4"
						(effects
							(font
								(size 1.27 1.27)
							)
						)
					)
					(number "E3"
						(effects
							(font
								(size 1.27 1.27)
							)
						)
					)
				)
				(pin bidirectional line
					(at 30.48 -25.4 180)
					(length 2.54)
					(name "NF/DQ5"
						(effects
							(font
								(size 1.27 1.27)
							)
						)
					)
					(number "E8"
						(effects
							(font
								(size 1.27 1.27)
							)
						)
					)
				)
				(pin bidirectional line
					(at 30.48 -27.94 180)
					(length 2.54)
					(name "NF/DQ6"
						(effects
							(font
								(size 1.27 1.27)
							)
						)
					)
					(number "D2"
						(effects
							(font
								(size 1.27 1.27)
							)
						)
					)
				)
				(pin bidirectional line
					(at 30.48 -30.48 180)
					(length 2.54)
					(name "NF/DQ7"
						(effects
							(font
								(size 1.27 1.27)
							)
						)
					)
					(number "E7"
						(effects
							(font
								(size 1.27 1.27)
							)
						)
					)
				)
				(pin bidirectional line
					(at 30.48 -33.02 180)
					(length 2.54)
					(name "DQS"
						(effects
							(font
								(size 1.27 1.27)
							)
						)
					)
					(number "C3"
						(effects
							(font
								(size 1.27 1.27)
							)
						)
					)
				)
				(pin bidirectional line
					(at 30.48 -35.56 180)
					(length 2.54)
					(name "DQS#"
						(effects
							(font
								(size 1.27 1.27)
							)
						)
					)
					(number "D3"
						(effects
							(font
								(size 1.27 1.27)
							)
						)
					)
				)
				(pin bidirectional line
					(at 30.48 -38.1 180)
					(length 2.54)
					(name "DM/TDQS"
						(effects
							(font
								(size 1.27 1.27)
							)
						)
					)
					(number "B7"
						(effects
							(font
								(size 1.27 1.27)
							)
						)
					)
				)
				(pin output line
					(at 30.48 -40.64 180)
					(length 2.54)
					(name "NF/TDQS#"
						(effects
							(font
								(size 1.27 1.27)
							)
						)
					)
					(number "A7"
						(effects
							(font
								(size 1.27 1.27)
							)
						)
					)
				)
				(pin input line
					(at 30.48 -45.72 180)
					(length 2.54)
					(name "WE#"
						(effects
							(font
								(size 1.27 1.27)
							)
						)
					)
					(number "H3"
						(effects
							(font
								(size 1.27 1.27)
							)
						)
					)
				)
				(pin input line
					(at 30.48 -48.26 180)
					(length 2.54)
					(name "CAS#"
						(effects
							(font
								(size 1.27 1.27)
							)
						)
					)
					(number "G3"
						(effects
							(font
								(size 1.27 1.27)
							)
						)
					)
				)
				(pin input line
					(at 30.48 -50.8 180)
					(length 2.54)
					(name "RAS#"
						(effects
							(font
								(size 1.27 1.27)
							)
						)
					)
					(number "F3"
						(effects
							(font
								(size 1.27 1.27)
							)
						)
					)
				)
				(pin input line
					(at 30.48 -53.34 180)
					(length 2.54)
					(name "CS#"
						(effects
							(font
								(size 1.27 1.27)
							)
						)
					)
					(number "H2"
						(effects
							(font
								(size 1.27 1.27)
							)
						)
					)
				)
				(pin output line
					(at 30.48 -55.88 180)
					(length 2.54)
					(name "ZQ"
						(effects
							(font
								(size 1.27 1.27)
							)
						)
					)
					(number "H8"
						(effects
							(font
								(size 1.27 1.27)
							)
						)
					)
				)
				(pin passive line
					(at 30.48 -60.96 180)
					(length 2.54)
					(name "VSS"
						(effects
							(font
								(size 1.27 1.27)
							)
						)
					)
					(number "A1"
						(effects
							(font
								(size 1.27 1.27)
							)
						)
					)
				)
				(pin passive line
					(at 30.48 -60.96 180)
					(length 2.54)
					(hide yes)
					(name "VSS"
						(effects
							(font
								(size 1.27 1.27)
							)
						)
					)
					(number "A8"
						(effects
							(font
								(size 1.27 1.27)
							)
						)
					)
				)
				(pin passive line
					(at 30.48 -60.96 180)
					(length 2.54)
					(hide yes)
					(name "VSS"
						(effects
							(font
								(size 1.27 1.27)
							)
						)
					)
					(number "B1"
						(effects
							(font
								(size 1.27 1.27)
							)
						)
					)
				)
				(pin passive line
					(at 30.48 -60.96 180)
					(length 2.54)
					(hide yes)
					(name "VSS"
						(effects
							(font
								(size 1.27 1.27)
							)
						)
					)
					(number "D8"
						(effects
							(font
								(size 1.27 1.27)
							)
						)
					)
				)
				(pin passive line
					(at 30.48 -60.96 180)
					(length 2.54)
					(hide yes)
					(name "VSS"
						(effects
							(font
								(size 1.27 1.27)
							)
						)
					)
					(number "F2"
						(effects
							(font
								(size 1.27 1.27)
							)
						)
					)
				)
				(pin passive line
					(at 30.48 -60.96 180)
					(length 2.54)
					(hide yes)
					(name "VSS"
						(effects
							(font
								(size 1.27 1.27)
							)
						)
					)
					(number "F8"
						(effects
							(font
								(size 1.27 1.27)
							)
						)
					)
				)
				(pin passive line
					(at 30.48 -60.96 180)
					(length 2.54)
					(hide yes)
					(name "VSS"
						(effects
							(font
								(size 1.27 1.27)
							)
						)
					)
					(number "J1"
						(effects
							(font
								(size 1.27 1.27)
							)
						)
					)
				)
				(pin passive line
					(at 30.48 -60.96 180)
					(length 2.54)
					(hide yes)
					(name "VSS"
						(effects
							(font
								(size 1.27 1.27)
							)
						)
					)
					(number "J9"
						(effects
							(font
								(size 1.27 1.27)
							)
						)
					)
				)
				(pin passive line
					(at 30.48 -60.96 180)
					(length 2.54)
					(hide yes)
					(name "VSS"
						(effects
							(font
								(size 1.27 1.27)
							)
						)
					)
					(number "L1"
						(effects
							(font
								(size 1.27 1.27)
							)
						)
					)
				)
				(pin passive line
					(at 30.48 -60.96 180)
					(length 2.54)
					(hide yes)
					(name "VSS"
						(effects
							(font
								(size 1.27 1.27)
							)
						)
					)
					(number "L9"
						(effects
							(font
								(size 1.27 1.27)
							)
						)
					)
				)
				(pin passive line
					(at 30.48 -60.96 180)
					(length 2.54)
					(hide yes)
					(name "VSS"
						(effects
							(font
								(size 1.27 1.27)
							)
						)
					)
					(number "N1"
						(effects
							(font
								(size 1.27 1.27)
							)
						)
					)
				)
				(pin passive line
					(at 30.48 -60.96 180)
					(length 2.54)
					(hide yes)
					(name "VSS"
						(effects
							(font
								(size 1.27 1.27)
							)
						)
					)
					(number "N9"
						(effects
							(font
								(size 1.27 1.27)
							)
						)
					)
				)
				(pin passive line
					(at 30.48 -63.5 180)
					(length 2.54)
					(name "VSSQ"
						(effects
							(font
								(size 1.27 1.27)
							)
						)
					)
					(number "B2"
						(effects
							(font
								(size 1.27 1.27)
							)
						)
					)
				)
				(pin passive line
					(at 30.48 -63.5 180)
					(length 2.54)
					(hide yes)
					(name "VSSQ"
						(effects
							(font
								(size 1.27 1.27)
							)
						)
					)
					(number "B8"
						(effects
							(font
								(size 1.27 1.27)
							)
						)
					)
				)
				(pin passive line
					(at 30.48 -63.5 180)
					(length 2.54)
					(hide yes)
					(name "VSSQ"
						(effects
							(font
								(size 1.27 1.27)
							)
						)
					)
					(number "C9"
						(effects
							(font
								(size 1.27 1.27)
							)
						)
					)
				)
				(pin passive line
					(at 30.48 -63.5 180)
					(length 2.54)
					(hide yes)
					(name "VSSQ"
						(effects
							(font
								(size 1.27 1.27)
							)
						)
					)
					(number "D1"
						(effects
							(font
								(size 1.27 1.27)
							)
						)
					)
				)
				(pin passive line
					(at 30.48 -63.5 180)
					(length 2.54)
					(hide yes)
					(name "VSSQ"
						(effects
							(font
								(size 1.27 1.27)
							)
						)
					)
					(number "D9"
						(effects
							(font
								(size 1.27 1.27)
							)
						)
					)
				)
			)
		)
	(symbol "antmicroMemoryConnectorsPCCardSockets:DM3AT-SF-PEJM5"
			(exclude_from_sim no)
			(in_bom yes)
			(on_board yes)
			(property "Reference" "J"
				(at 57.15 0 0)
				(effects
					(font
						(size 1.27 1.27)
						(thickness 0.15)
					)
					(justify left bottom)
				)
			)
			(property "Value" "DM3AT-SF-PEJM5"
				(at 57.15 -2.54 0)
				(effects
					(font
						(size 1.27 1.27)
						(thickness 0.15)
					)
					(justify left bottom)
				)
			)
			(property "Footprint" "antmicro-footprints:MicroSD_DM3AT-SF-PEJM5"
				(at 57.15 -5.08 0)
				(effects
					(font
						(size 1.27 1.27)
						(thickness 0.15)
					)
					(justify left bottom)
					(hide yes)
				)
			)
			(property "Datasheet" "https://www.hirose.com/en/product/document?clcode=CL0609-0031-0-00&productname=DM3AT-SF-PEJM5&series=DM3&documenttype=2DDrawing&lang=en&documentid=0000947170"
				(at 57.15 -7.62 0)
				(effects
					(font
						(size 1.27 1.27)
						(thickness 0.15)
					)
					(justify left bottom)
					(hide yes)
				)
			)
			(property "Description" "Memory Card Connector, MicroSD, Push-Push, 8 Contacts, Copper Alloy, Gold Plated Contacts, DM3"
				(at 0 0 0)
				(effects
					(font
						(size 1.27 1.27)
					)
					(hide yes)
				)
			)
			(property "Manufacturer" "Hirose Electric"
				(at 57.15 -10.16 0)
				(effects
					(font
						(size 1.27 1.27)
						(thickness 0.15)
					)
					(justify left bottom)
					(hide yes)
				)
			)
			(property "MPN" "DM3AT-SF-PEJM5"
				(at 57.15 -12.7 0)
				(effects
					(font
						(size 1.27 1.27)
						(thickness 0.15)
					)
					(justify left bottom)
					(hide yes)
				)
			)
			(property "Author" "Antmicro"
				(at 57.15 -15.24 0)
				(effects
					(font
						(size 1.27 1.27)
						(thickness 0.15)
					)
					(justify left bottom)
					(hide yes)
				)
			)
			(property "License" "Apache-2.0"
				(at 57.15 -17.78 0)
				(effects
					(font
						(size 1.27 1.27)
						(thickness 0.15)
					)
					(justify left bottom)
					(hide yes)
				)
			)
			(property "ki_keywords" "SMT"
				(at 0 0 0)
				(effects
					(font
						(size 1.27 1.27)
					)
					(hide yes)
				)
			)
			(symbol "DM3AT-SF-PEJM5_1_1"
				(polyline
					(pts
						(xy 12.7 -19.05) (xy 12.7 1.27) (xy 20.32 1.27) (xy 24.13 5.08) (xy 25.4 5.08) (xy 25.4 3.81)
						(xy 27.94 3.81) (xy 29.21 5.08) (xy 41.91 5.08) (xy 41.91 -19.05) (xy 12.7 -19.05)
					)
					(stroke
						(width 0.254)
						(type default)
					)
					(fill
						(type background)
					)
				)
				(rectangle
					(start 13.97 0.635)
					(end 16.51 -0.635)
					(stroke
						(width 0.254)
						(type default)
					)
					(fill
						(type background)
					)
				)
				(rectangle
					(start 13.97 -1.905)
					(end 16.51 -3.175)
					(stroke
						(width 0.254)
						(type default)
					)
					(fill
						(type background)
					)
				)
				(rectangle
					(start 13.97 -4.445)
					(end 16.51 -5.715)
					(stroke
						(width 0.254)
						(type default)
					)
					(fill
						(type background)
					)
				)
				(rectangle
					(start 13.97 -6.985)
					(end 16.51 -8.255)
					(stroke
						(width 0.254)
						(type default)
					)
					(fill
						(type background)
					)
				)
				(rectangle
					(start 13.97 -9.525)
					(end 16.51 -10.795)
					(stroke
						(width 0.254)
						(type default)
					)
					(fill
						(type background)
					)
				)
				(rectangle
					(start 13.97 -12.065)
					(end 16.51 -13.335)
					(stroke
						(width 0.254)
						(type default)
					)
					(fill
						(type background)
					)
				)
				(rectangle
					(start 13.97 -14.605)
					(end 16.51 -15.875)
					(stroke
						(width 0.254)
						(type default)
					)
					(fill
						(type background)
					)
				)
				(rectangle
					(start 13.97 -17.145)
					(end 16.51 -18.415)
					(stroke
						(width 0.254)
						(type default)
					)
					(fill
						(type background)
					)
				)
				(polyline
					(pts
						(xy 38.1 5.08) (xy 38.1 6.35) (xy 2.54 6.35) (xy 2.54 -26.67) (xy 38.1 -26.67) (xy 38.1 -19.05)
					)
					(stroke
						(width 0.254)
						(type default)
					)
					(fill
						(type background)
					)
				)
				(pin bidirectional line
					(at 0 0 0)
					(length 2.54)
					(name "DAT2"
						(effects
							(font
								(size 1.27 1.27)
							)
						)
					)
					(number "1"
						(effects
							(font
								(size 1.27 1.27)
							)
						)
					)
				)
				(pin bidirectional line
					(at 0 -2.54 0)
					(length 2.54)
					(name "DAT3/CD"
						(effects
							(font
								(size 1.27 1.27)
							)
						)
					)
					(number "2"
						(effects
							(font
								(size 1.27 1.27)
							)
						)
					)
				)
				(pin input line
					(at 0 -5.08 0)
					(length 2.54)
					(name "CMD"
						(effects
							(font
								(size 1.27 1.27)
							)
						)
					)
					(number "3"
						(effects
							(font
								(size 1.27 1.27)
							)
						)
					)
				)
				(pin power_in line
					(at 0 -7.62 0)
					(length 2.54)
					(name "VDD"
						(effects
							(font
								(size 1.27 1.27)
							)
						)
					)
					(number "4"
						(effects
							(font
								(size 1.27 1.27)
							)
						)
					)
				)
				(pin input line
					(at 0 -10.16 0)
					(length 2.54)
					(name "CLK"
						(effects
							(font
								(size 1.27 1.27)
							)
						)
					)
					(number "5"
						(effects
							(font
								(size 1.27 1.27)
							)
						)
					)
				)
				(pin power_in line
					(at 0 -12.7 0)
					(length 2.54)
					(name "VSS"
						(effects
							(font
								(size 1.27 1.27)
							)
						)
					)
					(number "6"
						(effects
							(font
								(size 1.27 1.27)
							)
						)
					)
				)
				(pin input line
					(at 0 -15.24 0)
					(length 2.54)
					(name "DAT0"
						(effects
							(font
								(size 1.27 1.27)
							)
						)
					)
					(number "7"
						(effects
							(font
								(size 1.27 1.27)
							)
						)
					)
				)
				(pin input line
					(at 0 -17.78 0)
					(length 2.54)
					(name "DAT1"
						(effects
							(font
								(size 1.27 1.27)
							)
						)
					)
					(number "8"
						(effects
							(font
								(size 1.27 1.27)
							)
						)
					)
				)
				(pin passive line
					(at 0 -20.32 0)
					(length 2.54)
					(name "DET_A"
						(effects
							(font
								(size 1.27 1.27)
							)
						)
					)
					(number "10"
						(effects
							(font
								(size 1.27 1.27)
							)
						)
					)
				)
				(pin passive line
					(at 0 -22.86 0)
					(length 2.54)
					(name "DET_B"
						(effects
							(font
								(size 1.27 1.27)
							)
						)
					)
					(number "9"
						(effects
							(font
								(size 1.27 1.27)
							)
						)
					)
				)
				(pin passive line
					(at 40.64 -22.86 180)
					(length 2.54)
					(name "SHIELD"
						(effects
							(font
								(size 1.27 1.27)
							)
						)
					)
					(number "11"
						(effects
							(font
								(size 1.27 1.27)
							)
						)
					)
				)
			)
		)
	(symbol "antmicroModularConnectorsJacksWithMagnetics:0895-2C1R-GVH"
			(exclude_from_sim no)
			(in_bom yes)
			(on_board yes)
			(property "Reference" "J"
				(at 40.64 -2.54 0)
				(effects
					(font
						(size 1.27 1.27)
						(thickness 0.15)
					)
					(justify left bottom)
				)
			)
			(property "Value" "0895-2C1R-GVH"
				(at 40.64 -5.08 0)
				(effects
					(font
						(size 1.27 1.27)
						(thickness 0.15)
					)
					(justify left bottom)
				)
			)
			(property "Footprint" "antmicro-footprints:0895-2C1R-GVH"
				(at 40.64 -7.62 0)
				(effects
					(font
						(size 1.27 1.27)
						(thickness 0.15)
					)
					(justify left bottom)
					(hide yes)
				)
			)
			(property "Datasheet" "https://www.belfuse.com/resources/drawings/magneticsolutions/dr-mag-0895-2c1r-gvh.pdf"
				(at 40.64 -10.16 0)
				(effects
					(font
						(size 1.27 1.27)
						(thickness 0.15)
					)
					(justify left bottom)
					(hide yes)
				)
			)
			(property "Description" "Modular connector with magnetics"
				(at 0 0 0)
				(effects
					(font
						(size 1.27 1.27)
					)
					(hide yes)
				)
			)
			(property "MPN" "0895-2C1R-GVH"
				(at 40.64 -12.7 0)
				(effects
					(font
						(size 1.27 1.27)
						(thickness 0.15)
					)
					(justify left bottom)
					(hide yes)
				)
			)
			(property "Manufacturer" "Bel Fuse"
				(at 40.64 -15.24 0)
				(effects
					(font
						(size 1.27 1.27)
						(thickness 0.15)
					)
					(justify left bottom)
					(hide yes)
				)
			)
			(property "Author" "Antmicro"
				(at 40.64 -17.78 0)
				(effects
					(font
						(size 1.27 1.27)
						(thickness 0.15)
					)
					(justify left bottom)
					(hide yes)
				)
			)
			(property "License" "Apache-2.0"
				(at 40.64 -20.32 0)
				(effects
					(font
						(size 1.27 1.27)
						(thickness 0.15)
					)
					(justify left bottom)
					(hide yes)
				)
			)
			(property "ki_keywords" "RJ45, HORIZONTAL, THT, ETHERNET, CONNECTOR"
				(at 0 0 0)
				(effects
					(font
						(size 1.27 1.27)
					)
					(hide yes)
				)
			)
			(symbol "0895-2C1R-GVH_1_1"
				(rectangle
					(start 5.08 2.54)
					(end 21.59 -35.56)
					(stroke
						(width 0.254)
						(type default)
					)
					(fill
						(type background)
					)
				)
				(polyline
					(pts
						(xy 17.018 -7.112) (xy 17.526 -6.858) (xy 17.272 -6.604) (xy 17.018 -7.112)
					)
					(stroke
						(width 0.254)
						(type default)
					)
					(fill
						(type background)
					)
				)
				(polyline
					(pts
						(xy 17.018 -7.874) (xy 17.526 -7.62) (xy 17.272 -7.366) (xy 17.018 -7.874)
					)
					(stroke
						(width 0.254)
						(type default)
					)
					(fill
						(type background)
					)
				)
				(polyline
					(pts
						(xy 17.018 -17.272) (xy 17.526 -17.018) (xy 17.272 -16.764) (xy 17.018 -17.272)
					)
					(stroke
						(width 0.254)
						(type default)
					)
					(fill
						(type background)
					)
				)
				(polyline
					(pts
						(xy 17.018 -18.034) (xy 17.526 -17.78) (xy 17.272 -17.526) (xy 17.018 -18.034)
					)
					(stroke
						(width 0.254)
						(type default)
					)
					(fill
						(type background)
					)
				)
				(polyline
					(pts
						(xy 17.526 -6.604) (xy 17.272 -6.858)
					)
					(stroke
						(width 0.254)
						(type default)
					)
					(fill
						(type background)
					)
				)
				(polyline
					(pts
						(xy 17.526 -7.366) (xy 17.272 -7.62)
					)
					(stroke
						(width 0.254)
						(type default)
					)
					(fill
						(type background)
					)
				)
				(polyline
					(pts
						(xy 17.526 -16.764) (xy 17.272 -17.018)
					)
					(stroke
						(width 0.254)
						(type default)
					)
					(fill
						(type background)
					)
				)
				(polyline
					(pts
						(xy 17.526 -17.526) (xy 17.272 -17.78)
					)
					(stroke
						(width 0.254)
						(type default)
					)
					(fill
						(type background)
					)
				)
				(polyline
					(pts
						(xy 17.78 -6.096) (xy 18.161 -7.112)
					)
					(stroke
						(width 0.254)
						(type default)
					)
					(fill
						(type background)
					)
				)
				(polyline
					(pts
						(xy 17.78 -6.096) (xy 18.542 -6.096)
					)
					(stroke
						(width 0.254)
						(type default)
					)
					(fill
						(type background)
					)
				)
				(polyline
					(pts
						(xy 17.78 -7.112) (xy 18.161 -7.112)
					)
					(stroke
						(width 0.254)
						(type default)
					)
					(fill
						(type background)
					)
				)
				(polyline
					(pts
						(xy 17.78 -16.256) (xy 18.161 -17.272)
					)
					(stroke
						(width 0.254)
						(type default)
					)
					(fill
						(type background)
					)
				)
				(polyline
					(pts
						(xy 17.78 -16.256) (xy 18.542 -16.256)
					)
					(stroke
						(width 0.254)
						(type default)
					)
					(fill
						(type background)
					)
				)
				(polyline
					(pts
						(xy 17.78 -17.272) (xy 18.161 -17.272)
					)
					(stroke
						(width 0.254)
						(type default)
					)
					(fill
						(type background)
					)
				)
				(polyline
					(pts
						(xy 18.034 -7.112) (xy 18.542 -7.112)
					)
					(stroke
						(width 0.254)
						(type default)
					)
					(fill
						(type background)
					)
				)
				(polyline
					(pts
						(xy 18.034 -17.272) (xy 18.542 -17.272)
					)
					(stroke
						(width 0.254)
						(type default)
					)
					(fill
						(type background)
					)
				)
				(polyline
					(pts
						(xy 18.161 -6.096) (xy 18.161 -5.461)
					)
					(stroke
						(width 0.254)
						(type default)
					)
					(fill
						(type background)
					)
				)
				(polyline
					(pts
						(xy 18.161 -7.112) (xy 18.542 -6.096)
					)
					(stroke
						(width 0.254)
						(type default)
					)
					(fill
						(type background)
					)
				)
				(polyline
					(pts
						(xy 18.161 -7.239) (xy 18.161 -7.874)
					)
					(stroke
						(width 0.254)
						(type default)
					)
					(fill
						(type background)
					)
				)
				(polyline
					(pts
						(xy 18.161 -7.874) (xy 19.685 -7.874)
					)
					(stroke
						(width 0.254)
						(type default)
					)
					(fill
						(type background)
					)
				)
				(polyline
					(pts
						(xy 18.161 -16.256) (xy 18.161 -15.621)
					)
					(stroke
						(width 0.254)
						(type default)
					)
					(fill
						(type background)
					)
				)
				(polyline
					(pts
						(xy 18.161 -17.272) (xy 18.542 -16.256)
					)
					(stroke
						(width 0.254)
						(type default)
					)
					(fill
						(type background)
					)
				)
				(polyline
					(pts
						(xy 18.161 -17.399) (xy 18.161 -18.034)
					)
					(stroke
						(width 0.254)
						(type default)
					)
					(fill
						(type background)
					)
				)
				(polyline
					(pts
						(xy 18.161 -18.034) (xy 19.685 -18.034)
					)
					(stroke
						(width 0.254)
						(type default)
					)
					(fill
						(type background)
					)
				)
				(polyline
					(pts
						(xy 18.923 -4.445) (xy 21.59 -4.445)
					)
					(stroke
						(width 0.254)
						(type default)
					)
					(fill
						(type background)
					)
				)
				(polyline
					(pts
						(xy 18.923 -5.461) (xy 18.923 -4.445)
					)
					(stroke
						(width 0.254)
						(type default)
					)
					(fill
						(type background)
					)
				)
				(polyline
					(pts
						(xy 18.923 -8.89) (xy 18.923 -7.874)
					)
					(stroke
						(width 0.254)
						(type default)
					)
					(fill
						(type background)
					)
				)
				(polyline
					(pts
						(xy 18.923 -8.89) (xy 21.59 -8.89)
					)
					(stroke
						(width 0.254)
						(type default)
					)
					(fill
						(type background)
					)
				)
				(polyline
					(pts
						(xy 18.923 -14.605) (xy 21.59 -14.605)
					)
					(stroke
						(width 0.254)
						(type default)
					)
					(fill
						(type background)
					)
				)
				(polyline
					(pts
						(xy 18.923 -15.621) (xy 18.923 -14.605)
					)
					(stroke
						(width 0.254)
						(type default)
					)
					(fill
						(type background)
					)
				)
				(polyline
					(pts
						(xy 18.923 -19.05) (xy 18.923 -18.034)
					)
					(stroke
						(width 0.254)
						(type default)
					)
					(fill
						(type background)
					)
				)
				(polyline
					(pts
						(xy 18.923 -19.05) (xy 21.59 -19.05)
					)
					(stroke
						(width 0.254)
						(type default)
					)
					(fill
						(type background)
					)
				)
				(polyline
					(pts
						(xy 19.685 -5.461) (xy 18.161 -5.461)
					)
					(stroke
						(width 0.254)
						(type default)
					)
					(fill
						(type background)
					)
				)
				(polyline
					(pts
						(xy 19.685 -6.096) (xy 19.304 -7.112)
					)
					(stroke
						(width 0.254)
						(type default)
					)
					(fill
						(type background)
					)
				)
				(polyline
					(pts
						(xy 19.685 -6.096) (xy 19.685 -5.461)
					)
					(stroke
						(width 0.254)
						(type default)
					)
					(fill
						(type background)
					)
				)
				(polyline
					(pts
						(xy 19.685 -7.239) (xy 19.685 -7.874)
					)
					(stroke
						(width 0.254)
						(type default)
					)
					(fill
						(type background)
					)
				)
				(polyline
					(pts
						(xy 19.685 -15.621) (xy 18.161 -15.621)
					)
					(stroke
						(width 0.254)
						(type default)
					)
					(fill
						(type background)
					)
				)
				(polyline
					(pts
						(xy 19.685 -16.256) (xy 19.304 -17.272)
					)
					(stroke
						(width 0.254)
						(type default)
					)
					(fill
						(type background)
					)
				)
				(polyline
					(pts
						(xy 19.685 -16.256) (xy 19.685 -15.621)
					)
					(stroke
						(width 0.254)
						(type default)
					)
					(fill
						(type background)
					)
				)
				(polyline
					(pts
						(xy 19.685 -17.399) (xy 19.685 -18.034)
					)
					(stroke
						(width 0.254)
						(type default)
					)
					(fill
						(type background)
					)
				)
				(polyline
					(pts
						(xy 19.812 -6.096) (xy 19.304 -6.096)
					)
					(stroke
						(width 0.254)
						(type default)
					)
					(fill
						(type background)
					)
				)
				(polyline
					(pts
						(xy 19.812 -16.256) (xy 19.304 -16.256)
					)
					(stroke
						(width 0.254)
						(type default)
					)
					(fill
						(type background)
					)
				)
				(polyline
					(pts
						(xy 20.066 -6.096) (xy 19.685 -6.096)
					)
					(stroke
						(width 0.254)
						(type default)
					)
					(fill
						(type background)
					)
				)
				(polyline
					(pts
						(xy 20.066 -7.112) (xy 19.304 -7.112)
					)
					(stroke
						(width 0.254)
						(type default)
					)
					(fill
						(type background)
					)
				)
				(polyline
					(pts
						(xy 20.066 -7.112) (xy 19.685 -6.096)
					)
					(stroke
						(width 0.254)
						(type default)
					)
					(fill
						(type background)
					)
				)
				(polyline
					(pts
						(xy 20.066 -16.256) (xy 19.685 -16.256)
					)
					(stroke
						(width 0.254)
						(type default)
					)
					(fill
						(type background)
					)
				)
				(polyline
					(pts
						(xy 20.066 -17.272) (xy 19.304 -17.272)
					)
					(stroke
						(width 0.254)
						(type default)
					)
					(fill
						(type background)
					)
				)
				(polyline
					(pts
						(xy 20.066 -17.272) (xy 19.685 -16.256)
					)
					(stroke
						(width 0.254)
						(type default)
					)
					(fill
						(type background)
					)
				)
				(polyline
					(pts
						(xy 20.32 -5.842) (xy 20.574 -5.588)
					)
					(stroke
						(width 0.254)
						(type default)
					)
					(fill
						(type background)
					)
				)
				(polyline
					(pts
						(xy 20.32 -6.604) (xy 20.574 -6.35)
					)
					(stroke
						(width 0.254)
						(type default)
					)
					(fill
						(type background)
					)
				)
				(polyline
					(pts
						(xy 20.32 -16.002) (xy 20.574 -15.748)
					)
					(stroke
						(width 0.254)
						(type default)
					)
					(fill
						(type background)
					)
				)
				(polyline
					(pts
						(xy 20.32 -16.764) (xy 20.574 -16.51)
					)
					(stroke
						(width 0.254)
						(type default)
					)
					(fill
						(type background)
					)
				)
				(polyline
					(pts
						(xy 20.828 -5.334) (xy 20.32 -5.588) (xy 20.574 -5.842) (xy 20.828 -5.334)
					)
					(stroke
						(width 0.254)
						(type default)
					)
					(fill
						(type background)
					)
				)
				(polyline
					(pts
						(xy 20.828 -6.096) (xy 20.32 -6.35) (xy 20.574 -6.604) (xy 20.828 -6.096)
					)
					(stroke
						(width 0.254)
						(type default)
					)
					(fill
						(type background)
					)
				)
				(polyline
					(pts
						(xy 20.828 -15.494) (xy 20.32 -15.748) (xy 20.574 -16.002) (xy 20.828 -15.494)
					)
					(stroke
						(width 0.254)
						(type default)
					)
					(fill
						(type background)
					)
				)
				(polyline
					(pts
						(xy 20.828 -16.256) (xy 20.32 -16.51) (xy 20.574 -16.764) (xy 20.828 -16.256)
					)
					(stroke
						(width 0.254)
						(type default)
					)
					(fill
						(type background)
					)
				)
				(text "LOWER"
					(at 14.605 -0.635 0)
					(effects
						(font
							(size 1.27 1.27)
							(thickness 0.15)
						)
						(justify left bottom)
					)
				)
				(text "Y"
					(at 17.399 -4.826 0)
					(effects
						(font
							(size 1.27 1.27)
							(thickness 0.15)
						)
						(justify left bottom)
					)
				)
				(text "Y"
					(at 17.399 -14.986 0)
					(effects
						(font
							(size 1.27 1.27)
							(thickness 0.15)
						)
						(justify left bottom)
					)
				)
				(text "G"
					(at 21.082 -8.128 0)
					(effects
						(font
							(size 1.27 1.27)
							(thickness 0.15)
						)
						(justify left bottom)
					)
				)
				(text "G"
					(at 21.082 -18.288 0)
					(effects
						(font
							(size 1.27 1.27)
							(thickness 0.15)
						)
						(justify left bottom)
					)
				)
				(pin passive line
					(at 0 0 0)
					(length 5.08)
					(name "TRD1-_1"
						(effects
							(font
								(size 1.27 1.27)
							)
						)
					)
					(number "1_1"
						(effects
							(font
								(size 1.27 1.27)
							)
						)
					)
				)
				(pin passive line
					(at 0 -2.54 0)
					(length 5.08)
					(name "TRD1+_1"
						(effects
							(font
								(size 1.27 1.27)
							)
						)
					)
					(number "2_1"
						(effects
							(font
								(size 1.27 1.27)
							)
						)
					)
				)
				(pin passive line
					(at 0 -5.08 0)
					(length 5.08)
					(name "TRD2-_1"
						(effects
							(font
								(size 1.27 1.27)
							)
						)
					)
					(number "3_1"
						(effects
							(font
								(size 1.27 1.27)
							)
						)
					)
				)
				(pin passive line
					(at 0 -7.62 0)
					(length 5.08)
					(name "TRD2+_1"
						(effects
							(font
								(size 1.27 1.27)
							)
						)
					)
					(number "4_1"
						(effects
							(font
								(size 1.27 1.27)
							)
						)
					)
				)
				(pin passive line
					(at 0 -10.16 0)
					(length 5.08)
					(name "TRD3-_1"
						(effects
							(font
								(size 1.27 1.27)
							)
						)
					)
					(number "5_1"
						(effects
							(font
								(size 1.27 1.27)
							)
						)
					)
				)
				(pin passive line
					(at 0 -12.7 0)
					(length 5.08)
					(name "TRD3+_1"
						(effects
							(font
								(size 1.27 1.27)
							)
						)
					)
					(number "6_1"
						(effects
							(font
								(size 1.27 1.27)
							)
						)
					)
				)
				(pin passive line
					(at 0 -15.24 0)
					(length 5.08)
					(name "TRD4-_1"
						(effects
							(font
								(size 1.27 1.27)
							)
						)
					)
					(number "7_1"
						(effects
							(font
								(size 1.27 1.27)
							)
						)
					)
				)
				(pin passive line
					(at 0 -17.78 0)
					(length 5.08)
					(name "TRD4+_1"
						(effects
							(font
								(size 1.27 1.27)
							)
						)
					)
					(number "8_1"
						(effects
							(font
								(size 1.27 1.27)
							)
						)
					)
				)
				(pin passive line
					(at 0 -20.32 0)
					(length 5.08)
					(name "TRDCT1/2/3/4_1"
						(effects
							(font
								(size 1.27 1.27)
							)
						)
					)
					(number "9_1"
						(effects
							(font
								(size 1.27 1.27)
							)
						)
					)
				)
				(pin passive line
					(at 0 -25.4 0)
					(length 5.08)
					(name "VC12_1"
						(effects
							(font
								(size 1.27 1.27)
							)
						)
					)
					(number "14_1"
						(effects
							(font
								(size 1.27 1.27)
							)
						)
					)
				)
				(pin passive line
					(at 0 -27.94 0)
					(length 5.08)
					(name "VC36_1"
						(effects
							(font
								(size 1.27 1.27)
							)
						)
					)
					(number "11_1"
						(effects
							(font
								(size 1.27 1.27)
							)
						)
					)
				)
				(pin passive line
					(at 0 -30.48 0)
					(length 5.08)
					(name "VC45_1"
						(effects
							(font
								(size 1.27 1.27)
							)
						)
					)
					(number "12_1"
						(effects
							(font
								(size 1.27 1.27)
							)
						)
					)
				)
				(pin passive line
					(at 0 -33.02 0)
					(length 5.08)
					(name "VC78_1"
						(effects
							(font
								(size 1.27 1.27)
							)
						)
					)
					(number "13_1"
						(effects
							(font
								(size 1.27 1.27)
							)
						)
					)
				)
				(pin passive line
					(at 26.67 -4.445 180)
					(length 5.08)
					(name "~"
						(effects
							(font
								(size 1.27 1.27)
							)
						)
					)
					(number "15_1"
						(effects
							(font
								(size 1.27 1.27)
							)
						)
					)
				)
				(pin passive line
					(at 26.67 -8.89 180)
					(length 5.08)
					(name "~"
						(effects
							(font
								(size 1.27 1.27)
							)
						)
					)
					(number "16_1"
						(effects
							(font
								(size 1.27 1.27)
							)
						)
					)
				)
				(pin passive line
					(at 26.67 -14.605 180)
					(length 5.08)
					(name "~"
						(effects
							(font
								(size 1.27 1.27)
							)
						)
					)
					(number "17_1"
						(effects
							(font
								(size 1.27 1.27)
							)
						)
					)
				)
				(pin passive line
					(at 26.67 -19.05 180)
					(length 5.08)
					(name "~"
						(effects
							(font
								(size 1.27 1.27)
							)
						)
					)
					(number "18_1"
						(effects
							(font
								(size 1.27 1.27)
							)
						)
					)
				)
				(pin passive line
					(at 26.67 -30.48 180)
					(length 5.08)
					(name "SHIELD"
						(effects
							(font
								(size 1.27 1.27)
							)
						)
					)
					(number "SH"
						(effects
							(font
								(size 1.27 1.27)
							)
						)
					)
				)
				(pin passive line
					(at 26.67 -30.48 180)
					(length 5.08)
					(hide yes)
					(name "SHIELD"
						(effects
							(font
								(size 1.27 1.27)
							)
						)
					)
					(number "SH"
						(effects
							(font
								(size 1.27 1.27)
							)
						)
					)
				)
				(pin passive line
					(at 26.67 -30.48 180)
					(length 5.08)
					(hide yes)
					(name "SHIELD"
						(effects
							(font
								(size 1.27 1.27)
							)
						)
					)
					(number "SH"
						(effects
							(font
								(size 1.27 1.27)
							)
						)
					)
				)
				(pin passive line
					(at 26.67 -30.48 180)
					(length 5.08)
					(hide yes)
					(name "SHIELD"
						(effects
							(font
								(size 1.27 1.27)
							)
						)
					)
					(number "SH"
						(effects
							(font
								(size 1.27 1.27)
							)
						)
					)
				)
				(pin passive line
					(at 26.67 -30.48 180)
					(length 5.08)
					(hide yes)
					(name "SHIELD"
						(effects
							(font
								(size 1.27 1.27)
							)
						)
					)
					(number "SH"
						(effects
							(font
								(size 1.27 1.27)
							)
						)
					)
				)
				(pin passive line
					(at 26.67 -30.48 180)
					(length 5.08)
					(hide yes)
					(name "SHIELD"
						(effects
							(font
								(size 1.27 1.27)
							)
						)
					)
					(number "SH"
						(effects
							(font
								(size 1.27 1.27)
							)
						)
					)
				)
				(pin power_in line
					(at 26.67 -33.02 180)
					(length 5.08)
					(name "GND_1"
						(effects
							(font
								(size 1.27 1.27)
							)
						)
					)
					(number "10_1"
						(effects
							(font
								(size 1.27 1.27)
							)
						)
					)
				)
			)
			(symbol "0895-2C1R-GVH_2_1"
				(rectangle
					(start 5.08 2.54)
					(end 21.59 -35.56)
					(stroke
						(width 0.254)
						(type default)
					)
					(fill
						(type background)
					)
				)
				(polyline
					(pts
						(xy 17.018 -7.112) (xy 17.526 -6.858) (xy 17.272 -6.604) (xy 17.018 -7.112)
					)
					(stroke
						(width 0.254)
						(type default)
					)
					(fill
						(type background)
					)
				)
				(polyline
					(pts
						(xy 17.018 -7.874) (xy 17.526 -7.62) (xy 17.272 -7.366) (xy 17.018 -7.874)
					)
					(stroke
						(width 0.254)
						(type default)
					)
					(fill
						(type background)
					)
				)
				(polyline
					(pts
						(xy 17.018 -17.272) (xy 17.526 -17.018) (xy 17.272 -16.764) (xy 17.018 -17.272)
					)
					(stroke
						(width 0.254)
						(type default)
					)
					(fill
						(type background)
					)
				)
				(polyline
					(pts
						(xy 17.018 -18.034) (xy 17.526 -17.78) (xy 17.272 -17.526) (xy 17.018 -18.034)
					)
					(stroke
						(width 0.254)
						(type default)
					)
					(fill
						(type background)
					)
				)
				(polyline
					(pts
						(xy 17.526 -6.604) (xy 17.272 -6.858)
					)
					(stroke
						(width 0.254)
						(type default)
					)
					(fill
						(type background)
					)
				)
				(polyline
					(pts
						(xy 17.526 -7.366) (xy 17.272 -7.62)
					)
					(stroke
						(width 0.254)
						(type default)
					)
					(fill
						(type background)
					)
				)
				(polyline
					(pts
						(xy 17.526 -16.764) (xy 17.272 -17.018)
					)
					(stroke
						(width 0.254)
						(type default)
					)
					(fill
						(type background)
					)
				)
				(polyline
					(pts
						(xy 17.526 -17.526) (xy 17.272 -17.78)
					)
					(stroke
						(width 0.254)
						(type default)
					)
					(fill
						(type background)
					)
				)
				(polyline
					(pts
						(xy 17.78 -6.096) (xy 18.161 -7.112)
					)
					(stroke
						(width 0.254)
						(type default)
					)
					(fill
						(type background)
					)
				)
				(polyline
					(pts
						(xy 17.78 -6.096) (xy 18.542 -6.096)
					)
					(stroke
						(width 0.254)
						(type default)
					)
					(fill
						(type background)
					)
				)
				(polyline
					(pts
						(xy 17.78 -7.112) (xy 18.161 -7.112)
					)
					(stroke
						(width 0.254)
						(type default)
					)
					(fill
						(type background)
					)
				)
				(polyline
					(pts
						(xy 17.78 -16.256) (xy 18.161 -17.272)
					)
					(stroke
						(width 0.254)
						(type default)
					)
					(fill
						(type background)
					)
				)
				(polyline
					(pts
						(xy 17.78 -16.256) (xy 18.542 -16.256)
					)
					(stroke
						(width 0.254)
						(type default)
					)
					(fill
						(type background)
					)
				)
				(polyline
					(pts
						(xy 17.78 -17.272) (xy 18.161 -17.272)
					)
					(stroke
						(width 0.254)
						(type default)
					)
					(fill
						(type background)
					)
				)
				(polyline
					(pts
						(xy 18.034 -7.112) (xy 18.542 -7.112)
					)
					(stroke
						(width 0.254)
						(type default)
					)
					(fill
						(type background)
					)
				)
				(polyline
					(pts
						(xy 18.034 -17.272) (xy 18.542 -17.272)
					)
					(stroke
						(width 0.254)
						(type default)
					)
					(fill
						(type background)
					)
				)
				(polyline
					(pts
						(xy 18.161 -6.096) (xy 18.161 -5.461)
					)
					(stroke
						(width 0.254)
						(type default)
					)
					(fill
						(type background)
					)
				)
				(polyline
					(pts
						(xy 18.161 -7.112) (xy 18.542 -6.096)
					)
					(stroke
						(width 0.254)
						(type default)
					)
					(fill
						(type background)
					)
				)
				(polyline
					(pts
						(xy 18.161 -7.239) (xy 18.161 -7.874)
					)
					(stroke
						(width 0.254)
						(type default)
					)
					(fill
						(type background)
					)
				)
				(polyline
					(pts
						(xy 18.161 -7.874) (xy 19.685 -7.874)
					)
					(stroke
						(width 0.254)
						(type default)
					)
					(fill
						(type background)
					)
				)
				(polyline
					(pts
						(xy 18.161 -16.256) (xy 18.161 -15.621)
					)
					(stroke
						(width 0.254)
						(type default)
					)
					(fill
						(type background)
					)
				)
				(polyline
					(pts
						(xy 18.161 -17.272) (xy 18.542 -16.256)
					)
					(stroke
						(width 0.254)
						(type default)
					)
					(fill
						(type background)
					)
				)
				(polyline
					(pts
						(xy 18.161 -17.399) (xy 18.161 -18.034)
					)
					(stroke
						(width 0.254)
						(type default)
					)
					(fill
						(type background)
					)
				)
				(polyline
					(pts
						(xy 18.161 -18.034) (xy 19.685 -18.034)
					)
					(stroke
						(width 0.254)
						(type default)
					)
					(fill
						(type background)
					)
				)
				(polyline
					(pts
						(xy 18.923 -4.445) (xy 21.59 -4.445)
					)
					(stroke
						(width 0.254)
						(type default)
					)
					(fill
						(type background)
					)
				)
				(polyline
					(pts
						(xy 18.923 -5.461) (xy 18.923 -4.445)
					)
					(stroke
						(width 0.254)
						(type default)
					)
					(fill
						(type background)
					)
				)
				(polyline
					(pts
						(xy 18.923 -8.89) (xy 18.923 -7.874)
					)
					(stroke
						(width 0.254)
						(type default)
					)
					(fill
						(type background)
					)
				)
				(polyline
					(pts
						(xy 18.923 -8.89) (xy 21.59 -8.89)
					)
					(stroke
						(width 0.254)
						(type default)
					)
					(fill
						(type background)
					)
				)
				(polyline
					(pts
						(xy 18.923 -14.605) (xy 21.59 -14.605)
					)
					(stroke
						(width 0.254)
						(type default)
					)
					(fill
						(type background)
					)
				)
				(polyline
					(pts
						(xy 18.923 -15.621) (xy 18.923 -14.605)
					)
					(stroke
						(width 0.254)
						(type default)
					)
					(fill
						(type background)
					)
				)
				(polyline
					(pts
						(xy 18.923 -19.05) (xy 18.923 -18.034)
					)
					(stroke
						(width 0.254)
						(type default)
					)
					(fill
						(type background)
					)
				)
				(polyline
					(pts
						(xy 18.923 -19.05) (xy 21.59 -19.05)
					)
					(stroke
						(width 0.254)
						(type default)
					)
					(fill
						(type background)
					)
				)
				(polyline
					(pts
						(xy 19.685 -5.461) (xy 18.161 -5.461)
					)
					(stroke
						(width 0.254)
						(type default)
					)
					(fill
						(type background)
					)
				)
				(polyline
					(pts
						(xy 19.685 -6.096) (xy 19.304 -7.112)
					)
					(stroke
						(width 0.254)
						(type default)
					)
					(fill
						(type background)
					)
				)
				(polyline
					(pts
						(xy 19.685 -6.096) (xy 19.685 -5.461)
					)
					(stroke
						(width 0.254)
						(type default)
					)
					(fill
						(type background)
					)
				)
				(polyline
					(pts
						(xy 19.685 -7.239) (xy 19.685 -7.874)
					)
					(stroke
						(width 0.254)
						(type default)
					)
					(fill
						(type background)
					)
				)
				(polyline
					(pts
						(xy 19.685 -15.621) (xy 18.161 -15.621)
					)
					(stroke
						(width 0.254)
						(type default)
					)
					(fill
						(type background)
					)
				)
				(polyline
					(pts
						(xy 19.685 -16.256) (xy 19.304 -17.272)
					)
					(stroke
						(width 0.254)
						(type default)
					)
					(fill
						(type background)
					)
				)
				(polyline
					(pts
						(xy 19.685 -16.256) (xy 19.685 -15.621)
					)
					(stroke
						(width 0.254)
						(type default)
					)
					(fill
						(type background)
					)
				)
				(polyline
					(pts
						(xy 19.685 -17.399) (xy 19.685 -18.034)
					)
					(stroke
						(width 0.254)
						(type default)
					)
					(fill
						(type background)
					)
				)
				(polyline
					(pts
						(xy 19.812 -6.096) (xy 19.304 -6.096)
					)
					(stroke
						(width 0.254)
						(type default)
					)
					(fill
						(type background)
					)
				)
				(polyline
					(pts
						(xy 19.812 -16.256) (xy 19.304 -16.256)
					)
					(stroke
						(width 0.254)
						(type default)
					)
					(fill
						(type background)
					)
				)
				(polyline
					(pts
						(xy 20.066 -6.096) (xy 19.685 -6.096)
					)
					(stroke
						(width 0.254)
						(type default)
					)
					(fill
						(type background)
					)
				)
				(polyline
					(pts
						(xy 20.066 -7.112) (xy 19.304 -7.112)
					)
					(stroke
						(width 0.254)
						(type default)
					)
					(fill
						(type background)
					)
				)
				(polyline
					(pts
						(xy 20.066 -7.112) (xy 19.685 -6.096)
					)
					(stroke
						(width 0.254)
						(type default)
					)
					(fill
						(type background)
					)
				)
				(polyline
					(pts
						(xy 20.066 -16.256) (xy 19.685 -16.256)
					)
					(stroke
						(width 0.254)
						(type default)
					)
					(fill
						(type background)
					)
				)
				(polyline
					(pts
						(xy 20.066 -17.272) (xy 19.304 -17.272)
					)
					(stroke
						(width 0.254)
						(type default)
					)
					(fill
						(type background)
					)
				)
				(polyline
					(pts
						(xy 20.066 -17.272) (xy 19.685 -16.256)
					)
					(stroke
						(width 0.254)
						(type default)
					)
					(fill
						(type background)
					)
				)
				(polyline
					(pts
						(xy 20.32 -5.842) (xy 20.574 -5.588)
					)
					(stroke
						(width 0.254)
						(type default)
					)
					(fill
						(type background)
					)
				)
				(polyline
					(pts
						(xy 20.32 -6.604) (xy 20.574 -6.35)
					)
					(stroke
						(width 0.254)
						(type default)
					)
					(fill
						(type background)
					)
				)
				(polyline
					(pts
						(xy 20.32 -16.002) (xy 20.574 -15.748)
					)
					(stroke
						(width 0.254)
						(type default)
					)
					(fill
						(type background)
					)
				)
				(polyline
					(pts
						(xy 20.32 -16.764) (xy 20.574 -16.51)
					)
					(stroke
						(width 0.254)
						(type default)
					)
					(fill
						(type background)
					)
				)
				(polyline
					(pts
						(xy 20.828 -5.334) (xy 20.32 -5.588) (xy 20.574 -5.842) (xy 20.828 -5.334)
					)
					(stroke
						(width 0.254)
						(type default)
					)
					(fill
						(type background)
					)
				)
				(polyline
					(pts
						(xy 20.828 -6.096) (xy 20.32 -6.35) (xy 20.574 -6.604) (xy 20.828 -6.096)
					)
					(stroke
						(width 0.254)
						(type default)
					)
					(fill
						(type background)
					)
				)
				(polyline
					(pts
						(xy 20.828 -15.494) (xy 20.32 -15.748) (xy 20.574 -16.002) (xy 20.828 -15.494)
					)
					(stroke
						(width 0.254)
						(type default)
					)
					(fill
						(type background)
					)
				)
				(polyline
					(pts
						(xy 20.828 -16.256) (xy 20.32 -16.51) (xy 20.574 -16.764) (xy 20.828 -16.256)
					)
					(stroke
						(width 0.254)
						(type default)
					)
					(fill
						(type background)
					)
				)
				(text "UPPER"
					(at 14.605 -0.635 0)
					(effects
						(font
							(size 1.27 1.27)
							(thickness 0.15)
						)
						(justify left bottom)
					)
				)
				(text "Y"
					(at 17.399 -4.826 0)
					(effects
						(font
							(size 1.27 1.27)
							(thickness 0.15)
						)
						(justify left bottom)
					)
				)
				(text "Y"
					(at 17.399 -14.986 0)
					(effects
						(font
							(size 1.27 1.27)
							(thickness 0.15)
						)
						(justify left bottom)
					)
				)
				(text "G"
					(at 21.082 -8.128 0)
					(effects
						(font
							(size 1.27 1.27)
							(thickness 0.15)
						)
						(justify left bottom)
					)
				)
				(text "G"
					(at 21.082 -18.288 0)
					(effects
						(font
							(size 1.27 1.27)
							(thickness 0.15)
						)
						(justify left bottom)
					)
				)
				(pin passive line
					(at 0 0 0)
					(length 5.08)
					(name "TRD1-_2"
						(effects
							(font
								(size 1.27 1.27)
							)
						)
					)
					(number "1_2"
						(effects
							(font
								(size 1.27 1.27)
							)
						)
					)
				)
				(pin passive line
					(at 0 -2.54 0)
					(length 5.08)
					(name "TRD1+_2"
						(effects
							(font
								(size 1.27 1.27)
							)
						)
					)
					(number "2_2"
						(effects
							(font
								(size 1.27 1.27)
							)
						)
					)
				)
				(pin passive line
					(at 0 -5.08 0)
					(length 5.08)
					(name "TRD2-_2"
						(effects
							(font
								(size 1.27 1.27)
							)
						)
					)
					(number "3_2"
						(effects
							(font
								(size 1.27 1.27)
							)
						)
					)
				)
				(pin passive line
					(at 0 -7.62 0)
					(length 5.08)
					(name "TRD2+_2"
						(effects
							(font
								(size 1.27 1.27)
							)
						)
					)
					(number "4_2"
						(effects
							(font
								(size 1.27 1.27)
							)
						)
					)
				)
				(pin passive line
					(at 0 -10.16 0)
					(length 5.08)
					(name "TRD3-_2"
						(effects
							(font
								(size 1.27 1.27)
							)
						)
					)
					(number "5_2"
						(effects
							(font
								(size 1.27 1.27)
							)
						)
					)
				)
				(pin passive line
					(at 0 -12.7 0)
					(length 5.08)
					(name "TRD3+_2"
						(effects
							(font
								(size 1.27 1.27)
							)
						)
					)
					(number "6_2"
						(effects
							(font
								(size 1.27 1.27)
							)
						)
					)
				)
				(pin passive line
					(at 0 -15.24 0)
					(length 5.08)
					(name "TRD4-_2"
						(effects
							(font
								(size 1.27 1.27)
							)
						)
					)
					(number "7_2"
						(effects
							(font
								(size 1.27 1.27)
							)
						)
					)
				)
				(pin passive line
					(at 0 -17.78 0)
					(length 5.08)
					(name "TRD4+_2"
						(effects
							(font
								(size 1.27 1.27)
							)
						)
					)
					(number "8_2"
						(effects
							(font
								(size 1.27 1.27)
							)
						)
					)
				)
				(pin passive line
					(at 0 -20.32 0)
					(length 5.08)
					(name "TRDCT1/2/3/4_2"
						(effects
							(font
								(size 1.27 1.27)
							)
						)
					)
					(number "9_2"
						(effects
							(font
								(size 1.27 1.27)
							)
						)
					)
				)
				(pin passive line
					(at 0 -25.4 0)
					(length 5.08)
					(name "VC12_2"
						(effects
							(font
								(size 1.27 1.27)
							)
						)
					)
					(number "14_2"
						(effects
							(font
								(size 1.27 1.27)
							)
						)
					)
				)
				(pin passive line
					(at 0 -27.94 0)
					(length 5.08)
					(name "VC36_2"
						(effects
							(font
								(size 1.27 1.27)
							)
						)
					)
					(number "11_2"
						(effects
							(font
								(size 1.27 1.27)
							)
						)
					)
				)
				(pin passive line
					(at 0 -30.48 0)
					(length 5.08)
					(name "VC45_2"
						(effects
							(font
								(size 1.27 1.27)
							)
						)
					)
					(number "12_2"
						(effects
							(font
								(size 1.27 1.27)
							)
						)
					)
				)
				(pin passive line
					(at 0 -33.02 0)
					(length 5.08)
					(name "VC78_2"
						(effects
							(font
								(size 1.27 1.27)
							)
						)
					)
					(number "13_2"
						(effects
							(font
								(size 1.27 1.27)
							)
						)
					)
				)
				(pin passive line
					(at 26.67 -4.445 180)
					(length 5.08)
					(name "~"
						(effects
							(font
								(size 1.27 1.27)
							)
						)
					)
					(number "15_2"
						(effects
							(font
								(size 1.27 1.27)
							)
						)
					)
				)
				(pin passive line
					(at 26.67 -8.89 180)
					(length 5.08)
					(name "~"
						(effects
							(font
								(size 1.27 1.27)
							)
						)
					)
					(number "16_2"
						(effects
							(font
								(size 1.27 1.27)
							)
						)
					)
				)
				(pin passive line
					(at 26.67 -14.605 180)
					(length 5.08)
					(name "~"
						(effects
							(font
								(size 1.27 1.27)
							)
						)
					)
					(number "17_2"
						(effects
							(font
								(size 1.27 1.27)
							)
						)
					)
				)
				(pin passive line
					(at 26.67 -19.05 180)
					(length 5.08)
					(name "~"
						(effects
							(font
								(size 1.27 1.27)
							)
						)
					)
					(number "18_2"
						(effects
							(font
								(size 1.27 1.27)
							)
						)
					)
				)
				(pin passive line
					(at 26.67 -33.02 180)
					(length 5.08)
					(name "GND_2"
						(effects
							(font
								(size 1.27 1.27)
							)
						)
					)
					(number "10_2"
						(effects
							(font
								(size 1.27 1.27)
							)
						)
					)
				)
			)
		)
	(symbol "antmicroOscillators:Oscillator_200MHz_AX3DC"
			(exclude_from_sim no)
			(in_bom yes)
			(on_board yes)
			(property "Reference" "Y"
				(at 28.575 -2.54 0)
				(effects
					(font
						(size 1.27 1.27)
						(thickness 0.15)
					)
					(justify left bottom)
				)
			)
			(property "Value" "Oscillator_200MHz_AX3DC"
				(at 28.575 -12.7 0)
				(effects
					(font
						(size 1.27 1.27)
						(thickness 0.15)
					)
					(justify left bottom)
					(hide yes)
				)
			)
			(property "Footprint" "antmicro-footprints:Oscillator_SMD_Abracon_AX3_3.2x2.5x1mm"
				(at 28.575 -15.24 0)
				(effects
					(font
						(size 1.27 1.27)
						(thickness 0.15)
					)
					(justify left bottom)
					(hide yes)
				)
			)
			(property "Datasheet" "https://abracon.com/datasheets/AX3.pdf"
				(at 28.575 -17.78 0)
				(effects
					(font
						(size 1.27 1.27)
						(thickness 0.15)
					)
					(justify left bottom)
					(hide yes)
				)
			)
			(property "Description" "150 MHz XO (Standard) LVDS Oscillator 1.8V Enable/Disable 6-SMD, No Lead"
				(at 0 0 0)
				(effects
					(font
						(size 1.27 1.27)
					)
					(hide yes)
				)
			)
			(property "Manufacturer" "Abracon"
				(at 28.575 -5.08 0)
				(effects
					(font
						(size 1.27 1.27)
						(thickness 0.15)
					)
					(justify left bottom)
					(hide yes)
				)
			)
			(property "MPN" "AX3DCF1-200.0000"
				(at 28.575 -7.62 0)
				(effects
					(font
						(size 1.27 1.27)
						(thickness 0.15)
					)
					(justify left bottom)
				)
			)
			(property "Val" "200 MHz"
				(at 28.575 -10.16 0)
				(effects
					(font
						(size 1.27 1.27)
						(thickness 0.15)
					)
					(justify left bottom)
				)
			)
			(property "Author" "Antmicro"
				(at 28.575 -20.32 0)
				(effects
					(font
						(size 1.27 1.27)
						(thickness 0.15)
					)
					(justify left bottom)
					(hide yes)
				)
			)
			(property "License" "Apache-2.0"
				(at 28.575 -22.86 0)
				(effects
					(font
						(size 1.27 1.27)
						(thickness 0.15)
					)
					(justify left bottom)
					(hide yes)
				)
			)
			(property "ki_keywords" "OSCILLATOR, LVDS"
				(at 0 0 0)
				(effects
					(font
						(size 1.27 1.27)
					)
					(hide yes)
				)
			)
			(symbol "Oscillator_200MHz_AX3DC_1_1"
				(rectangle
					(start 2.54 2.54)
					(end 16.51 -7.62)
					(stroke
						(width 0.254)
						(type default)
					)
					(fill
						(type background)
					)
				)
				(polyline
					(pts
						(xy 7.62 -1.27) (xy 8.255 -1.27) (xy 8.255 0) (xy 8.89 0) (xy 8.89 -1.27) (xy 9.525 -1.27) (xy 9.525 0)
						(xy 10.16 0) (xy 10.16 -1.27)
					)
					(stroke
						(width 0.254)
						(type default)
					)
					(fill
						(type background)
					)
				)
				(pin power_in line
					(at 0 0 0)
					(length 2.54)
					(name "VCC"
						(effects
							(font
								(size 1.27 1.27)
							)
						)
					)
					(number "6"
						(effects
							(font
								(size 1.27 1.27)
							)
						)
					)
				)
				(pin input line
					(at 0 -2.54 0)
					(length 2.54)
					(name "EN"
						(effects
							(font
								(size 1.27 1.27)
							)
						)
					)
					(number "1"
						(effects
							(font
								(size 1.27 1.27)
							)
						)
					)
				)
				(pin power_in line
					(at 0 -5.08 0)
					(length 2.54)
					(name "GND"
						(effects
							(font
								(size 1.27 1.27)
							)
						)
					)
					(number "3"
						(effects
							(font
								(size 1.27 1.27)
							)
						)
					)
				)
				(pin no_connect line
					(at 16.51 -5.08 180)
					(length 2.54)
					(hide yes)
					(name "NC"
						(effects
							(font
								(size 1.27 1.27)
							)
						)
					)
					(number "2"
						(effects
							(font
								(size 1.27 1.27)
							)
						)
					)
				)
				(pin output line
					(at 19.05 0 180)
					(length 2.54)
					(name "OUT+"
						(effects
							(font
								(size 1.27 1.27)
							)
						)
					)
					(number "4"
						(effects
							(font
								(size 1.27 1.27)
							)
						)
					)
				)
				(pin output line
					(at 19.05 -2.54 180)
					(length 2.54)
					(name "OUT-"
						(effects
							(font
								(size 1.27 1.27)
							)
						)
					)
					(number "5"
						(effects
							(font
								(size 1.27 1.27)
							)
						)
					)
				)
			)
		)
	(symbol "antmicroPMICORControllersIdealDiodes:LTC4412IS6"
			(exclude_from_sim no)
			(in_bom yes)
			(on_board yes)
			(property "Reference" "U"
				(at 31.75 -2.54 0)
				(effects
					(font
						(size 1.27 1.27)
						(thickness 0.15)
					)
					(justify left bottom)
				)
			)
			(property "Value" "LTC4412IS6"
				(at 31.75 -5.08 0)
				(effects
					(font
						(size 1.27 1.27)
						(thickness 0.15)
					)
					(justify left bottom)
					(hide yes)
				)
			)
			(property "Footprint" "antmicro-footprints:SOT-23-6"
				(at 31.75 -7.62 0)
				(effects
					(font
						(size 1.27 1.27)
						(thickness 0.15)
					)
					(justify left bottom)
					(hide yes)
				)
			)
			(property "Datasheet" "https://www.mouser.com/datasheet/2/308/NCV8187_D-1813214.pdf"
				(at 31.75 -10.16 0)
				(effects
					(font
						(size 1.27 1.27)
						(thickness 0.15)
					)
					(justify left bottom)
					(hide yes)
				)
			)
			(property "Description" "Ideal diode controller"
				(at 0 0 0)
				(effects
					(font
						(size 1.27 1.27)
					)
					(hide yes)
				)
			)
			(property "MPN" "LTC4412IS6#TRMPBF"
				(at 31.75 -12.7 0)
				(effects
					(font
						(size 1.27 1.27)
						(thickness 0.15)
					)
					(justify left bottom)
				)
			)
			(property "Manufacturer" "Analog Devices"
				(at 31.75 -15.24 0)
				(effects
					(font
						(size 1.27 1.27)
						(thickness 0.15)
					)
					(justify left bottom)
					(hide yes)
				)
			)
			(property "Author" "Antmicro"
				(at 31.75 -17.78 0)
				(effects
					(font
						(size 1.27 1.27)
						(thickness 0.15)
					)
					(justify left bottom)
					(hide yes)
				)
			)
			(property "License" "Apache-2.0"
				(at 31.75 -20.32 0)
				(effects
					(font
						(size 1.27 1.27)
						(thickness 0.15)
					)
					(justify left bottom)
					(hide yes)
				)
			)
			(property "ki_keywords" "SMT, CONTROLLER, IC, DIODE"
				(at 0 0 0)
				(effects
					(font
						(size 1.27 1.27)
					)
					(hide yes)
				)
			)
			(symbol "LTC4412IS6_1_1"
				(rectangle
					(start 2.54 2.54)
					(end 15.24 -7.62)
					(stroke
						(width 0.254)
						(type default)
					)
					(fill
						(type background)
					)
				)
				(pin power_in line
					(at 0 0 0)
					(length 2.54)
					(name "IN"
						(effects
							(font
								(size 1.27 1.27)
							)
						)
					)
					(number "1"
						(effects
							(font
								(size 1.27 1.27)
							)
						)
					)
				)
				(pin input line
					(at 0 -2.54 0)
					(length 2.54)
					(name "CTL"
						(effects
							(font
								(size 1.27 1.27)
							)
						)
					)
					(number "3"
						(effects
							(font
								(size 1.27 1.27)
							)
						)
					)
				)
				(pin power_in line
					(at 0 -5.08 0)
					(length 2.54)
					(name "GND"
						(effects
							(font
								(size 1.27 1.27)
							)
						)
					)
					(number "2"
						(effects
							(font
								(size 1.27 1.27)
							)
						)
					)
				)
				(pin input line
					(at 17.78 0 180)
					(length 2.54)
					(name "SENSE"
						(effects
							(font
								(size 1.27 1.27)
							)
						)
					)
					(number "6"
						(effects
							(font
								(size 1.27 1.27)
							)
						)
					)
				)
				(pin output line
					(at 17.78 -2.54 180)
					(length 2.54)
					(name "GATE"
						(effects
							(font
								(size 1.27 1.27)
							)
						)
					)
					(number "5"
						(effects
							(font
								(size 1.27 1.27)
							)
						)
					)
				)
				(pin output line
					(at 17.78 -5.08 180)
					(length 2.54)
					(name "STAT"
						(effects
							(font
								(size 1.27 1.27)
							)
						)
					)
					(number "4"
						(effects
							(font
								(size 1.27 1.27)
							)
						)
					)
				)
			)
		)
	(symbol "antmicroPMICPowerDistributionSwitchesLoadDrivers:AP22615A_TSOT26"
			(exclude_from_sim no)
			(in_bom yes)
			(on_board yes)
			(property "Reference" "U"
				(at 30.48 -2.54 0)
				(effects
					(font
						(size 1.27 1.27)
						(thickness 0.15)
					)
					(justify left bottom)
				)
			)
			(property "Value" "AP22615A_TSOT26"
				(at 30.48 -5.08 0)
				(effects
					(font
						(size 1.27 1.27)
						(thickness 0.15)
					)
					(justify left bottom)
				)
			)
			(property "Footprint" "antmicro-footprints:TSOT23-6"
				(at 30.48 -7.62 0)
				(effects
					(font
						(size 1.27 1.27)
						(thickness 0.15)
					)
					(justify left bottom)
					(hide yes)
				)
			)
			(property "Datasheet" "https://www.mouser.com/datasheet/2/115/DIOD_S_A0008958405_1-2543193.pdf"
				(at 30.48 -10.16 0)
				(effects
					(font
						(size 1.27 1.27)
						(thickness 0.15)
					)
					(justify left bottom)
					(hide yes)
				)
			)
			(property "Description" "Power Load Distribution Switch, High Side, Active High, 1 Output, 5.5 V, 3.6 A, 0.04 ohm, TSOT-26-6"
				(at 0 0 0)
				(effects
					(font
						(size 1.27 1.27)
					)
					(hide yes)
				)
			)
			(property "MPN" "AP22615AWU-7"
				(at 30.48 -12.7 0)
				(effects
					(font
						(size 1.27 1.27)
						(thickness 0.15)
					)
					(justify left bottom)
					(hide yes)
				)
			)
			(property "Manufacturer" "Diodes Incorporated"
				(at 30.48 -15.24 0)
				(effects
					(font
						(size 1.27 1.27)
						(thickness 0.15)
					)
					(justify left bottom)
					(hide yes)
				)
			)
			(property "Author" "Antmicro"
				(at 30.48 -17.78 0)
				(effects
					(font
						(size 1.27 1.27)
						(thickness 0.15)
					)
					(justify left bottom)
					(hide yes)
				)
			)
			(property "License" "Apache-2.0"
				(at 30.48 -20.32 0)
				(effects
					(font
						(size 1.27 1.27)
						(thickness 0.15)
					)
					(justify left bottom)
					(hide yes)
				)
			)
			(property "ki_keywords" "SMT, PMIC, IC, VOLTAGE"
				(at 0 0 0)
				(effects
					(font
						(size 1.27 1.27)
					)
					(hide yes)
				)
			)
			(symbol "AP22615A_TSOT26_1_1"
				(rectangle
					(start 2.54 2.54)
					(end 12.7 -7.62)
					(stroke
						(width 0.254)
						(type default)
					)
					(fill
						(type background)
					)
				)
				(pin power_in line
					(at 0 0 0)
					(length 2.54)
					(name "IN"
						(effects
							(font
								(size 1.27 1.27)
							)
						)
					)
					(number "6"
						(effects
							(font
								(size 1.27 1.27)
							)
						)
					)
				)
				(pin output line
					(at 0 -2.54 0)
					(length 2.54)
					(name "FLG"
						(effects
							(font
								(size 1.27 1.27)
							)
						)
					)
					(number "3"
						(effects
							(font
								(size 1.27 1.27)
							)
						)
					)
				)
				(pin input line
					(at 0 -5.08 0)
					(length 2.54)
					(name "EN"
						(effects
							(font
								(size 1.27 1.27)
							)
						)
					)
					(number "4"
						(effects
							(font
								(size 1.27 1.27)
							)
						)
					)
				)
				(pin power_out line
					(at 15.24 0 180)
					(length 2.54)
					(name "OUT"
						(effects
							(font
								(size 1.27 1.27)
							)
						)
					)
					(number "1"
						(effects
							(font
								(size 1.27 1.27)
							)
						)
					)
				)
				(pin passive line
					(at 15.24 -2.54 180)
					(length 2.54)
					(name "ISET"
						(effects
							(font
								(size 1.27 1.27)
							)
						)
					)
					(number "5"
						(effects
							(font
								(size 1.27 1.27)
							)
						)
					)
				)
				(pin power_in line
					(at 15.24 -5.08 180)
					(length 2.54)
					(name "GND"
						(effects
							(font
								(size 1.27 1.27)
							)
						)
					)
					(number "2"
						(effects
							(font
								(size 1.27 1.27)
							)
						)
					)
				)
			)
		)
	(symbol "antmicroPMICPowerDistributionSwitchesLoadDrivers:NCP451AFCT2G"
			(exclude_from_sim no)
			(in_bom yes)
			(on_board yes)
			(property "Reference" "U"
				(at 30.48 -2.54 0)
				(effects
					(font
						(size 1.27 1.27)
						(thickness 0.15)
					)
					(justify left bottom)
				)
			)
			(property "Value" "NCP451AFCT2G"
				(at 30.48 -5.08 0)
				(effects
					(font
						(size 1.27 1.27)
						(thickness 0.15)
					)
					(justify left bottom)
				)
			)
			(property "Footprint" "antmicro-footprints:Onsemi_WLCSP6_1.40x0.90"
				(at 30.48 -7.62 0)
				(effects
					(font
						(size 1.27 1.27)
						(thickness 0.15)
					)
					(justify left bottom)
					(hide yes)
				)
			)
			(property "Datasheet" "https://www.mouser.com/datasheet/2/308/NCP451_D-1812749.pdf"
				(at 30.48 -10.16 0)
				(effects
					(font
						(size 1.27 1.27)
						(thickness 0.15)
					)
					(justify left bottom)
					(hide yes)
				)
			)
			(property "Description" "Power Load Switch, High Side, Active High, 1 Output, 0.012 ohm On State, 5.5 V supp, 3 A, WLCSP-6"
				(at 0 0 0)
				(effects
					(font
						(size 1.27 1.27)
					)
					(hide yes)
				)
			)
			(property "MPN" "NCP451AFCT2G"
				(at 30.48 -12.7 0)
				(effects
					(font
						(size 1.27 1.27)
						(thickness 0.15)
					)
					(justify left bottom)
					(hide yes)
				)
			)
			(property "Manufacturer" "ON Semiconductor"
				(at 30.48 -15.24 0)
				(effects
					(font
						(size 1.27 1.27)
						(thickness 0.15)
					)
					(justify left bottom)
					(hide yes)
				)
			)
			(property "Author" "Antmicro"
				(at 30.48 -17.78 0)
				(effects
					(font
						(size 1.27 1.27)
						(thickness 0.15)
					)
					(justify left bottom)
					(hide yes)
				)
			)
			(property "License" "Apache-2.0"
				(at 30.48 -20.32 0)
				(effects
					(font
						(size 1.27 1.27)
						(thickness 0.15)
					)
					(justify left bottom)
					(hide yes)
				)
			)
			(property "ki_keywords" "IC"
				(at 0 0 0)
				(effects
					(font
						(size 1.27 1.27)
					)
					(hide yes)
				)
			)
			(symbol "NCP451AFCT2G_1_1"
				(rectangle
					(start 2.54 2.54)
					(end 12.7 -7.62)
					(stroke
						(width 0.254)
						(type default)
					)
					(fill
						(type background)
					)
				)
				(pin power_in line
					(at 0 0 0)
					(length 2.54)
					(name "IN"
						(effects
							(font
								(size 1.27 1.27)
							)
						)
					)
					(number "A2"
						(effects
							(font
								(size 1.27 1.27)
							)
						)
					)
				)
				(pin passive line
					(at 0 0 0)
					(length 2.54)
					(hide yes)
					(name "IN"
						(effects
							(font
								(size 1.27 1.27)
							)
						)
					)
					(number "B2"
						(effects
							(font
								(size 1.27 1.27)
							)
						)
					)
				)
				(pin input line
					(at 0 -5.08 0)
					(length 2.54)
					(name "EN"
						(effects
							(font
								(size 1.27 1.27)
							)
						)
					)
					(number "C2"
						(effects
							(font
								(size 1.27 1.27)
							)
						)
					)
				)
				(pin power_out line
					(at 15.24 0 180)
					(length 2.54)
					(name "OUT"
						(effects
							(font
								(size 1.27 1.27)
							)
						)
					)
					(number "A1"
						(effects
							(font
								(size 1.27 1.27)
							)
						)
					)
				)
				(pin passive line
					(at 15.24 0 180)
					(length 2.54)
					(hide yes)
					(name "OUT"
						(effects
							(font
								(size 1.27 1.27)
							)
						)
					)
					(number "B1"
						(effects
							(font
								(size 1.27 1.27)
							)
						)
					)
				)
				(pin power_in line
					(at 15.24 -5.08 180)
					(length 2.54)
					(name "GND"
						(effects
							(font
								(size 1.27 1.27)
							)
						)
					)
					(number "C1"
						(effects
							(font
								(size 1.27 1.27)
							)
						)
					)
				)
			)
		)
	(symbol "antmicroPMICPowerDistributionSwitchesLoadDrivers:REF3012AIDBZT"
			(exclude_from_sim no)
			(in_bom yes)
			(on_board yes)
			(property "Reference" "U"
				(at 33.02 -6.35 0)
				(effects
					(font
						(size 1.27 1.27)
						(thickness 0.15)
					)
					(justify left bottom)
				)
			)
			(property "Value" "REF3012AIDBZT"
				(at 33.02 -15.24 0)
				(effects
					(font
						(size 1.27 1.27)
						(thickness 0.15)
					)
					(justify left bottom)
					(hide yes)
				)
			)
			(property "Footprint" "antmicro-footprints:SOT-23-3"
				(at 33.02 -10.16 0)
				(effects
					(font
						(size 1.27 1.27)
						(thickness 0.15)
					)
					(justify left bottom)
					(hide yes)
				)
			)
			(property "Datasheet" "https://www.ti.com/lit/gpn/REF3012"
				(at 33.02 -12.7 0)
				(effects
					(font
						(size 1.27 1.27)
						(thickness 0.15)
					)
					(justify left bottom)
					(hide yes)
				)
			)
			(property "Description" "Voltage Reference, Low Power, Low Dropout, Series"
				(at 0 0 0)
				(effects
					(font
						(size 1.27 1.27)
					)
					(hide yes)
				)
			)
			(property "MPN" "REF3012AIDBZT"
				(at 33.02 -8.255 0)
				(effects
					(font
						(size 1.27 1.27)
						(thickness 0.15)
					)
					(justify left bottom)
				)
			)
			(property "Manufacturer" "Texas Instruments"
				(at 33.02 -17.78 0)
				(effects
					(font
						(size 1.27 1.27)
						(thickness 0.15)
					)
					(justify left bottom)
					(hide yes)
				)
			)
			(property "Author" "Antmicro"
				(at 33.02 -20.32 0)
				(effects
					(font
						(size 1.27 1.27)
						(thickness 0.15)
					)
					(justify left bottom)
					(hide yes)
				)
			)
			(property "License" "Apache-2.0"
				(at 33.02 -22.86 0)
				(effects
					(font
						(size 1.27 1.27)
						(thickness 0.15)
					)
					(justify left bottom)
					(hide yes)
				)
			)
			(property "ki_keywords" "SMT, PMIC, IC, POWER, SWITCH, DRIVER"
				(at 0 0 0)
				(effects
					(font
						(size 1.27 1.27)
					)
					(hide yes)
				)
			)
			(symbol "REF3012AIDBZT_1_1"
				(rectangle
					(start 2.54 1.27)
					(end 15.24 -5.08)
					(stroke
						(width 0.254)
						(type default)
					)
					(fill
						(type background)
					)
				)
				(pin power_in line
					(at 0 0 0)
					(length 2.54)
					(name "IN"
						(effects
							(font
								(size 1.27 1.27)
							)
						)
					)
					(number "1"
						(effects
							(font
								(size 1.27 1.27)
							)
						)
					)
				)
				(pin passive line
					(at 0 -3.81 0)
					(length 2.54)
					(name "GND"
						(effects
							(font
								(size 1.27 1.27)
							)
						)
					)
					(number "3"
						(effects
							(font
								(size 1.27 1.27)
							)
						)
					)
				)
				(pin output line
					(at 17.78 0 180)
					(length 2.54)
					(name "OUT"
						(effects
							(font
								(size 1.27 1.27)
							)
						)
					)
					(number "2"
						(effects
							(font
								(size 1.27 1.27)
							)
						)
					)
				)
			)
		)
	(symbol "antmicroPMICPowerDistributionSwitchesLoadDrivers:STUSB4500_QFN"
			(exclude_from_sim no)
			(in_bom yes)
			(on_board yes)
			(property "Reference" "U"
				(at 45.72 -2.54 0)
				(effects
					(font
						(size 1.27 1.27)
						(thickness 0.15)
					)
					(justify left bottom)
				)
			)
			(property "Value" "STUSB4500_QFN"
				(at 45.72 -7.62 0)
				(effects
					(font
						(size 1.27 1.27)
						(thickness 0.15)
					)
					(justify left bottom)
					(hide yes)
				)
			)
			(property "Footprint" "antmicro-footprints:QFN-24-1EP_4x4mm_P0.5_EP2.1x2.1mm"
				(at 45.72 -10.16 0)
				(effects
					(font
						(size 1.27 1.27)
						(thickness 0.15)
					)
					(justify left bottom)
					(hide yes)
				)
			)
			(property "Datasheet" "https://www.mouser.com/datasheet/2/389/dm00489312-1799262.pdf"
				(at 45.72 -12.7 0)
				(effects
					(font
						(size 1.27 1.27)
						(thickness 0.15)
					)
					(justify left bottom)
					(hide yes)
				)
			)
			(property "Description" "USB Controller USB 2.0 I2C Interface 24-QFN (4x4)"
				(at 0 0 0)
				(effects
					(font
						(size 1.27 1.27)
					)
					(hide yes)
				)
			)
			(property "MPN" "STUSB4500QTR"
				(at 45.72 -5.08 0)
				(effects
					(font
						(size 1.27 1.27)
						(thickness 0.15)
					)
					(justify left bottom)
				)
			)
			(property "Manufacturer" "STMicroelectronics"
				(at 45.72 -15.24 0)
				(effects
					(font
						(size 1.27 1.27)
						(thickness 0.15)
					)
					(justify left bottom)
					(hide yes)
				)
			)
			(property "Author" "Antmicro"
				(at 45.72 -17.78 0)
				(effects
					(font
						(size 1.27 1.27)
						(thickness 0.15)
					)
					(justify left bottom)
					(hide yes)
				)
			)
			(property "License" "Apache-2.0"
				(at 45.72 -20.32 0)
				(effects
					(font
						(size 1.27 1.27)
						(thickness 0.15)
					)
					(justify left bottom)
					(hide yes)
				)
			)
			(property "ki_keywords" "CONTROLLER"
				(at 0 0 0)
				(effects
					(font
						(size 1.27 1.27)
					)
					(hide yes)
				)
			)
			(symbol "STUSB4500_QFN_1_1"
				(rectangle
					(start 2.54 2.54)
					(end 27.94 -39.37)
					(stroke
						(width 0.254)
						(type default)
					)
					(fill
						(type background)
					)
				)
				(pin input line
					(at 0 0 0)
					(length 2.54)
					(name "VBUS_VS_DISCH"
						(effects
							(font
								(size 1.27 1.27)
							)
						)
					)
					(number "18"
						(effects
							(font
								(size 1.27 1.27)
							)
						)
					)
				)
				(pin output line
					(at 0 -2.54 0)
					(length 2.54)
					(name "VBUS_EN_SNK"
						(effects
							(font
								(size 1.27 1.27)
							)
						)
					)
					(number "16"
						(effects
							(font
								(size 1.27 1.27)
							)
						)
					)
				)
				(pin bidirectional line
					(at 0 -5.08 0)
					(length 2.54)
					(name "DISCH"
						(effects
							(font
								(size 1.27 1.27)
							)
						)
					)
					(number "9"
						(effects
							(font
								(size 1.27 1.27)
							)
						)
					)
				)
				(pin input line
					(at 0 -7.62 0)
					(length 2.54)
					(name "RESET"
						(effects
							(font
								(size 1.27 1.27)
							)
						)
					)
					(number "6"
						(effects
							(font
								(size 1.27 1.27)
							)
						)
					)
				)
				(pin input line
					(at 0 -12.7 0)
					(length 2.54)
					(name "SCL"
						(effects
							(font
								(size 1.27 1.27)
							)
						)
					)
					(number "7"
						(effects
							(font
								(size 1.27 1.27)
							)
						)
					)
				)
				(pin bidirectional line
					(at 0 -15.24 0)
					(length 2.54)
					(name "SDA"
						(effects
							(font
								(size 1.27 1.27)
							)
						)
					)
					(number "8"
						(effects
							(font
								(size 1.27 1.27)
							)
						)
					)
				)
				(pin bidirectional line
					(at 0 -20.32 0)
					(length 2.54)
					(name "CC1DB"
						(effects
							(font
								(size 1.27 1.27)
							)
						)
					)
					(number "1"
						(effects
							(font
								(size 1.27 1.27)
							)
						)
					)
				)
				(pin bidirectional line
					(at 0 -22.86 0)
					(length 2.54)
					(name "CC1"
						(effects
							(font
								(size 1.27 1.27)
							)
						)
					)
					(number "2"
						(effects
							(font
								(size 1.27 1.27)
							)
						)
					)
				)
				(pin bidirectional line
					(at 0 -25.4 0)
					(length 2.54)
					(name "CC2"
						(effects
							(font
								(size 1.27 1.27)
							)
						)
					)
					(number "4"
						(effects
							(font
								(size 1.27 1.27)
							)
						)
					)
				)
				(pin bidirectional line
					(at 0 -27.94 0)
					(length 2.54)
					(name "CC2DB"
						(effects
							(font
								(size 1.27 1.27)
							)
						)
					)
					(number "5"
						(effects
							(font
								(size 1.27 1.27)
							)
						)
					)
				)
				(pin input line
					(at 0 -33.02 0)
					(length 2.54)
					(name "ADDR0"
						(effects
							(font
								(size 1.27 1.27)
							)
						)
					)
					(number "12"
						(effects
							(font
								(size 1.27 1.27)
							)
						)
					)
				)
				(pin input line
					(at 0 -35.56 0)
					(length 2.54)
					(name "ADDR1"
						(effects
							(font
								(size 1.27 1.27)
							)
						)
					)
					(number "13"
						(effects
							(font
								(size 1.27 1.27)
							)
						)
					)
				)
				(pin no_connect line
					(at 2.54 -10.16 0)
					(length 2.54)
					(hide yes)
					(name "NC"
						(effects
							(font
								(size 1.27 1.27)
							)
						)
					)
					(number "3"
						(effects
							(font
								(size 1.27 1.27)
							)
						)
					)
				)
				(pin output line
					(at 30.48 0 180)
					(length 2.54)
					(name "~{ALERT}"
						(effects
							(font
								(size 1.27 1.27)
							)
						)
					)
					(number "19"
						(effects
							(font
								(size 1.27 1.27)
							)
						)
					)
				)
				(pin output line
					(at 30.48 -2.54 180)
					(length 2.54)
					(name "ATTACH"
						(effects
							(font
								(size 1.27 1.27)
							)
						)
					)
					(number "11"
						(effects
							(font
								(size 1.27 1.27)
							)
						)
					)
				)
				(pin output line
					(at 30.48 -5.08 180)
					(length 2.54)
					(name "GPIO"
						(effects
							(font
								(size 1.27 1.27)
							)
						)
					)
					(number "15"
						(effects
							(font
								(size 1.27 1.27)
							)
						)
					)
				)
				(pin output line
					(at 30.48 -7.62 180)
					(length 2.54)
					(name "A_B_SIDE"
						(effects
							(font
								(size 1.27 1.27)
							)
						)
					)
					(number "17"
						(effects
							(font
								(size 1.27 1.27)
							)
						)
					)
				)
				(pin output line
					(at 30.48 -12.7 180)
					(length 2.54)
					(name "POWER_OK2"
						(effects
							(font
								(size 1.27 1.27)
							)
						)
					)
					(number "20"
						(effects
							(font
								(size 1.27 1.27)
							)
						)
					)
				)
				(pin output line
					(at 30.48 -15.24 180)
					(length 2.54)
					(name "POWER_OK3"
						(effects
							(font
								(size 1.27 1.27)
							)
						)
					)
					(number "14"
						(effects
							(font
								(size 1.27 1.27)
							)
						)
					)
				)
				(pin power_in line
					(at 30.48 -20.32 180)
					(length 2.54)
					(name "VDD"
						(effects
							(font
								(size 1.27 1.27)
							)
						)
					)
					(number "24"
						(effects
							(font
								(size 1.27 1.27)
							)
						)
					)
				)
				(pin output line
					(at 30.48 -22.86 180)
					(length 2.54)
					(name "VREG_1V2"
						(effects
							(font
								(size 1.27 1.27)
							)
						)
					)
					(number "21"
						(effects
							(font
								(size 1.27 1.27)
							)
						)
					)
				)
				(pin output line
					(at 30.48 -25.4 180)
					(length 2.54)
					(name "VREG_2V7"
						(effects
							(font
								(size 1.27 1.27)
							)
						)
					)
					(number "23"
						(effects
							(font
								(size 1.27 1.27)
							)
						)
					)
				)
				(pin power_in line
					(at 30.48 -27.94 180)
					(length 2.54)
					(name "VSYS"
						(effects
							(font
								(size 1.27 1.27)
							)
						)
					)
					(number "22"
						(effects
							(font
								(size 1.27 1.27)
							)
						)
					)
				)
				(pin power_in line
					(at 30.48 -34.29 180)
					(length 2.54)
					(name "GND"
						(effects
							(font
								(size 1.27 1.27)
							)
						)
					)
					(number "10"
						(effects
							(font
								(size 1.27 1.27)
							)
						)
					)
				)
				(pin power_in line
					(at 30.48 -36.83 180)
					(length 2.54)
					(name "EP"
						(effects
							(font
								(size 1.27 1.27)
							)
						)
					)
					(number "25"
						(effects
							(font
								(size 1.27 1.27)
							)
						)
					)
				)
			)
		)
	(symbol "antmicroPMICPowerDistributionSwitchesLoadDrivers:TPS2372-3RGWR"
			(exclude_from_sim no)
			(in_bom yes)
			(on_board yes)
			(property "Reference" "U"
				(at 35.56 0 0)
				(effects
					(font
						(size 1.27 1.27)
						(thickness 0.15)
					)
					(justify left bottom)
				)
			)
			(property "Value" "TPS2372-3RGWR"
				(at 35.56 -2.54 0)
				(effects
					(font
						(size 1.27 1.27)
						(thickness 0.15)
					)
					(justify left bottom)
				)
			)
			(property "Footprint" "antmicro-footprints:VQFN-20_5x5x1mm_P0.65mm"
				(at 35.56 -5.08 0)
				(effects
					(font
						(size 1.27 1.27)
						(thickness 0.15)
					)
					(justify left bottom)
					(hide yes)
				)
			)
			(property "Datasheet" "https://www.ti.com/lit/ds/symlink/tps2372.pdf?ts=1679042478513&ref_url=https%253A%252F%252Fwww.google.com%252F"
				(at 35.56 -7.62 0)
				(effects
					(font
						(size 1.27 1.27)
						(thickness 0.15)
					)
					(justify left bottom)
					(hide yes)
				)
			)
			(property "Description" "PoE interface"
				(at 0 0 0)
				(effects
					(font
						(size 1.27 1.27)
					)
					(hide yes)
				)
			)
			(property "MPN" "TPS2372-3RGWR"
				(at 35.56 -10.16 0)
				(effects
					(font
						(size 1.27 1.27)
						(thickness 0.15)
					)
					(justify left bottom)
					(hide yes)
				)
			)
			(property "Manufacturer" "Texas Instruments"
				(at 35.56 -12.7 0)
				(effects
					(font
						(size 1.27 1.27)
						(thickness 0.15)
					)
					(justify left bottom)
					(hide yes)
				)
			)
			(property "Author" "Antmicro"
				(at 35.56 -15.24 0)
				(effects
					(font
						(size 1.27 1.27)
						(thickness 0.15)
					)
					(justify left bottom)
					(hide yes)
				)
			)
			(property "License" "Apache-2.0"
				(at 35.56 -17.78 0)
				(effects
					(font
						(size 1.27 1.27)
						(thickness 0.15)
					)
					(justify left bottom)
					(hide yes)
				)
			)
			(property "ki_keywords" "SMT, POE, IC, INTERFACE"
				(at 0 0 0)
				(effects
					(font
						(size 1.27 1.27)
					)
					(hide yes)
				)
			)
			(symbol "TPS2372-3RGWR_1_1"
				(rectangle
					(start 2.54 2.54)
					(end 19.05 -35.56)
					(stroke
						(width 0.254)
						(type default)
					)
					(fill
						(type background)
					)
				)
				(pin power_in line
					(at 0 0 0)
					(length 2.54)
					(name "VDD"
						(effects
							(font
								(size 1.27 1.27)
							)
						)
					)
					(number "1"
						(effects
							(font
								(size 1.27 1.27)
							)
						)
					)
				)
				(pin input line
					(at 0 -2.54 0)
					(length 2.54)
					(name "DEN"
						(effects
							(font
								(size 1.27 1.27)
							)
						)
					)
					(number "2"
						(effects
							(font
								(size 1.27 1.27)
							)
						)
					)
				)
				(pin input line
					(at 0 -7.62 0)
					(length 2.54)
					(name "CLSA"
						(effects
							(font
								(size 1.27 1.27)
							)
						)
					)
					(number "3"
						(effects
							(font
								(size 1.27 1.27)
							)
						)
					)
				)
				(pin input line
					(at 0 -10.16 0)
					(length 2.54)
					(name "CLSB"
						(effects
							(font
								(size 1.27 1.27)
							)
						)
					)
					(number "6"
						(effects
							(font
								(size 1.27 1.27)
							)
						)
					)
				)
				(pin power_in line
					(at 0 -15.24 0)
					(length 2.54)
					(name "VSSA"
						(effects
							(font
								(size 1.27 1.27)
							)
						)
					)
					(number "4"
						(effects
							(font
								(size 1.27 1.27)
							)
						)
					)
				)
				(pin power_in line
					(at 0 -17.78 0)
					(length 2.54)
					(name "VSSB"
						(effects
							(font
								(size 1.27 1.27)
							)
						)
					)
					(number "5"
						(effects
							(font
								(size 1.27 1.27)
							)
						)
					)
				)
				(pin power_in line
					(at 0 -20.32 0)
					(length 2.54)
					(name "PAD_VSSC"
						(effects
							(font
								(size 1.27 1.27)
							)
						)
					)
					(number "21"
						(effects
							(font
								(size 1.27 1.27)
							)
						)
					)
				)
				(pin input line
					(at 0 -22.86 0)
					(length 2.54)
					(name "AMPS_CTL"
						(effects
							(font
								(size 1.27 1.27)
							)
						)
					)
					(number "8"
						(effects
							(font
								(size 1.27 1.27)
							)
						)
					)
				)
				(pin input line
					(at 0 -25.4 0)
					(length 2.54)
					(name "REF"
						(effects
							(font
								(size 1.27 1.27)
							)
						)
					)
					(number "7"
						(effects
							(font
								(size 1.27 1.27)
							)
						)
					)
				)
				(pin input line
					(at 0 -27.94 0)
					(length 2.54)
					(name "MPS_DUTY"
						(effects
							(font
								(size 1.27 1.27)
							)
						)
					)
					(number "9"
						(effects
							(font
								(size 1.27 1.27)
							)
						)
					)
				)
				(pin input line
					(at 0 -33.02 0)
					(length 2.54)
					(name "~{AUTCLS}"
						(effects
							(font
								(size 1.27 1.27)
							)
						)
					)
					(number "10"
						(effects
							(font
								(size 1.27 1.27)
							)
						)
					)
				)
				(pin no_connect line
					(at 19.05 -10.16 180)
					(length 2.54)
					(hide yes)
					(name "NC"
						(effects
							(font
								(size 1.27 1.27)
							)
						)
					)
					(number "20"
						(effects
							(font
								(size 1.27 1.27)
							)
						)
					)
				)
				(pin no_connect line
					(at 19.05 -12.7 180)
					(length 2.54)
					(hide yes)
					(name "NC"
						(effects
							(font
								(size 1.27 1.27)
							)
						)
					)
					(number "15"
						(effects
							(font
								(size 1.27 1.27)
							)
						)
					)
				)
				(pin no_connect line
					(at 19.05 -15.24 180)
					(length 2.54)
					(hide yes)
					(name "NC"
						(effects
							(font
								(size 1.27 1.27)
							)
						)
					)
					(number "14"
						(effects
							(font
								(size 1.27 1.27)
							)
						)
					)
				)
				(pin output line
					(at 21.59 0 180)
					(length 2.54)
					(name "TPH"
						(effects
							(font
								(size 1.27 1.27)
							)
						)
					)
					(number "18"
						(effects
							(font
								(size 1.27 1.27)
							)
						)
					)
				)
				(pin output line
					(at 21.59 -2.54 180)
					(length 2.54)
					(name "TPL"
						(effects
							(font
								(size 1.27 1.27)
							)
						)
					)
					(number "17"
						(effects
							(font
								(size 1.27 1.27)
							)
						)
					)
				)
				(pin output line
					(at 21.59 -5.08 180)
					(length 2.54)
					(name "~{BT}"
						(effects
							(font
								(size 1.27 1.27)
							)
						)
					)
					(number "19"
						(effects
							(font
								(size 1.27 1.27)
							)
						)
					)
				)
				(pin output line
					(at 21.59 -20.32 180)
					(length 2.54)
					(name "PG"
						(effects
							(font
								(size 1.27 1.27)
							)
						)
					)
					(number "13"
						(effects
							(font
								(size 1.27 1.27)
							)
						)
					)
				)
				(pin output line
					(at 21.59 -25.4 180)
					(length 2.54)
					(name "IRSHDL_EN"
						(effects
							(font
								(size 1.27 1.27)
							)
						)
					)
					(number "16"
						(effects
							(font
								(size 1.27 1.27)
							)
						)
					)
				)
				(pin output line
					(at 21.59 -30.48 180)
					(length 2.54)
					(name "RTNA"
						(effects
							(font
								(size 1.27 1.27)
							)
						)
					)
					(number "11"
						(effects
							(font
								(size 1.27 1.27)
							)
						)
					)
				)
				(pin output line
					(at 21.59 -33.02 180)
					(length 2.54)
					(name "RTNB"
						(effects
							(font
								(size 1.27 1.27)
							)
						)
					)
					(number "12"
						(effects
							(font
								(size 1.27 1.27)
							)
						)
					)
				)
			)
		)
	(symbol "antmicroPMICPowerSequencers:LM3880"
			(exclude_from_sim no)
			(in_bom yes)
			(on_board yes)
			(property "Reference" "U"
				(at 25.4 -5.08 0)
				(effects
					(font
						(size 1.27 1.27)
						(thickness 0.15)
					)
					(justify left bottom)
				)
			)
			(property "Value" "LM3880"
				(at 25.4 -7.62 0)
				(effects
					(font
						(size 1.27 1.27)
						(thickness 0.15)
					)
					(justify left bottom)
				)
			)
			(property "Footprint" "antmicro-footprints:SOT-23-6"
				(at 25.4 -10.16 0)
				(effects
					(font
						(size 1.27 1.27)
						(thickness 0.15)
					)
					(justify left bottom)
					(hide yes)
				)
			)
			(property "Datasheet" "http://www.ti.com/lit/ds/symlink/lm3880.pdf"
				(at 25.4 -12.7 0)
				(effects
					(font
						(size 1.27 1.27)
						(thickness 0.15)
					)
					(justify left bottom)
					(hide yes)
				)
			)
			(property "Description" "Power sequencer"
				(at 0 0 0)
				(effects
					(font
						(size 1.27 1.27)
					)
					(hide yes)
				)
			)
			(property "Manufacturer" "Texas Instruments"
				(at 25.4 -15.24 0)
				(effects
					(font
						(size 1.27 1.27)
						(thickness 0.15)
					)
					(justify left bottom)
					(hide yes)
				)
			)
			(property "MPN" "LM3880MFX-1AA/NOPB"
				(at 25.4 -17.78 0)
				(effects
					(font
						(size 1.27 1.27)
						(thickness 0.15)
					)
					(justify left bottom)
					(hide yes)
				)
			)
			(property "Author" "Antmicro"
				(at 25.4 -20.32 0)
				(effects
					(font
						(size 1.27 1.27)
						(thickness 0.15)
					)
					(justify left bottom)
					(hide yes)
				)
			)
			(property "License" "Apache-2.0"
				(at 25.4 -22.86 0)
				(effects
					(font
						(size 1.27 1.27)
						(thickness 0.15)
					)
					(justify left bottom)
					(hide yes)
				)
			)
			(property "ki_keywords" "SMT, PMIC, IC, POWER, SEQUENCER"
				(at 0 0 0)
				(effects
					(font
						(size 1.27 1.27)
					)
					(hide yes)
				)
			)
			(property "ki_fp_filters" "SOT?23*"
				(at 0 0 0)
				(effects
					(font
						(size 1.27 1.27)
					)
					(hide yes)
				)
			)
			(symbol "LM3880_1_1"
				(rectangle
					(start -7.62 -2.54)
					(end 7.62 -12.7)
					(stroke
						(width 0.254)
						(type default)
					)
					(fill
						(type background)
					)
				)
				(pin input line
					(at -10.16 -7.62 0)
					(length 2.54)
					(name "EN"
						(effects
							(font
								(size 1.27 1.27)
							)
						)
					)
					(number "3"
						(effects
							(font
								(size 1.27 1.27)
							)
						)
					)
				)
				(pin power_in line
					(at 0 0 270)
					(length 2.54)
					(name "VCC"
						(effects
							(font
								(size 1.27 1.27)
							)
						)
					)
					(number "1"
						(effects
							(font
								(size 1.27 1.27)
							)
						)
					)
				)
				(pin power_in line
					(at 0 -15.24 90)
					(length 2.54)
					(name "GND"
						(effects
							(font
								(size 1.27 1.27)
							)
						)
					)
					(number "2"
						(effects
							(font
								(size 1.27 1.27)
							)
						)
					)
				)
				(pin open_collector line
					(at 10.16 -5.08 180)
					(length 2.54)
					(name "FLAG1"
						(effects
							(font
								(size 1.27 1.27)
							)
						)
					)
					(number "6"
						(effects
							(font
								(size 1.27 1.27)
							)
						)
					)
				)
				(pin open_collector line
					(at 10.16 -7.62 180)
					(length 2.54)
					(name "FLAG2"
						(effects
							(font
								(size 1.27 1.27)
							)
						)
					)
					(number "5"
						(effects
							(font
								(size 1.27 1.27)
							)
						)
					)
				)
				(pin open_collector line
					(at 10.16 -10.16 180)
					(length 2.54)
					(name "FLAG3"
						(effects
							(font
								(size 1.27 1.27)
							)
						)
					)
					(number "4"
						(effects
							(font
								(size 1.27 1.27)
							)
						)
					)
				)
			)
		)
	(symbol "antmicroPMICPowerSequencers:MAX16150A_SOT"
			(exclude_from_sim no)
			(in_bom yes)
			(on_board yes)
			(property "Reference" "U"
				(at 31.75 -3.81 0)
				(effects
					(font
						(size 1.27 1.27)
						(thickness 0.15)
					)
					(justify left bottom)
				)
			)
			(property "Value" "MAX16150A_SOT"
				(at 31.75 -6.35 0)
				(effects
					(font
						(size 1.27 1.27)
						(thickness 0.15)
					)
					(justify left bottom)
				)
			)
			(property "Footprint" "antmicro-footprints:SOT-23-6"
				(at 31.75 -8.89 0)
				(effects
					(font
						(size 1.27 1.27)
						(thickness 0.15)
					)
					(justify left bottom)
					(hide yes)
				)
			)
			(property "Datasheet" "https://datasheets.maximintegrated.com/en/ds/MAX16150.pdf"
				(at 31.75 -11.43 0)
				(effects
					(font
						(size 1.27 1.27)
						(thickness 0.15)
					)
					(justify left bottom)
					(hide yes)
				)
			)
			(property "Description" "Push Button On/Off Controller, Latched Output, 1.3 to 5.5 V Supply, 50 ms Debounce Time, SOT-23-6"
				(at 0 0 0)
				(effects
					(font
						(size 1.27 1.27)
					)
					(hide yes)
				)
			)
			(property "Manufacturer" "Maxim Integrated Products"
				(at 31.75 -13.97 0)
				(effects
					(font
						(size 1.27 1.27)
						(thickness 0.15)
					)
					(justify left bottom)
					(hide yes)
				)
			)
			(property "MPN" "MAX16150AUT+T"
				(at 31.75 -16.51 0)
				(effects
					(font
						(size 1.27 1.27)
						(thickness 0.15)
					)
					(justify left bottom)
					(hide yes)
				)
			)
			(property "License" "Apache-2.0"
				(at 31.75 -19.05 0)
				(effects
					(font
						(size 1.27 1.27)
						(thickness 0.15)
					)
					(justify left bottom)
					(hide yes)
				)
			)
			(property "Author" "Antmicro"
				(at 31.75 -21.59 0)
				(effects
					(font
						(size 1.27 1.27)
						(thickness 0.15)
					)
					(justify left bottom)
					(hide yes)
				)
			)
			(property "ki_keywords" "SMT, PMIC, IC, CONTROLLER, ESD"
				(at 0 0 0)
				(effects
					(font
						(size 1.27 1.27)
					)
					(hide yes)
				)
			)
			(symbol "MAX16150A_SOT_0_0"
				(text "CTRL"
					(at 8.89 -0.254 0)
					(effects
						(font
							(size 0.635 0.635)
						)
					)
				)
			)
			(symbol "MAX16150A_SOT_1_1"
				(rectangle
					(start 2.54 2.54)
					(end 15.24 -7.62)
					(stroke
						(width 0.254)
						(type default)
					)
					(fill
						(type background)
					)
				)
				(polyline
					(pts
						(xy 6.35 -3.429) (xy 7.112 -3.429)
					)
					(stroke
						(width 0.254)
						(type default)
					)
					(fill
						(type background)
					)
				)
				(polyline
					(pts
						(xy 7.112 -2.54) (xy 10.668 -2.54)
					)
					(stroke
						(width 0.254)
						(type default)
					)
					(fill
						(type background)
					)
				)
				(circle
					(center 7.366 -3.429)
					(radius 0.254)
					(stroke
						(width 0.254)
						(type default)
					)
					(fill
						(type outline)
					)
				)
				(polyline
					(pts
						(xy 7.874 -1.016) (xy 9.906 -1.016)
					)
					(stroke
						(width 0.254)
						(type default)
					)
					(fill
						(type background)
					)
				)
				(polyline
					(pts
						(xy 8.89 -2.54) (xy 8.89 -1.016)
					)
					(stroke
						(width 0.254)
						(type default)
					)
					(fill
						(type background)
					)
				)
				(circle
					(center 10.414 -3.429)
					(radius 0.254)
					(stroke
						(width 0.254)
						(type default)
					)
					(fill
						(type outline)
					)
				)
				(polyline
					(pts
						(xy 11.43 -3.429) (xy 10.668 -3.429)
					)
					(stroke
						(width 0.254)
						(type default)
					)
					(fill
						(type background)
					)
				)
				(pin power_in line
					(at 0 0 0)
					(length 2.54)
					(name "VCC"
						(effects
							(font
								(size 1.27 1.27)
							)
						)
					)
					(number "3"
						(effects
							(font
								(size 1.27 1.27)
							)
						)
					)
				)
				(pin input line
					(at 0 -2.54 0)
					(length 2.54)
					(name "~{CLR}"
						(effects
							(font
								(size 1.27 1.27)
							)
						)
					)
					(number "6"
						(effects
							(font
								(size 1.27 1.27)
							)
						)
					)
				)
				(pin input line
					(at 0 -5.08 0)
					(length 2.54)
					(name "~{PB_IN}"
						(effects
							(font
								(size 1.27 1.27)
							)
						)
					)
					(number "1"
						(effects
							(font
								(size 1.27 1.27)
							)
						)
					)
				)
				(pin output line
					(at 17.78 0 180)
					(length 2.54)
					(name "OUT"
						(effects
							(font
								(size 1.27 1.27)
							)
						)
					)
					(number "4"
						(effects
							(font
								(size 1.27 1.27)
							)
						)
					)
				)
				(pin output line
					(at 17.78 -2.54 180)
					(length 2.54)
					(name "~{INT}"
						(effects
							(font
								(size 1.27 1.27)
							)
						)
					)
					(number "5"
						(effects
							(font
								(size 1.27 1.27)
							)
						)
					)
				)
				(pin power_in line
					(at 17.78 -5.08 180)
					(length 2.54)
					(name "GND"
						(effects
							(font
								(size 1.27 1.27)
							)
						)
					)
					(number "2"
						(effects
							(font
								(size 1.27 1.27)
							)
						)
					)
				)
			)
		)
	(symbol "antmicroPMICVoltageRegulatorsDCDCSwitchingControllers:NCP51400MNTXG"
			(exclude_from_sim no)
			(in_bom yes)
			(on_board yes)
			(property "Reference" "U"
				(at 38.1 -3.81 0)
				(effects
					(font
						(size 1.27 1.27)
						(thickness 0.15)
					)
					(justify left bottom)
				)
			)
			(property "Value" "NCP51400MNTXG"
				(at 38.1 -6.35 0)
				(effects
					(font
						(size 1.27 1.27)
						(thickness 0.15)
					)
					(justify left bottom)
				)
			)
			(property "Footprint" "antmicro-footprints:DFN-10-1EP_3x3mm"
				(at 38.1 -8.89 0)
				(effects
					(font
						(size 1.27 1.27)
						(thickness 0.15)
					)
					(justify left bottom)
					(hide yes)
				)
			)
			(property "Datasheet" "https://www.mouser.com/datasheet/2/308/NCP51400_D-1812533.pdf"
				(at 38.1 -11.43 0)
				(effects
					(font
						(size 1.27 1.27)
						(thickness 0.15)
					)
					(justify left bottom)
					(hide yes)
				)
			)
			(property "Description" "Fixed LDO Voltage Regulator, 2.375V to 5.5V, 1.2 V Drop, 750 mV/3A out, DFN-10 Pins"
				(at 0 0 0)
				(effects
					(font
						(size 1.27 1.27)
					)
					(hide yes)
				)
			)
			(property "MPN" "NCP51400MNTXG"
				(at 38.1 -13.97 0)
				(effects
					(font
						(size 1.27 1.27)
						(thickness 0.15)
					)
					(justify left bottom)
					(hide yes)
				)
			)
			(property "Manufacturer" "ON Semiconductor"
				(at 38.1 -16.51 0)
				(effects
					(font
						(size 1.27 1.27)
						(thickness 0.15)
					)
					(justify left bottom)
					(hide yes)
				)
			)
			(property "Author" "Antmicro"
				(at 38.1 -19.05 0)
				(effects
					(font
						(size 1.27 1.27)
						(thickness 0.15)
					)
					(justify left bottom)
					(hide yes)
				)
			)
			(property "License" "Apache-2.0"
				(at 38.1 -21.59 0)
				(effects
					(font
						(size 1.27 1.27)
						(thickness 0.15)
					)
					(justify left bottom)
					(hide yes)
				)
			)
			(property "ki_keywords" "SMT, PMIC, IC, VOLTAGE, REGULATOR, SWITCHING, DC-DC"
				(at 0 0 0)
				(effects
					(font
						(size 1.27 1.27)
					)
					(hide yes)
				)
			)
			(property "ki_fp_filters" "DFN10_3X3_ONS DFN10_3X3_ONS-M DFN10_3X3_ONS-L"
				(at 0 0 0)
				(effects
					(font
						(size 1.27 1.27)
					)
					(hide yes)
				)
			)
			(symbol "NCP51400MNTXG_1_1"
				(rectangle
					(start 2.54 2.54)
					(end 21.59 -20.32)
					(stroke
						(width 0.254)
						(type default)
					)
					(fill
						(type background)
					)
				)
				(pin power_in line
					(at 0 0 0)
					(length 2.54)
					(name "VCC"
						(effects
							(font
								(size 1.27 1.27)
							)
						)
					)
					(number "10"
						(effects
							(font
								(size 1.27 1.27)
							)
						)
					)
				)
				(pin unspecified line
					(at 0 -6.35 0)
					(length 2.54)
					(name "EN"
						(effects
							(font
								(size 1.27 1.27)
							)
						)
					)
					(number "7"
						(effects
							(font
								(size 1.27 1.27)
							)
						)
					)
				)
				(pin unspecified line
					(at 0 -8.89 0)
					(length 2.54)
					(name "PVCC"
						(effects
							(font
								(size 1.27 1.27)
							)
						)
					)
					(number "2"
						(effects
							(font
								(size 1.27 1.27)
							)
						)
					)
				)
				(pin unspecified line
					(at 0 -17.78 0)
					(length 2.54)
					(name "VRI"
						(effects
							(font
								(size 1.27 1.27)
							)
						)
					)
					(number "1"
						(effects
							(font
								(size 1.27 1.27)
							)
						)
					)
				)
				(pin power_in line
					(at 10.16 -22.86 90)
					(length 2.54)
					(name "PGND"
						(effects
							(font
								(size 1.27 1.27)
							)
						)
					)
					(number "4"
						(effects
							(font
								(size 1.27 1.27)
							)
						)
					)
				)
				(pin power_in line
					(at 12.7 -22.86 90)
					(length 2.54)
					(name "GND"
						(effects
							(font
								(size 1.27 1.27)
							)
						)
					)
					(number "8"
						(effects
							(font
								(size 1.27 1.27)
							)
						)
					)
				)
				(pin unspecified line
					(at 15.24 -22.86 90)
					(length 2.54)
					(name "EPAD"
						(effects
							(font
								(size 1.27 1.27)
							)
						)
					)
					(number "11"
						(effects
							(font
								(size 1.27 1.27)
							)
						)
					)
				)
				(pin power_in line
					(at 24.13 0 180)
					(length 2.54)
					(name "PGOOD"
						(effects
							(font
								(size 1.27 1.27)
							)
						)
					)
					(number "9"
						(effects
							(font
								(size 1.27 1.27)
							)
						)
					)
				)
				(pin unspecified line
					(at 24.13 -3.81 180)
					(length 2.54)
					(name "VTT"
						(effects
							(font
								(size 1.27 1.27)
							)
						)
					)
					(number "3"
						(effects
							(font
								(size 1.27 1.27)
							)
						)
					)
				)
				(pin unspecified line
					(at 24.13 -6.35 180)
					(length 2.54)
					(name "VTTS"
						(effects
							(font
								(size 1.27 1.27)
							)
						)
					)
					(number "5"
						(effects
							(font
								(size 1.27 1.27)
							)
						)
					)
				)
				(pin unspecified line
					(at 24.13 -17.78 180)
					(length 2.54)
					(name "VRO"
						(effects
							(font
								(size 1.27 1.27)
							)
						)
					)
					(number "6"
						(effects
							(font
								(size 1.27 1.27)
							)
						)
					)
				)
			)
		)
	(symbol "antmicroPMICVoltageRegulatorsDCDCSwitchingRegulators:MP8869S"
			(exclude_from_sim no)
			(in_bom yes)
			(on_board yes)
			(property "Reference" "U"
				(at 25.4 -6.35 0)
				(effects
					(font
						(size 1.27 1.27)
						(thickness 0.15)
					)
					(justify left bottom)
				)
			)
			(property "Value" "MP8869S"
				(at 25.4 -8.89 0)
				(effects
					(font
						(size 1.27 1.27)
						(thickness 0.15)
					)
					(justify left bottom)
				)
			)
			(property "Footprint" "antmicro-footprints:MPS_QFN-14_MP8869S"
				(at 25.4 -11.43 0)
				(effects
					(font
						(size 1.27 1.27)
						(thickness 0.15)
					)
					(justify left bottom)
					(hide yes)
				)
			)
			(property "Datasheet" "https://www.mouser.com/datasheet/2/277/MP8869S-2946178.pdf"
				(at 25.4 -13.97 0)
				(effects
					(font
						(size 1.27 1.27)
						(thickness 0.15)
					)
					(justify left bottom)
					(hide yes)
				)
			)
			(property "Description" "DC-DC Switching Synchronous Buck Regulator, 2.85V-18V in, 600mV to 5.5V out, 12A, 500kHz, QFN-14"
				(at 0 0 0)
				(effects
					(font
						(size 1.27 1.27)
					)
					(hide yes)
				)
			)
			(property "MPN" "MP8869SGL-P"
				(at 25.4 -16.51 0)
				(effects
					(font
						(size 1.27 1.27)
						(thickness 0.15)
					)
					(justify left bottom)
					(hide yes)
				)
			)
			(property "Manufacturer" "Monolithic Power Systems"
				(at 25.4 -19.05 0)
				(effects
					(font
						(size 1.27 1.27)
						(thickness 0.15)
					)
					(justify left bottom)
					(hide yes)
				)
			)
			(property "Author" "Antmicro"
				(at 25.4 -21.59 0)
				(effects
					(font
						(size 1.27 1.27)
						(thickness 0.15)
					)
					(justify left bottom)
					(hide yes)
				)
			)
			(property "License" "Apache-2.0"
				(at 25.4 -24.13 0)
				(effects
					(font
						(size 1.27 1.27)
						(thickness 0.15)
					)
					(justify left bottom)
					(hide yes)
				)
			)
			(property "ki_keywords" "SMT, PMIC, IC, VOLTAGE, REGULATOR, SWITCHING, DC-DC"
				(at 0 0 0)
				(effects
					(font
						(size 1.27 1.27)
					)
					(hide yes)
				)
			)
			(property "ki_fp_filters" "QFN-14_MP8869S_MNP"
				(at 0 0 0)
				(effects
					(font
						(size 1.27 1.27)
					)
					(hide yes)
				)
			)
			(symbol "MP8869S_1_1"
				(rectangle
					(start -7.62 -2.54)
					(end 7.62 -30.48)
					(stroke
						(width 0.254)
						(type default)
					)
					(fill
						(type background)
					)
				)
				(pin power_in line
					(at -10.16 -5.08 0)
					(length 2.54)
					(name "VIN"
						(effects
							(font
								(size 1.27 1.27)
							)
						)
					)
					(number "9"
						(effects
							(font
								(size 1.27 1.27)
							)
						)
					)
				)
				(pin unspecified line
					(at -10.16 -10.16 0)
					(length 2.54)
					(name "EN"
						(effects
							(font
								(size 1.27 1.27)
							)
						)
					)
					(number "5"
						(effects
							(font
								(size 1.27 1.27)
							)
						)
					)
				)
				(pin power_out line
					(at -10.16 -12.7 0)
					(length 2.54)
					(name "VCC"
						(effects
							(font
								(size 1.27 1.27)
							)
						)
					)
					(number "13"
						(effects
							(font
								(size 1.27 1.27)
							)
						)
					)
				)
				(pin unspecified line
					(at -10.16 -19.05 0)
					(length 2.54)
					(name "PG"
						(effects
							(font
								(size 1.27 1.27)
							)
						)
					)
					(number "7"
						(effects
							(font
								(size 1.27 1.27)
							)
						)
					)
				)
				(pin unspecified line
					(at -10.16 -22.86 0)
					(length 2.54)
					(name "SDA"
						(effects
							(font
								(size 1.27 1.27)
							)
						)
					)
					(number "4"
						(effects
							(font
								(size 1.27 1.27)
							)
						)
					)
				)
				(pin unspecified line
					(at -10.16 -25.4 0)
					(length 2.54)
					(name "SCL"
						(effects
							(font
								(size 1.27 1.27)
							)
						)
					)
					(number "3"
						(effects
							(font
								(size 1.27 1.27)
							)
						)
					)
				)
				(pin unspecified line
					(at -10.16 -27.94 0)
					(length 2.54)
					(name "A0"
						(effects
							(font
								(size 1.27 1.27)
							)
						)
					)
					(number "6"
						(effects
							(font
								(size 1.27 1.27)
							)
						)
					)
				)
				(pin power_in line
					(at -1.27 -33.02 90)
					(length 2.54)
					(name "AGND"
						(effects
							(font
								(size 1.27 1.27)
							)
						)
					)
					(number "14"
						(effects
							(font
								(size 1.27 1.27)
							)
						)
					)
				)
				(pin unspecified line
					(at 0 0 270)
					(length 2.54)
					(name "BST"
						(effects
							(font
								(size 1.27 1.27)
							)
						)
					)
					(number "1"
						(effects
							(font
								(size 1.27 1.27)
							)
						)
					)
				)
				(pin power_in line
					(at 1.27 -33.02 90)
					(length 2.54)
					(name "PGND"
						(effects
							(font
								(size 1.27 1.27)
							)
						)
					)
					(number "8"
						(effects
							(font
								(size 1.27 1.27)
							)
						)
					)
				)
				(pin output line
					(at 10.16 -5.08 180)
					(length 2.54)
					(name "SW"
						(effects
							(font
								(size 1.27 1.27)
							)
						)
					)
					(number "2"
						(effects
							(font
								(size 1.27 1.27)
							)
						)
					)
				)
				(pin unspecified line
					(at 10.16 -12.7 180)
					(length 2.54)
					(name "VOUT"
						(effects
							(font
								(size 1.27 1.27)
							)
						)
					)
					(number "10"
						(effects
							(font
								(size 1.27 1.27)
							)
						)
					)
				)
				(pin unspecified line
					(at 10.16 -20.32 180)
					(length 2.54)
					(name "FB"
						(effects
							(font
								(size 1.27 1.27)
							)
						)
					)
					(number "11"
						(effects
							(font
								(size 1.27 1.27)
							)
						)
					)
				)
				(pin unspecified line
					(at 10.16 -27.94 180)
					(length 2.54)
					(name "SS"
						(effects
							(font
								(size 1.27 1.27)
							)
						)
					)
					(number "12"
						(effects
							(font
								(size 1.27 1.27)
							)
						)
					)
				)
			)
		)
	(symbol "antmicroPMICVoltageRegulatorsDCDCSwitchingRegulators:MPM54304GMN"
			(exclude_from_sim no)
			(in_bom yes)
			(on_board yes)
			(property "Reference" "U"
				(at 46.99 -2.54 0)
				(effects
					(font
						(size 1.27 1.27)
						(thickness 0.15)
					)
					(justify left bottom)
				)
			)
			(property "Value" "MPM54304GMN"
				(at 46.99 -5.08 0)
				(effects
					(font
						(size 1.27 1.27)
						(thickness 0.15)
					)
					(justify left bottom)
				)
			)
			(property "Footprint" "antmicro-footprints:LGA-33_7x7mm_P0.65mm"
				(at 46.99 -7.62 0)
				(effects
					(font
						(size 1.27 1.27)
						(thickness 0.15)
					)
					(justify left bottom)
					(hide yes)
				)
			)
			(property "Datasheet" "https://www.monolithicpower.com/en/documentview/productdocument/index/version/2/document_type/Datasheet/lang/en/sku/MPM54304/document_id/4982/"
				(at 46.99 -10.16 0)
				(effects
					(font
						(size 1.27 1.27)
						(thickness 0.15)
					)
					(justify left bottom)
					(hide yes)
				)
			)
			(property "Description" "DC-DC Switching Synchronous Step-Down Regulator, Multi Output, 4-16V in, 1V/3.3V, 4.2/3A out, LGA33"
				(at 0 0 0)
				(effects
					(font
						(size 1.27 1.27)
					)
					(hide yes)
				)
			)
			(property "MPN" "MPM54304GMN-0000"
				(at 46.99 -12.7 0)
				(effects
					(font
						(size 1.27 1.27)
						(thickness 0.15)
					)
					(justify left bottom)
					(hide yes)
				)
			)
			(property "Manufacturer" "Monolithic Power Systems"
				(at 46.99 -15.24 0)
				(effects
					(font
						(size 1.27 1.27)
						(thickness 0.15)
					)
					(justify left bottom)
					(hide yes)
				)
			)
			(property "Author" "Antmicro"
				(at 46.99 -17.78 0)
				(effects
					(font
						(size 1.27 1.27)
						(thickness 0.15)
					)
					(justify left bottom)
					(hide yes)
				)
			)
			(property "License" "Apache-2.0"
				(at 46.99 -20.32 0)
				(effects
					(font
						(size 1.27 1.27)
						(thickness 0.15)
					)
					(justify left bottom)
					(hide yes)
				)
			)
			(property "ki_keywords" "SMT, PMIC, IC, VOLTAGE, REGULATOR, SWITCHING, DC-DC"
				(at 0 0 0)
				(effects
					(font
						(size 1.27 1.27)
					)
					(hide yes)
				)
			)
			(property "ki_fp_filters" "CP_48_13_ADI CP_48_13_ADI-M CP_48_13_ADI-L"
				(at 0 0 0)
				(effects
					(font
						(size 1.27 1.27)
					)
					(hide yes)
				)
			)
			(symbol "MPM54304GMN_1_1"
				(rectangle
					(start 2.54 3.81)
					(end 2.54 3.81)
					(stroke
						(width 0.254)
						(type default)
					)
					(fill
						(type background)
					)
				)
				(rectangle
					(start 2.54 2.54)
					(end 25.4 -38.1)
					(stroke
						(width 0.254)
						(type default)
					)
					(fill
						(type background)
					)
				)
				(polyline
					(pts
						(xy 25.4 1.27) (xy 17.78 1.27) (xy 17.78 -8.89) (xy 25.4 -8.89)
					)
					(stroke
						(width 0.254)
						(type default)
					)
					(fill
						(type background)
					)
				)
				(polyline
					(pts
						(xy 25.4 -11.43) (xy 17.78 -11.43) (xy 17.78 -19.05) (xy 25.4 -19.05)
					)
					(stroke
						(width 0.254)
						(type default)
					)
					(fill
						(type background)
					)
				)
				(polyline
					(pts
						(xy 25.4 -21.59) (xy 17.78 -21.59) (xy 17.78 -29.21) (xy 25.4 -29.21)
					)
					(stroke
						(width 0.254)
						(type default)
					)
					(fill
						(type background)
					)
				)
				(polyline
					(pts
						(xy 25.4 -31.75) (xy 17.78 -31.75) (xy 17.78 -36.83) (xy 25.4 -36.83)
					)
					(stroke
						(width 0.254)
						(type default)
					)
					(fill
						(type background)
					)
				)
				(pin input line
					(at 0 0 0)
					(length 2.54)
					(name "VIN"
						(effects
							(font
								(size 1.27 1.27)
							)
						)
					)
					(number "28"
						(effects
							(font
								(size 1.27 1.27)
							)
						)
					)
				)
				(pin passive line
					(at 0 0 0)
					(length 2.54)
					(hide yes)
					(name "VIN"
						(effects
							(font
								(size 1.27 1.27)
							)
						)
					)
					(number "29"
						(effects
							(font
								(size 1.27 1.27)
							)
						)
					)
				)
				(pin input line
					(at 0 -2.54 0)
					(length 2.54)
					(name "VCC"
						(effects
							(font
								(size 1.27 1.27)
							)
						)
					)
					(number "25"
						(effects
							(font
								(size 1.27 1.27)
							)
						)
					)
				)
				(pin input line
					(at 0 -10.16 0)
					(length 2.54)
					(name "EN/SYNCI"
						(effects
							(font
								(size 1.27 1.27)
							)
						)
					)
					(number "19"
						(effects
							(font
								(size 1.27 1.27)
							)
						)
					)
				)
				(pin bidirectional line
					(at 0 -19.05 0)
					(length 2.54)
					(name "SDA"
						(effects
							(font
								(size 1.27 1.27)
							)
						)
					)
					(number "3"
						(effects
							(font
								(size 1.27 1.27)
							)
						)
					)
				)
				(pin input line
					(at 0 -21.59 0)
					(length 2.54)
					(name "SCL"
						(effects
							(font
								(size 1.27 1.27)
							)
						)
					)
					(number "4"
						(effects
							(font
								(size 1.27 1.27)
							)
						)
					)
				)
				(pin input line
					(at 0 -30.48 0)
					(length 2.54)
					(name "GPIO"
						(effects
							(font
								(size 1.27 1.27)
							)
						)
					)
					(number "26"
						(effects
							(font
								(size 1.27 1.27)
							)
						)
					)
				)
				(pin passive line
					(at 0 -35.56 0)
					(length 2.54)
					(name "GND"
						(effects
							(font
								(size 1.27 1.27)
							)
						)
					)
					(number "10"
						(effects
							(font
								(size 1.27 1.27)
							)
						)
					)
				)
				(pin passive line
					(at 0 -35.56 0)
					(length 2.54)
					(hide yes)
					(name "GND"
						(effects
							(font
								(size 1.27 1.27)
							)
						)
					)
					(number "13"
						(effects
							(font
								(size 1.27 1.27)
							)
						)
					)
				)
				(pin passive line
					(at 0 -35.56 0)
					(length 2.54)
					(hide yes)
					(name "GND"
						(effects
							(font
								(size 1.27 1.27)
							)
						)
					)
					(number "16"
						(effects
							(font
								(size 1.27 1.27)
							)
						)
					)
				)
				(pin passive line
					(at 0 -35.56 0)
					(length 2.54)
					(hide yes)
					(name "GND"
						(effects
							(font
								(size 1.27 1.27)
							)
						)
					)
					(number "2"
						(effects
							(font
								(size 1.27 1.27)
							)
						)
					)
				)
				(pin passive line
					(at 0 -35.56 0)
					(length 2.54)
					(hide yes)
					(name "GND"
						(effects
							(font
								(size 1.27 1.27)
							)
						)
					)
					(number "20"
						(effects
							(font
								(size 1.27 1.27)
							)
						)
					)
				)
				(pin passive line
					(at 0 -35.56 0)
					(length 2.54)
					(hide yes)
					(name "GND"
						(effects
							(font
								(size 1.27 1.27)
							)
						)
					)
					(number "21"
						(effects
							(font
								(size 1.27 1.27)
							)
						)
					)
				)
				(pin passive line
					(at 0 -35.56 0)
					(length 2.54)
					(hide yes)
					(name "GND"
						(effects
							(font
								(size 1.27 1.27)
							)
						)
					)
					(number "27"
						(effects
							(font
								(size 1.27 1.27)
							)
						)
					)
				)
				(pin passive line
					(at 0 -35.56 0)
					(length 2.54)
					(hide yes)
					(name "GND"
						(effects
							(font
								(size 1.27 1.27)
							)
						)
					)
					(number "33"
						(effects
							(font
								(size 1.27 1.27)
							)
						)
					)
				)
				(pin passive line
					(at 0 -35.56 0)
					(length 2.54)
					(hide yes)
					(name "GND"
						(effects
							(font
								(size 1.27 1.27)
							)
						)
					)
					(number "5"
						(effects
							(font
								(size 1.27 1.27)
							)
						)
					)
				)
				(pin passive line
					(at 0 -35.56 0)
					(length 2.54)
					(hide yes)
					(name "GND"
						(effects
							(font
								(size 1.27 1.27)
							)
						)
					)
					(number "7"
						(effects
							(font
								(size 1.27 1.27)
							)
						)
					)
				)
				(pin power_out line
					(at 27.94 0 180)
					(length 2.54)
					(name "VOUT1"
						(effects
							(font
								(size 1.27 1.27)
							)
						)
					)
					(number "14"
						(effects
							(font
								(size 1.27 1.27)
							)
						)
					)
				)
				(pin passive line
					(at 27.94 0 180)
					(length 2.54)
					(hide yes)
					(name "VOUT1"
						(effects
							(font
								(size 1.27 1.27)
							)
						)
					)
					(number "15"
						(effects
							(font
								(size 1.27 1.27)
							)
						)
					)
				)
				(pin power_out line
					(at 27.94 -2.54 180)
					(length 2.54)
					(name "SW1"
						(effects
							(font
								(size 1.27 1.27)
							)
						)
					)
					(number "12"
						(effects
							(font
								(size 1.27 1.27)
							)
						)
					)
				)
				(pin input line
					(at 27.94 -5.08 180)
					(length 2.54)
					(name "FB1"
						(effects
							(font
								(size 1.27 1.27)
							)
						)
					)
					(number "18"
						(effects
							(font
								(size 1.27 1.27)
							)
						)
					)
				)
				(pin power_out line
					(at 27.94 -7.62 180)
					(length 2.54)
					(name "SGND1"
						(effects
							(font
								(size 1.27 1.27)
							)
						)
					)
					(number "17"
						(effects
							(font
								(size 1.27 1.27)
							)
						)
					)
				)
				(pin power_out line
					(at 27.94 -12.7 180)
					(length 2.54)
					(name "VOUT2"
						(effects
							(font
								(size 1.27 1.27)
							)
						)
					)
					(number "8"
						(effects
							(font
								(size 1.27 1.27)
							)
						)
					)
				)
				(pin passive line
					(at 27.94 -12.7 180)
					(length 2.54)
					(hide yes)
					(name "VOUT2"
						(effects
							(font
								(size 1.27 1.27)
							)
						)
					)
					(number "9"
						(effects
							(font
								(size 1.27 1.27)
							)
						)
					)
				)
				(pin power_out line
					(at 27.94 -15.24 180)
					(length 2.54)
					(name "SW2"
						(effects
							(font
								(size 1.27 1.27)
							)
						)
					)
					(number "11"
						(effects
							(font
								(size 1.27 1.27)
							)
						)
					)
				)
				(pin input line
					(at 27.94 -17.78 180)
					(length 2.54)
					(name "FB2"
						(effects
							(font
								(size 1.27 1.27)
							)
						)
					)
					(number "6"
						(effects
							(font
								(size 1.27 1.27)
							)
						)
					)
				)
				(pin power_out line
					(at 27.94 -22.86 180)
					(length 2.54)
					(name "VOUT3"
						(effects
							(font
								(size 1.27 1.27)
							)
						)
					)
					(number "1"
						(effects
							(font
								(size 1.27 1.27)
							)
						)
					)
				)
				(pin passive line
					(at 27.94 -22.86 180)
					(length 2.54)
					(hide yes)
					(name "VOUT3"
						(effects
							(font
								(size 1.27 1.27)
							)
						)
					)
					(number "32"
						(effects
							(font
								(size 1.27 1.27)
							)
						)
					)
				)
				(pin input line
					(at 27.94 -25.4 180)
					(length 2.54)
					(name "FB3"
						(effects
							(font
								(size 1.27 1.27)
							)
						)
					)
					(number "31"
						(effects
							(font
								(size 1.27 1.27)
							)
						)
					)
				)
				(pin power_out line
					(at 27.94 -27.94 180)
					(length 2.54)
					(name "SGND2"
						(effects
							(font
								(size 1.27 1.27)
							)
						)
					)
					(number "30"
						(effects
							(font
								(size 1.27 1.27)
							)
						)
					)
				)
				(pin power_out line
					(at 27.94 -33.02 180)
					(length 2.54)
					(name "VOUT4"
						(effects
							(font
								(size 1.27 1.27)
							)
						)
					)
					(number "22"
						(effects
							(font
								(size 1.27 1.27)
							)
						)
					)
				)
				(pin passive line
					(at 27.94 -33.02 180)
					(length 2.54)
					(hide yes)
					(name "VOUT4"
						(effects
							(font
								(size 1.27 1.27)
							)
						)
					)
					(number "23"
						(effects
							(font
								(size 1.27 1.27)
							)
						)
					)
				)
				(pin input line
					(at 27.94 -35.56 180)
					(length 2.54)
					(name "FB4"
						(effects
							(font
								(size 1.27 1.27)
							)
						)
					)
					(number "24"
						(effects
							(font
								(size 1.27 1.27)
							)
						)
					)
				)
			)
		)
	(symbol "antmicroPMICVoltageRegulatorsLinear:NCP718BSN330T1G"
			(exclude_from_sim no)
			(in_bom yes)
			(on_board yes)
			(property "Reference" "U"
				(at 35.56 -3.81 0)
				(effects
					(font
						(size 1.27 1.27)
						(thickness 0.15)
					)
					(justify left bottom)
				)
			)
			(property "Value" "NCP718BSN330T1G"
				(at 35.56 -6.35 0)
				(effects
					(font
						(size 1.27 1.27)
						(thickness 0.15)
					)
					(justify left bottom)
				)
			)
			(property "Footprint" "antmicro-footprints:SOT-23-5"
				(at 35.56 -8.89 0)
				(effects
					(font
						(size 1.27 1.27)
						(thickness 0.15)
					)
					(justify left bottom)
					(hide yes)
				)
			)
			(property "Datasheet" "https://www.mouser.com/datasheet/2/308/NCP718_D-1224359.pdf"
				(at 35.56 -11.43 0)
				(effects
					(font
						(size 1.27 1.27)
						(thickness 0.15)
					)
					(justify left bottom)
					(hide yes)
				)
			)
			(property "Description" "Linear Voltage Regulator IC Positive Fixed 1 Output 300mA TSOT-23-5"
				(at 0 0 0)
				(effects
					(font
						(size 1.27 1.27)
					)
					(hide yes)
				)
			)
			(property "MPN" "NCP718BSN330T1G"
				(at 35.56 -13.97 0)
				(effects
					(font
						(size 1.27 1.27)
						(thickness 0.15)
					)
					(justify left bottom)
					(hide yes)
				)
			)
			(property "Manufacturer" "ON Semiconductor"
				(at 35.56 -16.51 0)
				(effects
					(font
						(size 1.27 1.27)
						(thickness 0.15)
					)
					(justify left bottom)
					(hide yes)
				)
			)
			(property "Author" "Antmicro"
				(at 35.56 -19.05 0)
				(effects
					(font
						(size 1.27 1.27)
						(thickness 0.15)
					)
					(justify left bottom)
					(hide yes)
				)
			)
			(property "License" "Apache-2.0"
				(at 35.56 -21.59 0)
				(effects
					(font
						(size 1.27 1.27)
						(thickness 0.15)
					)
					(justify left bottom)
					(hide yes)
				)
			)
			(property "ki_keywords" "SMT, PMIC, IC, LDO, VOLTAGE, REGULATOR"
				(at 0 0 0)
				(effects
					(font
						(size 1.27 1.27)
					)
					(hide yes)
				)
			)
			(symbol "NCP718BSN330T1G_1_1"
				(rectangle
					(start 2.54 2.54)
					(end 17.78 -5.08)
					(stroke
						(width 0.254)
						(type default)
					)
					(fill
						(type background)
					)
				)
				(pin passive line
					(at 0 0 0)
					(length 2.54)
					(name "VIN"
						(effects
							(font
								(size 1.27 1.27)
							)
						)
					)
					(number "1"
						(effects
							(font
								(size 1.27 1.27)
							)
						)
					)
				)
				(pin passive line
					(at 0 -2.54 0)
					(length 2.54)
					(name "EN"
						(effects
							(font
								(size 1.27 1.27)
							)
						)
					)
					(number "3"
						(effects
							(font
								(size 1.27 1.27)
							)
						)
					)
				)
				(pin no_connect line
					(at 10.16 -5.08 90)
					(length 2.54)
					(hide yes)
					(name "NC"
						(effects
							(font
								(size 1.27 1.27)
							)
						)
					)
					(number "4"
						(effects
							(font
								(size 1.27 1.27)
							)
						)
					)
				)
				(pin passive line
					(at 20.32 0 180)
					(length 2.54)
					(name "VOUT"
						(effects
							(font
								(size 1.27 1.27)
							)
						)
					)
					(number "5"
						(effects
							(font
								(size 1.27 1.27)
							)
						)
					)
				)
				(pin passive line
					(at 20.32 -2.54 180)
					(length 2.54)
					(name "GND"
						(effects
							(font
								(size 1.27 1.27)
							)
						)
					)
					(number "2"
						(effects
							(font
								(size 1.27 1.27)
							)
						)
					)
				)
			)
		)
	(symbol "antmicroPMICVoltageRegulatorsLinear:TPS7A20185PDQNR"
			(exclude_from_sim no)
			(in_bom yes)
			(on_board yes)
			(property "Reference" "U"
				(at 33.02 -2.54 0)
				(effects
					(font
						(size 1.27 1.27)
						(thickness 0.15)
					)
					(justify left bottom)
				)
			)
			(property "Value" "TPS7A20185PDQNR"
				(at 33.02 -5.08 0)
				(effects
					(font
						(size 1.27 1.27)
						(thickness 0.15)
					)
					(justify left bottom)
				)
			)
			(property "Footprint" "antmicro-footprints:XDFN4"
				(at 33.02 -7.62 0)
				(effects
					(font
						(size 1.27 1.27)
						(thickness 0.15)
					)
					(justify left bottom)
					(hide yes)
				)
			)
			(property "Datasheet" "https://www.ti.com/general/docs/suppproductinfo.tsp?distId=26&gotoUrl=https://www.ti.com/lit/gpn/tps7a20"
				(at 33.02 -10.16 0)
				(effects
					(font
						(size 1.27 1.27)
						(thickness 0.15)
					)
					(justify left bottom)
					(hide yes)
				)
			)
			(property "Description" "Linear voltage regulator"
				(at 0 0 0)
				(effects
					(font
						(size 1.27 1.27)
					)
					(hide yes)
				)
			)
			(property "MPN" "TPS7A20185PDQNR"
				(at 33.02 -12.7 0)
				(effects
					(font
						(size 1.27 1.27)
						(thickness 0.15)
					)
					(justify left bottom)
					(hide yes)
				)
			)
			(property "Manufacturer" "Texas Instruments"
				(at 33.02 -15.24 0)
				(effects
					(font
						(size 1.27 1.27)
						(thickness 0.15)
					)
					(justify left bottom)
					(hide yes)
				)
			)
			(property "Author" "Antmicro"
				(at 33.02 -17.78 0)
				(effects
					(font
						(size 1.27 1.27)
						(thickness 0.15)
					)
					(justify left bottom)
					(hide yes)
				)
			)
			(property "License" "Apache-2.0"
				(at 33.02 -20.32 0)
				(effects
					(font
						(size 1.27 1.27)
						(thickness 0.15)
					)
					(justify left bottom)
					(hide yes)
				)
			)
			(property "ki_keywords" "SMT, PMIC, IC, LDO, LINEAR, VOLTAGE, REGULATOR"
				(at 0 0 0)
				(effects
					(font
						(size 1.27 1.27)
					)
					(hide yes)
				)
			)
			(symbol "TPS7A20185PDQNR_1_1"
				(rectangle
					(start 2.54 2.54)
					(end 15.24 -10.16)
					(stroke
						(width 0.254)
						(type default)
					)
					(fill
						(type background)
					)
				)
				(pin input line
					(at 0 0 0)
					(length 2.54)
					(name "VIN"
						(effects
							(font
								(size 1.27 1.27)
							)
						)
					)
					(number "4"
						(effects
							(font
								(size 1.27 1.27)
							)
						)
					)
				)
				(pin input line
					(at 0 -5.08 0)
					(length 2.54)
					(name "EN"
						(effects
							(font
								(size 1.27 1.27)
							)
						)
					)
					(number "3"
						(effects
							(font
								(size 1.27 1.27)
							)
						)
					)
				)
				(pin power_in line
					(at 8.89 -12.7 90)
					(length 2.54)
					(name "GND"
						(effects
							(font
								(size 1.27 1.27)
							)
						)
					)
					(number "2"
						(effects
							(font
								(size 1.27 1.27)
							)
						)
					)
				)
				(pin power_out line
					(at 17.78 0 180)
					(length 2.54)
					(name "VOUT"
						(effects
							(font
								(size 1.27 1.27)
							)
						)
					)
					(number "1"
						(effects
							(font
								(size 1.27 1.27)
							)
						)
					)
				)
				(pin passive line
					(at 17.78 -5.08 180)
					(length 2.54)
					(name "EXP"
						(effects
							(font
								(size 1.27 1.27)
							)
						)
					)
					(number "5"
						(effects
							(font
								(size 1.27 1.27)
							)
						)
					)
				)
			)
		)
	(symbol "antmicroPMICVoltageRegulatorsLinear:XC6230H001ER-G"
			(exclude_from_sim no)
			(in_bom yes)
			(on_board yes)
			(property "Reference" "U"
				(at 30.48 -2.54 0)
				(effects
					(font
						(size 1.27 1.27)
						(thickness 0.15)
					)
					(justify left bottom)
				)
			)
			(property "Value" "XC6230H001ER-G"
				(at 30.48 -5.08 0)
				(effects
					(font
						(size 1.27 1.27)
						(thickness 0.15)
					)
					(justify left bottom)
				)
			)
			(property "Footprint" "antmicro-footprints:Torex_USP-6C"
				(at 30.48 -7.62 0)
				(effects
					(font
						(size 1.27 1.27)
						(thickness 0.15)
					)
					(justify left bottom)
					(hide yes)
				)
			)
			(property "Datasheet" "https://www.torexsemi.com/file/xc6230/XC6230.pdf"
				(at 30.48 -10.16 0)
				(effects
					(font
						(size 1.27 1.27)
						(thickness 0.15)
					)
					(justify left bottom)
					(hide yes)
				)
			)
			(property "Description" "LDO Voltage Regulator, Adjustable, 1.7 V to 6 V in, 350 mV Drop, 1.188-1.212 V/2 A out, USP-6C-6"
				(at 0 0 0)
				(effects
					(font
						(size 1.27 1.27)
					)
					(hide yes)
				)
			)
			(property "MPN" "XC6230H001ER-G"
				(at 30.48 -12.7 0)
				(effects
					(font
						(size 1.27 1.27)
						(thickness 0.15)
					)
					(justify left bottom)
					(hide yes)
				)
			)
			(property "Manufacturer" "Torex Semiconductor"
				(at 30.48 -15.24 0)
				(effects
					(font
						(size 1.27 1.27)
						(thickness 0.15)
					)
					(justify left bottom)
					(hide yes)
				)
			)
			(property "Author" "Antmicro"
				(at 30.48 -17.78 0)
				(effects
					(font
						(size 1.27 1.27)
						(thickness 0.15)
					)
					(justify left bottom)
					(hide yes)
				)
			)
			(property "License" "Apache-2.0"
				(at 30.48 -20.32 0)
				(effects
					(font
						(size 1.27 1.27)
						(thickness 0.15)
					)
					(justify left bottom)
					(hide yes)
				)
			)
			(property "ki_keywords" "SMT, PMIC, IC, LDO, LINEAR, VOLTAGE, REGULATOR"
				(at 0 0 0)
				(effects
					(font
						(size 1.27 1.27)
					)
					(hide yes)
				)
			)
			(symbol "XC6230H001ER-G_1_1"
				(rectangle
					(start 2.54 2.54)
					(end 12.7 -7.62)
					(stroke
						(width 0.254)
						(type default)
					)
					(fill
						(type background)
					)
				)
				(pin power_out line
					(at 0 0 0)
					(length 2.54)
					(name "IN"
						(effects
							(font
								(size 1.27 1.27)
							)
						)
					)
					(number "6"
						(effects
							(font
								(size 1.27 1.27)
							)
						)
					)
				)
				(pin input line
					(at 0 -2.54 0)
					(length 2.54)
					(name "EN"
						(effects
							(font
								(size 1.27 1.27)
							)
						)
					)
					(number "4"
						(effects
							(font
								(size 1.27 1.27)
							)
						)
					)
				)
				(pin output line
					(at 0 -5.08 0)
					(length 2.54)
					(name "ILIM"
						(effects
							(font
								(size 1.27 1.27)
							)
						)
					)
					(number "2"
						(effects
							(font
								(size 1.27 1.27)
							)
						)
					)
				)
				(pin power_out line
					(at 15.24 0 180)
					(length 2.54)
					(name "OUT"
						(effects
							(font
								(size 1.27 1.27)
							)
						)
					)
					(number "1"
						(effects
							(font
								(size 1.27 1.27)
							)
						)
					)
				)
				(pin open_collector line
					(at 15.24 -2.54 180)
					(length 2.54)
					(name "FB"
						(effects
							(font
								(size 1.27 1.27)
							)
						)
					)
					(number "3"
						(effects
							(font
								(size 1.27 1.27)
							)
						)
					)
				)
				(pin power_in line
					(at 15.24 -5.08 180)
					(length 2.54)
					(name "GND"
						(effects
							(font
								(size 1.27 1.27)
							)
						)
					)
					(number "5"
						(effects
							(font
								(size 1.27 1.27)
							)
						)
					)
				)
				(pin passive line
					(at 15.24 -5.08 180)
					(length 2.54)
					(hide yes)
					(name "EP"
						(effects
							(font
								(size 1.27 1.27)
							)
						)
					)
					(number "7"
						(effects
							(font
								(size 1.27 1.27)
							)
						)
					)
				)
			)
		)
	(symbol "antmicroPushbuttonSwitches:SW_KMR211NGLFS_SMD"
			(pin_names
				(hide yes)
			)
			(exclude_from_sim no)
			(in_bom yes)
			(on_board yes)
			(property "Reference" "SW"
				(at 25.4 -2.54 0)
				(effects
					(font
						(size 1.27 1.27)
						(thickness 0.15)
					)
					(justify left bottom)
				)
			)
			(property "Value" "SW_KMR211NGLFS_SMD"
				(at 25.4 -7.62 0)
				(effects
					(font
						(size 1.27 1.27)
						(thickness 0.15)
					)
					(justify left bottom)
					(hide yes)
				)
			)
			(property "Footprint" "antmicro-footprints:SW_KMR211NGLFS_SMD"
				(at 25.4 -10.16 0)
				(effects
					(font
						(size 1.27 1.27)
						(thickness 0.15)
					)
					(justify left bottom)
					(hide yes)
				)
			)
			(property "Datasheet" "http://www.farnell.com/datasheets/2631211.pdf"
				(at 25.4 -12.7 0)
				(effects
					(font
						(size 1.27 1.27)
						(thickness 0.15)
					)
					(justify left bottom)
					(hide yes)
				)
			)
			(property "Description" "Tactile Switch, KMR 2 Series, Top Actuated, Surface Mount, Oval Button, 120 gf, 50mA at 32VDC"
				(at 0 0 0)
				(effects
					(font
						(size 1.27 1.27)
					)
					(hide yes)
				)
			)
			(property "MPN" "KMR211NGLFS"
				(at 25.4 -5.08 0)
				(effects
					(font
						(size 1.27 1.27)
						(thickness 0.15)
					)
					(justify left bottom)
				)
			)
			(property "Manufacturer" "C&K"
				(at 25.4 -15.24 0)
				(effects
					(font
						(size 1.27 1.27)
						(thickness 0.15)
					)
					(justify left bottom)
					(hide yes)
				)
			)
			(property "Author" "Antmicro"
				(at 25.4 -17.78 0)
				(effects
					(font
						(size 1.27 1.27)
						(thickness 0.15)
					)
					(justify left bottom)
					(hide yes)
				)
			)
			(property "License" "Apache-2.0"
				(at 25.4 -20.32 0)
				(effects
					(font
						(size 1.27 1.27)
						(thickness 0.15)
					)
					(justify left bottom)
					(hide yes)
				)
			)
			(property "ki_keywords" "VERTICAL, SMT, SWITCH, MECHANICAL, TACTILE"
				(at 0 0 0)
				(effects
					(font
						(size 1.27 1.27)
					)
					(hide yes)
				)
			)
			(symbol "SW_KMR211NGLFS_SMD_1_1"
				(polyline
					(pts
						(xy 2.54 0) (xy 3.302 0)
					)
					(stroke
						(width 0.254)
						(type default)
					)
					(fill
						(type none)
					)
				)
				(polyline
					(pts
						(xy 2.54 -2.54) (xy 3.302 -2.54)
					)
					(stroke
						(width 0.254)
						(type default)
					)
					(fill
						(type none)
					)
				)
				(polyline
					(pts
						(xy 3.302 1.27) (xy 6.858 1.27)
					)
					(stroke
						(width 0.254)
						(type default)
					)
					(fill
						(type none)
					)
				)
				(circle
					(center 3.556 0)
					(radius 0.254)
					(stroke
						(width 0.254)
						(type default)
					)
					(fill
						(type none)
					)
				)
				(polyline
					(pts
						(xy 3.556 -0.3048) (xy 3.556 -2.1844)
					)
					(stroke
						(width 0.254)
						(type default)
					)
					(fill
						(type none)
					)
				)
				(circle
					(center 3.556 -2.54)
					(radius 0.254)
					(stroke
						(width 0.254)
						(type default)
					)
					(fill
						(type none)
					)
				)
				(polyline
					(pts
						(xy 4.064 2.794) (xy 6.096 2.794)
					)
					(stroke
						(width 0.254)
						(type default)
					)
					(fill
						(type none)
					)
				)
				(polyline
					(pts
						(xy 5.08 1.27) (xy 5.08 2.794)
					)
					(stroke
						(width 0.254)
						(type default)
					)
					(fill
						(type none)
					)
				)
				(circle
					(center 6.604 0)
					(radius 0.254)
					(stroke
						(width 0.254)
						(type default)
					)
					(fill
						(type none)
					)
				)
				(polyline
					(pts
						(xy 6.604 -0.254) (xy 6.604 -2.1844)
					)
					(stroke
						(width 0.254)
						(type default)
					)
					(fill
						(type none)
					)
				)
				(circle
					(center 6.604 -2.54)
					(radius 0.254)
					(stroke
						(width 0.254)
						(type default)
					)
					(fill
						(type none)
					)
				)
				(polyline
					(pts
						(xy 7.62 0) (xy 6.858 0)
					)
					(stroke
						(width 0.254)
						(type default)
					)
					(fill
						(type none)
					)
				)
				(polyline
					(pts
						(xy 7.62 -2.54) (xy 6.858 -2.54)
					)
					(stroke
						(width 0.254)
						(type default)
					)
					(fill
						(type none)
					)
				)
				(pin passive line
					(at 0 0 0)
					(length 2.54)
					(name "1"
						(effects
							(font
								(size 1.27 1.27)
							)
						)
					)
					(number "1"
						(effects
							(font
								(size 1.27 1.27)
							)
						)
					)
				)
				(pin passive line
					(at 0 -2.54 0)
					(length 2.54)
					(name "2"
						(effects
							(font
								(size 1.27 1.27)
							)
						)
					)
					(number "2"
						(effects
							(font
								(size 1.27 1.27)
							)
						)
					)
				)
				(pin passive line
					(at 10.16 0 180)
					(length 2.54)
					(name "3"
						(effects
							(font
								(size 1.27 1.27)
							)
						)
					)
					(number "3"
						(effects
							(font
								(size 1.27 1.27)
							)
						)
					)
				)
				(pin passive line
					(at 10.16 -2.54 180)
					(length 2.54)
					(name "4"
						(effects
							(font
								(size 1.27 1.27)
							)
						)
					)
					(number "4"
						(effects
							(font
								(size 1.27 1.27)
							)
						)
					)
				)
			)
		)
	(symbol "antmicroResistorNetworksArrays:4x10k_0201_array"
			(pin_names
				(hide yes)
			)
			(exclude_from_sim no)
			(in_bom yes)
			(on_board yes)
			(property "Reference" "R"
				(at 26.67 -5.08 0)
				(effects
					(font
						(size 1.27 1.27)
						(thickness 0.15)
					)
					(justify left bottom)
				)
			)
			(property "Value" "4x10k_0201_array"
				(at 26.67 -7.62 0)
				(effects
					(font
						(size 1.27 1.27)
						(thickness 0.15)
					)
					(justify left bottom)
					(hide yes)
				)
			)
			(property "Footprint" "antmicro-footprints:R_Array_4x0201_Panasonic_EXB18V"
				(at 26.67 -12.7 0)
				(effects
					(font
						(size 1.27 1.27)
						(thickness 0.15)
					)
					(justify left bottom)
					(hide yes)
				)
			)
			(property "Datasheet" "http://industrial.panasonic.com/cdbs/www-data/pdf/AOC0000/AOC0000C14.pdf"
				(at 26.67 -15.24 0)
				(effects
					(font
						(size 1.27 1.27)
						(thickness 0.15)
					)
					(justify left bottom)
					(hide yes)
				)
			)
			(property "Description" "Fixed Network Resistor, 10 kohm, Isolated, 4 Resistors, 0502 [1406 Metric], Flat, ± 5%"
				(at 0 0 0)
				(effects
					(font
						(size 1.27 1.27)
					)
					(hide yes)
				)
			)
			(property "MPN" "EXB-18V103JX"
				(at 26.67 -17.78 0)
				(effects
					(font
						(size 1.27 1.27)
						(thickness 0.15)
					)
					(justify left bottom)
					(hide yes)
				)
			)
			(property "Manufacturer" "Panasonic"
				(at 26.67 -20.32 0)
				(effects
					(font
						(size 1.27 1.27)
						(thickness 0.15)
					)
					(justify left bottom)
					(hide yes)
				)
			)
			(property "Val" "4x10k_0201"
				(at 26.67 -10.16 0)
				(effects
					(font
						(size 1.27 1.27)
						(thickness 0.15)
					)
					(justify left bottom)
				)
			)
			(property "Author" "Antmicro"
				(at 26.67 -22.86 0)
				(effects
					(font
						(size 1.27 1.27)
						(thickness 0.15)
					)
					(justify left bottom)
					(hide yes)
				)
			)
			(property "License" "Apache-2.0"
				(at 26.67 -25.4 0)
				(effects
					(font
						(size 1.27 1.27)
						(thickness 0.15)
					)
					(justify left bottom)
					(hide yes)
				)
			)
			(property "ki_keywords" "0201, SMT, RESISTOR, PASSIVE, ARRAY"
				(at 0 0 0)
				(effects
					(font
						(size 1.27 1.27)
					)
					(hide yes)
				)
			)
			(symbol "4x10k_0201_array_0_1"
				(polyline
					(pts
						(xy 2.54 0) (xy 3.175 0)
					)
					(stroke
						(width 0)
						(type default)
					)
					(fill
						(type none)
					)
				)
				(polyline
					(pts
						(xy 2.54 -2.54) (xy 3.175 -2.54)
					)
					(stroke
						(width 0)
						(type default)
					)
					(fill
						(type none)
					)
				)
				(polyline
					(pts
						(xy 2.54 -5.08) (xy 3.175 -5.08)
					)
					(stroke
						(width 0)
						(type default)
					)
					(fill
						(type none)
					)
				)
				(polyline
					(pts
						(xy 2.54 -7.62) (xy 3.175 -7.62)
					)
					(stroke
						(width 0)
						(type default)
					)
					(fill
						(type none)
					)
				)
				(rectangle
					(start 2.667 1.27)
					(end 7.493 -8.89)
					(stroke
						(width 0.254)
						(type default)
					)
					(fill
						(type background)
					)
				)
				(rectangle
					(start 6.985 0.635)
					(end 3.175 -0.635)
					(stroke
						(width 0.254)
						(type default)
					)
					(fill
						(type none)
					)
				)
				(polyline
					(pts
						(xy 6.985 0) (xy 7.62 0)
					)
					(stroke
						(width 0)
						(type default)
					)
					(fill
						(type none)
					)
				)
				(rectangle
					(start 6.985 -1.905)
					(end 3.175 -3.175)
					(stroke
						(width 0.254)
						(type default)
					)
					(fill
						(type none)
					)
				)
				(polyline
					(pts
						(xy 6.985 -2.54) (xy 7.62 -2.54)
					)
					(stroke
						(width 0)
						(type default)
					)
					(fill
						(type none)
					)
				)
				(rectangle
					(start 6.985 -4.445)
					(end 3.175 -5.715)
					(stroke
						(width 0.254)
						(type default)
					)
					(fill
						(type none)
					)
				)
				(polyline
					(pts
						(xy 6.985 -5.08) (xy 7.62 -5.08)
					)
					(stroke
						(width 0)
						(type default)
					)
					(fill
						(type none)
					)
				)
				(rectangle
					(start 6.985 -6.985)
					(end 3.175 -8.255)
					(stroke
						(width 0.254)
						(type default)
					)
					(fill
						(type none)
					)
				)
				(polyline
					(pts
						(xy 6.985 -7.62) (xy 7.62 -7.62)
					)
					(stroke
						(width 0)
						(type default)
					)
					(fill
						(type none)
					)
				)
			)
			(symbol "4x10k_0201_array_1_1"
				(pin passive line
					(at 0 0 0)
					(length 2.54)
					(name "R1.1"
						(effects
							(font
								(size 1.27 1.27)
							)
						)
					)
					(number "1"
						(effects
							(font
								(size 1.27 1.27)
							)
						)
					)
				)
				(pin passive line
					(at 0 -2.54 0)
					(length 2.54)
					(name "R2.1"
						(effects
							(font
								(size 1.27 1.27)
							)
						)
					)
					(number "2"
						(effects
							(font
								(size 1.27 1.27)
							)
						)
					)
				)
				(pin passive line
					(at 0 -5.08 0)
					(length 2.54)
					(name "R3.1"
						(effects
							(font
								(size 1.27 1.27)
							)
						)
					)
					(number "3"
						(effects
							(font
								(size 1.27 1.27)
							)
						)
					)
				)
				(pin passive line
					(at 0 -7.62 0)
					(length 2.54)
					(name "R4.1"
						(effects
							(font
								(size 1.27 1.27)
							)
						)
					)
					(number "4"
						(effects
							(font
								(size 1.27 1.27)
							)
						)
					)
				)
				(pin passive line
					(at 10.16 0 180)
					(length 2.54)
					(name "R1.2"
						(effects
							(font
								(size 1.27 1.27)
							)
						)
					)
					(number "8"
						(effects
							(font
								(size 1.27 1.27)
							)
						)
					)
				)
				(pin passive line
					(at 10.16 -2.54 180)
					(length 2.54)
					(name "R2.2"
						(effects
							(font
								(size 1.27 1.27)
							)
						)
					)
					(number "7"
						(effects
							(font
								(size 1.27 1.27)
							)
						)
					)
				)
				(pin passive line
					(at 10.16 -5.08 180)
					(length 2.54)
					(name "R3.2"
						(effects
							(font
								(size 1.27 1.27)
							)
						)
					)
					(number "6"
						(effects
							(font
								(size 1.27 1.27)
							)
						)
					)
				)
				(pin passive line
					(at 10.16 -7.62 180)
					(length 2.54)
					(name "R4.2"
						(effects
							(font
								(size 1.27 1.27)
							)
						)
					)
					(number "5"
						(effects
							(font
								(size 1.27 1.27)
							)
						)
					)
				)
			)
		)
	(symbol "antmicroResistorNetworksArrays:4x39R_0201_array"
			(pin_names
				(hide yes)
			)
			(exclude_from_sim no)
			(in_bom yes)
			(on_board yes)
			(property "Reference" "R"
				(at 26.67 -3.175 0)
				(effects
					(font
						(size 1.27 1.27)
						(thickness 0.15)
					)
					(justify left bottom)
				)
			)
			(property "Value" "4x39R_0201_array"
				(at 26.67 -5.715 0)
				(effects
					(font
						(size 1.27 1.27)
						(thickness 0.15)
					)
					(justify left bottom)
					(hide yes)
				)
			)
			(property "Footprint" "antmicro-footprints:R_Array_4x0201_Panasonic_EXB18V"
				(at 26.67 -10.795 0)
				(effects
					(font
						(size 1.27 1.27)
						(thickness 0.15)
					)
					(justify left bottom)
					(hide yes)
				)
			)
			(property "Datasheet" "https://eu.mouser.com/datasheet/2/315/AOC0000C14-1108062.pdf"
				(at 26.67 -13.335 0)
				(effects
					(font
						(size 1.27 1.27)
						(thickness 0.15)
					)
					(justify left bottom)
					(hide yes)
				)
			)
			(property "Description" "Fixed Network Resistor, 39 ohm, Isolated, 4 Resistors, 0502 [1406 Metric], Flat, ± 5%"
				(at 0 0 0)
				(effects
					(font
						(size 1.27 1.27)
					)
					(hide yes)
				)
			)
			(property "MPN" "EXB-18V390JX"
				(at 26.67 -15.875 0)
				(effects
					(font
						(size 1.27 1.27)
						(thickness 0.15)
					)
					(justify left bottom)
					(hide yes)
				)
			)
			(property "Manufacturer" "Panasonic"
				(at 26.67 -18.415 0)
				(effects
					(font
						(size 1.27 1.27)
						(thickness 0.15)
					)
					(justify left bottom)
					(hide yes)
				)
			)
			(property "Author" "Antmicro"
				(at 26.67 -20.955 0)
				(effects
					(font
						(size 1.27 1.27)
						(thickness 0.15)
					)
					(justify left bottom)
					(hide yes)
				)
			)
			(property "License" "Apache-2.0"
				(at 26.67 -23.495 0)
				(effects
					(font
						(size 1.27 1.27)
						(thickness 0.15)
					)
					(justify left bottom)
					(hide yes)
				)
			)
			(property "Val" "4x39R_0201"
				(at 26.67 -8.255 0)
				(effects
					(font
						(size 1.27 1.27)
					)
					(justify left bottom)
				)
			)
			(property "ki_keywords" "0201, SMT, RESISTOR, PASSIVE, ARRAY"
				(at 0 0 0)
				(effects
					(font
						(size 1.27 1.27)
					)
					(hide yes)
				)
			)
			(symbol "4x39R_0201_array_0_1"
				(polyline
					(pts
						(xy 2.54 0) (xy 3.175 0)
					)
					(stroke
						(width 0)
						(type default)
					)
					(fill
						(type none)
					)
				)
				(polyline
					(pts
						(xy 2.54 -2.54) (xy 3.175 -2.54)
					)
					(stroke
						(width 0)
						(type default)
					)
					(fill
						(type none)
					)
				)
				(polyline
					(pts
						(xy 2.54 -5.08) (xy 3.175 -5.08)
					)
					(stroke
						(width 0)
						(type default)
					)
					(fill
						(type none)
					)
				)
				(polyline
					(pts
						(xy 2.54 -7.62) (xy 3.175 -7.62)
					)
					(stroke
						(width 0)
						(type default)
					)
					(fill
						(type none)
					)
				)
				(rectangle
					(start 2.667 1.27)
					(end 7.493 -8.89)
					(stroke
						(width 0.254)
						(type default)
					)
					(fill
						(type background)
					)
				)
				(rectangle
					(start 6.985 0.635)
					(end 3.175 -0.635)
					(stroke
						(width 0.254)
						(type default)
					)
					(fill
						(type none)
					)
				)
				(polyline
					(pts
						(xy 6.985 0) (xy 7.62 0)
					)
					(stroke
						(width 0)
						(type default)
					)
					(fill
						(type none)
					)
				)
				(rectangle
					(start 6.985 -1.905)
					(end 3.175 -3.175)
					(stroke
						(width 0.254)
						(type default)
					)
					(fill
						(type none)
					)
				)
				(polyline
					(pts
						(xy 6.985 -2.54) (xy 7.62 -2.54)
					)
					(stroke
						(width 0)
						(type default)
					)
					(fill
						(type none)
					)
				)
				(rectangle
					(start 6.985 -4.445)
					(end 3.175 -5.715)
					(stroke
						(width 0.254)
						(type default)
					)
					(fill
						(type none)
					)
				)
				(polyline
					(pts
						(xy 6.985 -5.08) (xy 7.62 -5.08)
					)
					(stroke
						(width 0)
						(type default)
					)
					(fill
						(type none)
					)
				)
				(rectangle
					(start 6.985 -6.985)
					(end 3.175 -8.255)
					(stroke
						(width 0.254)
						(type default)
					)
					(fill
						(type none)
					)
				)
				(polyline
					(pts
						(xy 6.985 -7.62) (xy 7.62 -7.62)
					)
					(stroke
						(width 0)
						(type default)
					)
					(fill
						(type none)
					)
				)
			)
			(symbol "4x39R_0201_array_1_1"
				(pin passive line
					(at 0 0 0)
					(length 2.54)
					(name "R1.1"
						(effects
							(font
								(size 1.27 1.27)
							)
						)
					)
					(number "1"
						(effects
							(font
								(size 1.27 1.27)
							)
						)
					)
				)
				(pin passive line
					(at 0 -2.54 0)
					(length 2.54)
					(name "R2.1"
						(effects
							(font
								(size 1.27 1.27)
							)
						)
					)
					(number "2"
						(effects
							(font
								(size 1.27 1.27)
							)
						)
					)
				)
				(pin passive line
					(at 0 -5.08 0)
					(length 2.54)
					(name "R3.1"
						(effects
							(font
								(size 1.27 1.27)
							)
						)
					)
					(number "3"
						(effects
							(font
								(size 1.27 1.27)
							)
						)
					)
				)
				(pin passive line
					(at 0 -7.62 0)
					(length 2.54)
					(name "R4.1"
						(effects
							(font
								(size 1.27 1.27)
							)
						)
					)
					(number "4"
						(effects
							(font
								(size 1.27 1.27)
							)
						)
					)
				)
				(pin passive line
					(at 10.16 0 180)
					(length 2.54)
					(name "R1.2"
						(effects
							(font
								(size 1.27 1.27)
							)
						)
					)
					(number "8"
						(effects
							(font
								(size 1.27 1.27)
							)
						)
					)
				)
				(pin passive line
					(at 10.16 -2.54 180)
					(length 2.54)
					(name "R2.2"
						(effects
							(font
								(size 1.27 1.27)
							)
						)
					)
					(number "7"
						(effects
							(font
								(size 1.27 1.27)
							)
						)
					)
				)
				(pin passive line
					(at 10.16 -5.08 180)
					(length 2.54)
					(name "R3.2"
						(effects
							(font
								(size 1.27 1.27)
							)
						)
					)
					(number "6"
						(effects
							(font
								(size 1.27 1.27)
							)
						)
					)
				)
				(pin passive line
					(at 10.16 -7.62 180)
					(length 2.54)
					(name "R4.2"
						(effects
							(font
								(size 1.27 1.27)
							)
						)
					)
					(number "5"
						(effects
							(font
								(size 1.27 1.27)
							)
						)
					)
				)
			)
		)
	(symbol "antmicroResistorNetworksArrays:R_4x33R_0201_array"
			(pin_names
				(hide yes)
			)
			(exclude_from_sim no)
			(in_bom yes)
			(on_board yes)
			(property "Reference" "R"
				(at 26.67 -3.175 0)
				(effects
					(font
						(size 1.27 1.27)
						(thickness 0.15)
					)
					(justify left bottom)
				)
			)
			(property "Value" "R_4x33R_0201_array"
				(at 26.67 -5.715 0)
				(effects
					(font
						(size 1.27 1.27)
						(thickness 0.15)
					)
					(justify left bottom)
				)
			)
			(property "Footprint" "antmicro-footprints:R_Array_4x0201_Panasonic_EXB18V"
				(at 26.67 -10.795 0)
				(effects
					(font
						(size 1.27 1.27)
						(thickness 0.15)
					)
					(justify left bottom)
					(hide yes)
				)
			)
			(property "Datasheet" "http://industrial.panasonic.com/cdbs/www-data/pdf/AOC0000/AOC0000C14.pdf"
				(at 26.67 -13.335 0)
				(effects
					(font
						(size 1.27 1.27)
						(thickness 0.15)
					)
					(justify left bottom)
					(hide yes)
				)
			)
			(property "Description" "Fixed Network Resistor, 33 ohm, Isolated, 4 Resistors, 0502 [1406 Metric], Flat, ± 5%"
				(at 0 0 0)
				(effects
					(font
						(size 1.27 1.27)
					)
					(hide yes)
				)
			)
			(property "MPN" "EXB-18V330JX"
				(at 26.67 -15.875 0)
				(effects
					(font
						(size 1.27 1.27)
						(thickness 0.15)
					)
					(justify left bottom)
					(hide yes)
				)
			)
			(property "Manufacturer" "Panasonic"
				(at 26.67 -18.415 0)
				(effects
					(font
						(size 1.27 1.27)
						(thickness 0.15)
					)
					(justify left bottom)
					(hide yes)
				)
			)
			(property "Author" "Antmicro"
				(at 26.67 -20.955 0)
				(effects
					(font
						(size 1.27 1.27)
						(thickness 0.15)
					)
					(justify left bottom)
					(hide yes)
				)
			)
			(property "License" "Apache-2.0"
				(at 26.67 -23.495 0)
				(effects
					(font
						(size 1.27 1.27)
						(thickness 0.15)
					)
					(justify left bottom)
					(hide yes)
				)
			)
			(property "Val" "R_4x33R_0201"
				(at 26.67 -8.255 0)
				(effects
					(font
						(size 1.27 1.27)
					)
					(justify left bottom)
				)
			)
			(property "ki_keywords" "0201, SMT, RESISTOR, PASSIVE"
				(at 0 0 0)
				(effects
					(font
						(size 1.27 1.27)
					)
					(hide yes)
				)
			)
			(symbol "R_4x33R_0201_array_0_1"
				(polyline
					(pts
						(xy 2.54 0) (xy 3.175 0)
					)
					(stroke
						(width 0)
						(type default)
					)
					(fill
						(type none)
					)
				)
				(polyline
					(pts
						(xy 2.54 -2.54) (xy 3.175 -2.54)
					)
					(stroke
						(width 0)
						(type default)
					)
					(fill
						(type none)
					)
				)
				(polyline
					(pts
						(xy 2.54 -5.08) (xy 3.175 -5.08)
					)
					(stroke
						(width 0)
						(type default)
					)
					(fill
						(type none)
					)
				)
				(polyline
					(pts
						(xy 2.54 -7.62) (xy 3.175 -7.62)
					)
					(stroke
						(width 0)
						(type default)
					)
					(fill
						(type none)
					)
				)
				(rectangle
					(start 2.667 1.27)
					(end 7.493 -8.89)
					(stroke
						(width 0.254)
						(type default)
					)
					(fill
						(type background)
					)
				)
				(rectangle
					(start 6.985 0.635)
					(end 3.175 -0.635)
					(stroke
						(width 0.254)
						(type default)
					)
					(fill
						(type none)
					)
				)
				(polyline
					(pts
						(xy 6.985 0) (xy 7.62 0)
					)
					(stroke
						(width 0)
						(type default)
					)
					(fill
						(type none)
					)
				)
				(rectangle
					(start 6.985 -1.905)
					(end 3.175 -3.175)
					(stroke
						(width 0.254)
						(type default)
					)
					(fill
						(type none)
					)
				)
				(polyline
					(pts
						(xy 6.985 -2.54) (xy 7.62 -2.54)
					)
					(stroke
						(width 0)
						(type default)
					)
					(fill
						(type none)
					)
				)
				(rectangle
					(start 6.985 -4.445)
					(end 3.175 -5.715)
					(stroke
						(width 0.254)
						(type default)
					)
					(fill
						(type none)
					)
				)
				(polyline
					(pts
						(xy 6.985 -5.08) (xy 7.62 -5.08)
					)
					(stroke
						(width 0)
						(type default)
					)
					(fill
						(type none)
					)
				)
				(rectangle
					(start 6.985 -6.985)
					(end 3.175 -8.255)
					(stroke
						(width 0.254)
						(type default)
					)
					(fill
						(type none)
					)
				)
				(polyline
					(pts
						(xy 6.985 -7.62) (xy 7.62 -7.62)
					)
					(stroke
						(width 0)
						(type default)
					)
					(fill
						(type none)
					)
				)
			)
			(symbol "R_4x33R_0201_array_1_1"
				(pin passive line
					(at 0 0 0)
					(length 2.54)
					(name "R1.1"
						(effects
							(font
								(size 1.27 1.27)
							)
						)
					)
					(number "1"
						(effects
							(font
								(size 1.27 1.27)
							)
						)
					)
				)
				(pin passive line
					(at 0 -2.54 0)
					(length 2.54)
					(name "R2.1"
						(effects
							(font
								(size 1.27 1.27)
							)
						)
					)
					(number "2"
						(effects
							(font
								(size 1.27 1.27)
							)
						)
					)
				)
				(pin passive line
					(at 0 -5.08 0)
					(length 2.54)
					(name "R3.1"
						(effects
							(font
								(size 1.27 1.27)
							)
						)
					)
					(number "3"
						(effects
							(font
								(size 1.27 1.27)
							)
						)
					)
				)
				(pin passive line
					(at 0 -7.62 0)
					(length 2.54)
					(name "R4.1"
						(effects
							(font
								(size 1.27 1.27)
							)
						)
					)
					(number "4"
						(effects
							(font
								(size 1.27 1.27)
							)
						)
					)
				)
				(pin passive line
					(at 10.16 0 180)
					(length 2.54)
					(name "R1.2"
						(effects
							(font
								(size 1.27 1.27)
							)
						)
					)
					(number "8"
						(effects
							(font
								(size 1.27 1.27)
							)
						)
					)
				)
				(pin passive line
					(at 10.16 -2.54 180)
					(length 2.54)
					(name "R2.2"
						(effects
							(font
								(size 1.27 1.27)
							)
						)
					)
					(number "7"
						(effects
							(font
								(size 1.27 1.27)
							)
						)
					)
				)
				(pin passive line
					(at 10.16 -5.08 180)
					(length 2.54)
					(name "R3.2"
						(effects
							(font
								(size 1.27 1.27)
							)
						)
					)
					(number "6"
						(effects
							(font
								(size 1.27 1.27)
							)
						)
					)
				)
				(pin passive line
					(at 10.16 -7.62 180)
					(length 2.54)
					(name "R4.2"
						(effects
							(font
								(size 1.27 1.27)
							)
						)
					)
					(number "5"
						(effects
							(font
								(size 1.27 1.27)
							)
						)
					)
				)
			)
		)
	(symbol "antmicroResistors0402:R_0R_0402"
			(pin_numbers
				(hide yes)
			)
			(pin_names
				(hide yes)
			)
			(exclude_from_sim no)
			(in_bom yes)
			(on_board yes)
			(property "Reference" "R"
				(at 20.32 -5.08 0)
				(effects
					(font
						(size 1.27 1.27)
						(thickness 0.15)
					)
					(justify left bottom)
				)
			)
			(property "Value" "R_0R_0402"
				(at 20.32 -12.7 0)
				(effects
					(font
						(size 1.27 1.27)
						(thickness 0.15)
					)
					(justify left bottom)
					(hide yes)
				)
			)
			(property "Footprint" "antmicro-footprints:R_0402_1005Metric"
				(at 20.32 -15.24 0)
				(effects
					(font
						(size 1.27 1.27)
						(thickness 0.15)
					)
					(justify left bottom)
					(hide yes)
				)
			)
			(property "Datasheet" "https://industrial.panasonic.com/cdbs/www-data/pdf/RDA0000/AOA0000C301.pdf"
				(at 20.32 -17.78 0)
				(effects
					(font
						(size 1.27 1.27)
						(thickness 0.15)
					)
					(justify left bottom)
					(hide yes)
				)
			)
			(property "Description" "SMD Chip Resistor, Jumper, 0 ohm, 100 mW, 0402 [1005 Metric], Thick Film, General Purpose"
				(at 0 0 0)
				(effects
					(font
						(size 1.27 1.27)
					)
					(hide yes)
				)
			)
			(property "MPN" "ERJ2GE0R00X"
				(at 20.32 -20.32 0)
				(effects
					(font
						(size 1.27 1.27)
						(thickness 0.15)
					)
					(justify left bottom)
					(hide yes)
				)
			)
			(property "Manufacturer" "Panasonic"
				(at 20.32 -22.86 0)
				(effects
					(font
						(size 1.27 1.27)
						(thickness 0.15)
					)
					(justify left bottom)
					(hide yes)
				)
			)
			(property "License" "Apache-2.0"
				(at 20.32 -25.4 0)
				(effects
					(font
						(size 1.27 1.27)
						(thickness 0.15)
					)
					(justify left bottom)
					(hide yes)
				)
			)
			(property "Author" "Antmicro"
				(at 20.32 -27.94 0)
				(effects
					(font
						(size 1.27 1.27)
						(thickness 0.15)
					)
					(justify left bottom)
					(hide yes)
				)
			)
			(property "Val" "0R"
				(at 20.32 -7.62 0)
				(effects
					(font
						(size 1.27 1.27)
						(thickness 0.15)
					)
					(justify left bottom)
				)
			)
			(property "Tolerance" "~"
				(at 20.32 -10.16 0)
				(effects
					(font
						(size 1.27 1.27)
					)
					(justify left bottom)
					(hide yes)
				)
			)
			(property "Current" "1A"
				(at 20.32 -30.48 0)
				(effects
					(font
						(size 1.27 1.27)
						(thickness 0.15)
					)
					(justify left bottom)
					(hide yes)
				)
			)
			(property "ki_keywords" "0402, SMT, RESISTOR, PASSIVE"
				(at 0 0 0)
				(effects
					(font
						(size 1.27 1.27)
					)
					(hide yes)
				)
			)
			(symbol "R_0R_0402_0_1"
				(rectangle
					(start 0.635 0.889)
					(end 4.445 -0.889)
					(stroke
						(width 0.254)
						(type default)
					)
					(fill
						(type none)
					)
				)
			)
			(symbol "R_0R_0402_1_1"
				(pin passive line
					(at 0 0 0)
					(length 0.635)
					(name "~"
						(effects
							(font
								(size 1.27 1.27)
							)
						)
					)
					(number "1"
						(effects
							(font
								(size 1.27 1.27)
							)
						)
					)
				)
				(pin passive line
					(at 5.08 0 180)
					(length 0.635)
					(name "~"
						(effects
							(font
								(size 1.27 1.27)
							)
						)
					)
					(number "2"
						(effects
							(font
								(size 1.27 1.27)
							)
						)
					)
				)
			)
		)
	(symbol "antmicroResistors0402:R_100R_0402"
			(pin_numbers
				(hide yes)
			)
			(pin_names
				(hide yes)
			)
			(exclude_from_sim no)
			(in_bom yes)
			(on_board yes)
			(property "Reference" "R"
				(at 20.32 -5.08 0)
				(effects
					(font
						(size 1.27 1.27)
						(thickness 0.15)
					)
					(justify left bottom)
				)
			)
			(property "Value" "R_100R_0402"
				(at 20.32 -12.7 0)
				(effects
					(font
						(size 1.27 1.27)
						(thickness 0.15)
					)
					(justify left bottom)
					(hide yes)
				)
			)
			(property "Footprint" "antmicro-footprints:R_0402_1005Metric"
				(at 20.32 -15.24 0)
				(effects
					(font
						(size 1.27 1.27)
						(thickness 0.15)
					)
					(justify left bottom)
					(hide yes)
				)
			)
			(property "Datasheet" "https://www.bourns.com/docs/product-datasheets/cr.pdf"
				(at 20.32 -17.78 0)
				(effects
					(font
						(size 1.27 1.27)
						(thickness 0.15)
					)
					(justify left bottom)
					(hide yes)
				)
			)
			(property "Description" "SMD Chip Resistor, 100 ohm, ± 1%, 62.5 mW, 0402 [1005 Metric], Thick Film, General Purpose"
				(at 0 0 0)
				(effects
					(font
						(size 1.27 1.27)
					)
					(hide yes)
				)
			)
			(property "MPN" "CR0402-FX-1000GLF"
				(at 20.32 -20.32 0)
				(effects
					(font
						(size 1.27 1.27)
						(thickness 0.15)
					)
					(justify left bottom)
					(hide yes)
				)
			)
			(property "Manufacturer" "Bourns"
				(at 20.32 -22.86 0)
				(effects
					(font
						(size 1.27 1.27)
						(thickness 0.15)
					)
					(justify left bottom)
					(hide yes)
				)
			)
			(property "License" "Apache-2.0"
				(at 20.32 -25.4 0)
				(effects
					(font
						(size 1.27 1.27)
						(thickness 0.15)
					)
					(justify left bottom)
					(hide yes)
				)
			)
			(property "Author" "Antmicro"
				(at 20.32 -27.94 0)
				(effects
					(font
						(size 1.27 1.27)
						(thickness 0.15)
					)
					(justify left bottom)
					(hide yes)
				)
			)
			(property "Val" "100R"
				(at 20.32 -7.62 0)
				(effects
					(font
						(size 1.27 1.27)
						(thickness 0.15)
					)
					(justify left bottom)
				)
			)
			(property "Tolerance" "1%"
				(at 20.32 -10.16 0)
				(effects
					(font
						(size 1.27 1.27)
					)
					(justify left bottom)
					(hide yes)
				)
			)
			(property "ki_keywords" "0402, SMT, RESISTOR, PASSIVE"
				(at 0 0 0)
				(effects
					(font
						(size 1.27 1.27)
					)
					(hide yes)
				)
			)
			(symbol "R_100R_0402_0_1"
				(rectangle
					(start 0.635 0.889)
					(end 4.445 -0.889)
					(stroke
						(width 0.254)
						(type default)
					)
					(fill
						(type none)
					)
				)
			)
			(symbol "R_100R_0402_1_1"
				(pin passive line
					(at 0 0 0)
					(length 0.635)
					(name "~"
						(effects
							(font
								(size 1.27 1.27)
							)
						)
					)
					(number "1"
						(effects
							(font
								(size 1.27 1.27)
							)
						)
					)
				)
				(pin passive line
					(at 5.08 0 180)
					(length 0.635)
					(name "~"
						(effects
							(font
								(size 1.27 1.27)
							)
						)
					)
					(number "2"
						(effects
							(font
								(size 1.27 1.27)
							)
						)
					)
				)
			)
		)
	(symbol "antmicroResistors0402:R_100k_0402"
			(pin_numbers
				(hide yes)
			)
			(pin_names
				(hide yes)
			)
			(exclude_from_sim no)
			(in_bom yes)
			(on_board yes)
			(property "Reference" "R"
				(at 20.32 -5.08 0)
				(effects
					(font
						(size 1.27 1.27)
						(thickness 0.15)
					)
					(justify left bottom)
				)
			)
			(property "Value" "R_100k_0402"
				(at 20.32 -12.7 0)
				(effects
					(font
						(size 1.27 1.27)
						(thickness 0.15)
					)
					(justify left bottom)
					(hide yes)
				)
			)
			(property "Footprint" "antmicro-footprints:R_0402_1005Metric"
				(at 20.32 -15.24 0)
				(effects
					(font
						(size 1.27 1.27)
						(thickness 0.15)
					)
					(justify left bottom)
					(hide yes)
				)
			)
			(property "Datasheet" "https://www.bourns.com/docs/product-datasheets/cr.pdf"
				(at 20.32 -17.78 0)
				(effects
					(font
						(size 1.27 1.27)
						(thickness 0.15)
					)
					(justify left bottom)
					(hide yes)
				)
			)
			(property "Description" "SMD Chip Resistor, 100 kohm, ± 1%, 62.5 mW, 0402 [1005 Metric], Thick Film, General Purpose"
				(at 0 0 0)
				(effects
					(font
						(size 1.27 1.27)
					)
					(hide yes)
				)
			)
			(property "MPN" "CR0402-FX-1003GLF"
				(at 20.32 -20.32 0)
				(effects
					(font
						(size 1.27 1.27)
						(thickness 0.15)
					)
					(justify left bottom)
					(hide yes)
				)
			)
			(property "Manufacturer" "Bourns"
				(at 20.32 -22.86 0)
				(effects
					(font
						(size 1.27 1.27)
						(thickness 0.15)
					)
					(justify left bottom)
					(hide yes)
				)
			)
			(property "License" "Apache-2.0"
				(at 20.32 -25.4 0)
				(effects
					(font
						(size 1.27 1.27)
						(thickness 0.15)
					)
					(justify left bottom)
					(hide yes)
				)
			)
			(property "Author" "Antmicro"
				(at 20.32 -27.94 0)
				(effects
					(font
						(size 1.27 1.27)
						(thickness 0.15)
					)
					(justify left bottom)
					(hide yes)
				)
			)
			(property "Val" "100k"
				(at 20.32 -7.62 0)
				(effects
					(font
						(size 1.27 1.27)
						(thickness 0.15)
					)
					(justify left bottom)
				)
			)
			(property "Tolerance" "1%"
				(at 20.32 -10.16 0)
				(effects
					(font
						(size 1.27 1.27)
					)
					(justify left bottom)
					(hide yes)
				)
			)
			(property "ki_keywords" "0402, SMT, RESISTOR, PASSIVE"
				(at 0 0 0)
				(effects
					(font
						(size 1.27 1.27)
					)
					(hide yes)
				)
			)
			(symbol "R_100k_0402_0_1"
				(rectangle
					(start 0.635 0.889)
					(end 4.445 -0.889)
					(stroke
						(width 0.254)
						(type default)
					)
					(fill
						(type none)
					)
				)
			)
			(symbol "R_100k_0402_1_1"
				(pin passive line
					(at 0 0 0)
					(length 0.635)
					(name "~"
						(effects
							(font
								(size 1.27 1.27)
							)
						)
					)
					(number "1"
						(effects
							(font
								(size 1.27 1.27)
							)
						)
					)
				)
				(pin passive line
					(at 5.08 0 180)
					(length 0.635)
					(name "~"
						(effects
							(font
								(size 1.27 1.27)
							)
						)
					)
					(number "2"
						(effects
							(font
								(size 1.27 1.27)
							)
						)
					)
				)
			)
		)
	(symbol "antmicroResistors0402:R_10R_0402"
			(pin_numbers
				(hide yes)
			)
			(pin_names
				(hide yes)
			)
			(exclude_from_sim no)
			(in_bom yes)
			(on_board yes)
			(property "Reference" "R"
				(at 20.32 -5.08 0)
				(effects
					(font
						(size 1.27 1.27)
						(thickness 0.15)
					)
					(justify left bottom)
				)
			)
			(property "Value" "R_10R_0402"
				(at 20.32 -12.7 0)
				(effects
					(font
						(size 1.27 1.27)
						(thickness 0.15)
					)
					(justify left bottom)
					(hide yes)
				)
			)
			(property "Footprint" "antmicro-footprints:R_0402_1005Metric"
				(at 20.32 -15.24 0)
				(effects
					(font
						(size 1.27 1.27)
						(thickness 0.15)
					)
					(justify left bottom)
					(hide yes)
				)
			)
			(property "Datasheet" "https://www.bourns.com/docs/product-datasheets/cr.pdf"
				(at 20.32 -17.78 0)
				(effects
					(font
						(size 1.27 1.27)
						(thickness 0.15)
					)
					(justify left bottom)
					(hide yes)
				)
			)
			(property "Description" "SMD Chip Resistor, 10 ohm, ± 1%, 62.5 mW, 0402 [1005 Metric], Thick Film, General Purpose"
				(at 0 0 0)
				(effects
					(font
						(size 1.27 1.27)
					)
					(hide yes)
				)
			)
			(property "MPN" "CR0402-FX-10R0GLF"
				(at 20.32 -20.32 0)
				(effects
					(font
						(size 1.27 1.27)
						(thickness 0.15)
					)
					(justify left bottom)
					(hide yes)
				)
			)
			(property "Manufacturer" "Bourns"
				(at 20.32 -22.86 0)
				(effects
					(font
						(size 1.27 1.27)
						(thickness 0.15)
					)
					(justify left bottom)
					(hide yes)
				)
			)
			(property "License" "Apache-2.0"
				(at 20.32 -25.4 0)
				(effects
					(font
						(size 1.27 1.27)
						(thickness 0.15)
					)
					(justify left bottom)
					(hide yes)
				)
			)
			(property "Author" "Antmicro"
				(at 20.32 -27.94 0)
				(effects
					(font
						(size 1.27 1.27)
						(thickness 0.15)
					)
					(justify left bottom)
					(hide yes)
				)
			)
			(property "Val" "10R"
				(at 20.32 -7.62 0)
				(effects
					(font
						(size 1.27 1.27)
						(thickness 0.15)
					)
					(justify left bottom)
				)
			)
			(property "Tolerance" "1%"
				(at 20.32 -10.16 0)
				(effects
					(font
						(size 1.27 1.27)
					)
					(justify left bottom)
					(hide yes)
				)
			)
			(property "ki_keywords" "0402, SMT, RESISTOR, PASSIVE"
				(at 0 0 0)
				(effects
					(font
						(size 1.27 1.27)
					)
					(hide yes)
				)
			)
			(symbol "R_10R_0402_0_1"
				(rectangle
					(start 0.635 0.889)
					(end 4.445 -0.889)
					(stroke
						(width 0.254)
						(type default)
					)
					(fill
						(type none)
					)
				)
			)
			(symbol "R_10R_0402_1_1"
				(pin passive line
					(at 0 0 0)
					(length 0.635)
					(name "~"
						(effects
							(font
								(size 1.27 1.27)
							)
						)
					)
					(number "1"
						(effects
							(font
								(size 1.27 1.27)
							)
						)
					)
				)
				(pin passive line
					(at 5.08 0 180)
					(length 0.635)
					(name "~"
						(effects
							(font
								(size 1.27 1.27)
							)
						)
					)
					(number "2"
						(effects
							(font
								(size 1.27 1.27)
							)
						)
					)
				)
			)
		)
	(symbol "antmicroResistors0402:R_10k_0402"
			(pin_numbers
				(hide yes)
			)
			(pin_names
				(hide yes)
			)
			(exclude_from_sim no)
			(in_bom yes)
			(on_board yes)
			(property "Reference" "R"
				(at 20.32 -5.08 0)
				(effects
					(font
						(size 1.27 1.27)
						(thickness 0.15)
					)
					(justify left bottom)
				)
			)
			(property "Value" "R_10k_0402"
				(at 20.32 -12.7 0)
				(effects
					(font
						(size 1.27 1.27)
						(thickness 0.15)
					)
					(justify left bottom)
					(hide yes)
				)
			)
			(property "Footprint" "antmicro-footprints:R_0402_1005Metric"
				(at 20.32 -15.24 0)
				(effects
					(font
						(size 1.27 1.27)
						(thickness 0.15)
					)
					(justify left bottom)
					(hide yes)
				)
			)
			(property "Datasheet" "https://www.bourns.com/docs/product-datasheets/cr.pdf"
				(at 20.32 -17.78 0)
				(effects
					(font
						(size 1.27 1.27)
						(thickness 0.15)
					)
					(justify left bottom)
					(hide yes)
				)
			)
			(property "Description" "SMD Chip Resistor, 10 kohm, ± 1%, 62.5 mW, 0402 [1005 Metric], Thick Film, General Purpose"
				(at 0 0 0)
				(effects
					(font
						(size 1.27 1.27)
					)
					(hide yes)
				)
			)
			(property "MPN" "CR0402-FX-1002GLF"
				(at 20.32 -20.32 0)
				(effects
					(font
						(size 1.27 1.27)
						(thickness 0.15)
					)
					(justify left bottom)
					(hide yes)
				)
			)
			(property "Manufacturer" "Bourns"
				(at 20.32 -22.86 0)
				(effects
					(font
						(size 1.27 1.27)
						(thickness 0.15)
					)
					(justify left bottom)
					(hide yes)
				)
			)
			(property "License" "Apache-2.0"
				(at 20.32 -25.4 0)
				(effects
					(font
						(size 1.27 1.27)
						(thickness 0.15)
					)
					(justify left bottom)
					(hide yes)
				)
			)
			(property "Author" "Antmicro"
				(at 20.32 -27.94 0)
				(effects
					(font
						(size 1.27 1.27)
						(thickness 0.15)
					)
					(justify left bottom)
					(hide yes)
				)
			)
			(property "Val" "10k"
				(at 20.32 -7.62 0)
				(effects
					(font
						(size 1.27 1.27)
						(thickness 0.15)
					)
					(justify left bottom)
				)
			)
			(property "Tolerance" "1%"
				(at 20.32 -10.16 0)
				(effects
					(font
						(size 1.27 1.27)
					)
					(justify left bottom)
					(hide yes)
				)
			)
			(property "ki_keywords" "0402, SMT, RESISTOR, PASSIVE"
				(at 0 0 0)
				(effects
					(font
						(size 1.27 1.27)
					)
					(hide yes)
				)
			)
			(symbol "R_10k_0402_0_1"
				(rectangle
					(start 0.635 0.889)
					(end 4.445 -0.889)
					(stroke
						(width 0.254)
						(type default)
					)
					(fill
						(type none)
					)
				)
			)
			(symbol "R_10k_0402_1_1"
				(pin passive line
					(at 0 0 0)
					(length 0.635)
					(name "~"
						(effects
							(font
								(size 1.27 1.27)
							)
						)
					)
					(number "1"
						(effects
							(font
								(size 1.27 1.27)
							)
						)
					)
				)
				(pin passive line
					(at 5.08 0 180)
					(length 0.635)
					(name "~"
						(effects
							(font
								(size 1.27 1.27)
							)
						)
					)
					(number "2"
						(effects
							(font
								(size 1.27 1.27)
							)
						)
					)
				)
			)
		)
	(symbol "antmicroResistors0402:R_12k_0402"
			(pin_numbers
				(hide yes)
			)
			(pin_names
				(hide yes)
			)
			(exclude_from_sim no)
			(in_bom yes)
			(on_board yes)
			(property "Reference" "R"
				(at 20.32 -5.08 0)
				(effects
					(font
						(size 1.27 1.27)
						(thickness 0.15)
					)
					(justify left bottom)
				)
			)
			(property "Value" "R_12k_0402"
				(at 20.32 -12.7 0)
				(effects
					(font
						(size 1.27 1.27)
						(thickness 0.15)
					)
					(justify left bottom)
					(hide yes)
				)
			)
			(property "Footprint" "antmicro-footprints:R_0402_1005Metric"
				(at 20.32 -15.24 0)
				(effects
					(font
						(size 1.27 1.27)
						(thickness 0.15)
					)
					(justify left bottom)
					(hide yes)
				)
			)
			(property "Datasheet" "https://www.bourns.com/docs/product-datasheets/cr.pdf"
				(at 20.32 -17.78 0)
				(effects
					(font
						(size 1.27 1.27)
						(thickness 0.15)
					)
					(justify left bottom)
					(hide yes)
				)
			)
			(property "Description" "SMD Chip Resistor, 12 kohm, ± 1%, 62.5 mW, 0402 [1005 Metric], Thick Film, General Purpose"
				(at 0 0 0)
				(effects
					(font
						(size 1.27 1.27)
					)
					(hide yes)
				)
			)
			(property "MPN" "CR0402-FX-1202GLF"
				(at 20.32 -20.32 0)
				(effects
					(font
						(size 1.27 1.27)
						(thickness 0.15)
					)
					(justify left bottom)
					(hide yes)
				)
			)
			(property "Manufacturer" "Bourns"
				(at 20.32 -22.86 0)
				(effects
					(font
						(size 1.27 1.27)
						(thickness 0.15)
					)
					(justify left bottom)
					(hide yes)
				)
			)
			(property "License" "Apache-2.0"
				(at 20.32 -25.4 0)
				(effects
					(font
						(size 1.27 1.27)
						(thickness 0.15)
					)
					(justify left bottom)
					(hide yes)
				)
			)
			(property "Author" "Antmicro"
				(at 20.32 -27.94 0)
				(effects
					(font
						(size 1.27 1.27)
						(thickness 0.15)
					)
					(justify left bottom)
					(hide yes)
				)
			)
			(property "Val" "12k"
				(at 20.32 -7.62 0)
				(effects
					(font
						(size 1.27 1.27)
						(thickness 0.15)
					)
					(justify left bottom)
				)
			)
			(property "Tolerance" "1%"
				(at 20.32 -10.16 0)
				(effects
					(font
						(size 1.27 1.27)
					)
					(justify left bottom)
					(hide yes)
				)
			)
			(property "ki_keywords" "0402, SMT, RESISTOR, PASSIVE"
				(at 0 0 0)
				(effects
					(font
						(size 1.27 1.27)
					)
					(hide yes)
				)
			)
			(symbol "R_12k_0402_0_1"
				(rectangle
					(start 0.635 0.889)
					(end 4.445 -0.889)
					(stroke
						(width 0.254)
						(type default)
					)
					(fill
						(type none)
					)
				)
			)
			(symbol "R_12k_0402_1_1"
				(pin passive line
					(at 0 0 0)
					(length 0.635)
					(name "~"
						(effects
							(font
								(size 1.27 1.27)
							)
						)
					)
					(number "1"
						(effects
							(font
								(size 1.27 1.27)
							)
						)
					)
				)
				(pin passive line
					(at 5.08 0 180)
					(length 0.635)
					(name "~"
						(effects
							(font
								(size 1.27 1.27)
							)
						)
					)
					(number "2"
						(effects
							(font
								(size 1.27 1.27)
							)
						)
					)
				)
			)
		)
	(symbol "antmicroResistors0402:R_15k_0402"
			(pin_numbers
				(hide yes)
			)
			(pin_names
				(hide yes)
			)
			(exclude_from_sim no)
			(in_bom yes)
			(on_board yes)
			(property "Reference" "R"
				(at 20.32 -5.08 0)
				(effects
					(font
						(size 1.27 1.27)
						(thickness 0.15)
					)
					(justify left bottom)
				)
			)
			(property "Value" "R_15k_0402"
				(at 20.32 -12.7 0)
				(effects
					(font
						(size 1.27 1.27)
						(thickness 0.15)
					)
					(justify left bottom)
					(hide yes)
				)
			)
			(property "Footprint" "antmicro-footprints:R_0402_1005Metric"
				(at 20.32 -15.24 0)
				(effects
					(font
						(size 1.27 1.27)
						(thickness 0.15)
					)
					(justify left bottom)
					(hide yes)
				)
			)
			(property "Datasheet" "https://www.bourns.com/docs/product-datasheets/cr.pdf"
				(at 20.32 -17.78 0)
				(effects
					(font
						(size 1.27 1.27)
						(thickness 0.15)
					)
					(justify left bottom)
					(hide yes)
				)
			)
			(property "Description" "SMD Chip Resistor, 15 kohm, ± 1%, 62.5 mW, 0402 [1005 Metric], Thick Film, General Purpose"
				(at 0 0 0)
				(effects
					(font
						(size 1.27 1.27)
					)
					(hide yes)
				)
			)
			(property "MPN" "CR0402-FX-1502GLF"
				(at 20.32 -20.32 0)
				(effects
					(font
						(size 1.27 1.27)
						(thickness 0.15)
					)
					(justify left bottom)
					(hide yes)
				)
			)
			(property "Manufacturer" "Bourns"
				(at 20.32 -22.86 0)
				(effects
					(font
						(size 1.27 1.27)
						(thickness 0.15)
					)
					(justify left bottom)
					(hide yes)
				)
			)
			(property "License" "Apache-2.0"
				(at 20.32 -25.4 0)
				(effects
					(font
						(size 1.27 1.27)
						(thickness 0.15)
					)
					(justify left bottom)
					(hide yes)
				)
			)
			(property "Author" "Antmicro"
				(at 20.32 -27.94 0)
				(effects
					(font
						(size 1.27 1.27)
						(thickness 0.15)
					)
					(justify left bottom)
					(hide yes)
				)
			)
			(property "Val" "15k"
				(at 20.32 -7.62 0)
				(effects
					(font
						(size 1.27 1.27)
						(thickness 0.15)
					)
					(justify left bottom)
				)
			)
			(property "Tolerance" "1%"
				(at 20.32 -10.16 0)
				(effects
					(font
						(size 1.27 1.27)
					)
					(justify left bottom)
					(hide yes)
				)
			)
			(property "ki_keywords" "0402, SMT, RESISTOR, PASSIVE"
				(at 0 0 0)
				(effects
					(font
						(size 1.27 1.27)
					)
					(hide yes)
				)
			)
			(symbol "R_15k_0402_0_1"
				(rectangle
					(start 0.635 0.889)
					(end 4.445 -0.889)
					(stroke
						(width 0.254)
						(type default)
					)
					(fill
						(type none)
					)
				)
			)
			(symbol "R_15k_0402_1_1"
				(pin passive line
					(at 0 0 0)
					(length 0.635)
					(name "~"
						(effects
							(font
								(size 1.27 1.27)
							)
						)
					)
					(number "1"
						(effects
							(font
								(size 1.27 1.27)
							)
						)
					)
				)
				(pin passive line
					(at 5.08 0 180)
					(length 0.635)
					(name "~"
						(effects
							(font
								(size 1.27 1.27)
							)
						)
					)
					(number "2"
						(effects
							(font
								(size 1.27 1.27)
							)
						)
					)
				)
			)
		)
	(symbol "antmicroResistors0402:R_1M_0402"
			(pin_numbers
				(hide yes)
			)
			(pin_names
				(hide yes)
			)
			(exclude_from_sim no)
			(in_bom yes)
			(on_board yes)
			(property "Reference" "R"
				(at 20.32 -5.08 0)
				(effects
					(font
						(size 1.27 1.27)
						(thickness 0.15)
					)
					(justify left bottom)
				)
			)
			(property "Value" "R_1M_0402"
				(at 20.32 -12.7 0)
				(effects
					(font
						(size 1.27 1.27)
						(thickness 0.15)
					)
					(justify left bottom)
					(hide yes)
				)
			)
			(property "Footprint" "antmicro-footprints:R_0402_1005Metric"
				(at 20.32 -15.24 0)
				(effects
					(font
						(size 1.27 1.27)
						(thickness 0.15)
					)
					(justify left bottom)
					(hide yes)
				)
			)
			(property "Datasheet" "https://www.bourns.com/docs/product-datasheets/cr.pdf"
				(at 20.32 -17.78 0)
				(effects
					(font
						(size 1.27 1.27)
						(thickness 0.15)
					)
					(justify left bottom)
					(hide yes)
				)
			)
			(property "Description" "SMD Chip Resistor, 1 Mohm, ± 1%, 62.5 mW, 0402 [1005 Metric], Thick Film, General Purpose"
				(at 0 0 0)
				(effects
					(font
						(size 1.27 1.27)
					)
					(hide yes)
				)
			)
			(property "MPN" "CR0402-FX-1004GLF"
				(at 20.32 -20.32 0)
				(effects
					(font
						(size 1.27 1.27)
						(thickness 0.15)
					)
					(justify left bottom)
					(hide yes)
				)
			)
			(property "Manufacturer" "Bourns"
				(at 20.32 -22.86 0)
				(effects
					(font
						(size 1.27 1.27)
						(thickness 0.15)
					)
					(justify left bottom)
					(hide yes)
				)
			)
			(property "License" "Apache-2.0"
				(at 20.32 -25.4 0)
				(effects
					(font
						(size 1.27 1.27)
						(thickness 0.15)
					)
					(justify left bottom)
					(hide yes)
				)
			)
			(property "Author" "Antmicro"
				(at 20.32 -27.94 0)
				(effects
					(font
						(size 1.27 1.27)
						(thickness 0.15)
					)
					(justify left bottom)
					(hide yes)
				)
			)
			(property "Val" "1M"
				(at 20.32 -7.62 0)
				(effects
					(font
						(size 1.27 1.27)
						(thickness 0.15)
					)
					(justify left bottom)
				)
			)
			(property "Tolerance" "1%"
				(at 20.32 -10.16 0)
				(effects
					(font
						(size 1.27 1.27)
					)
					(justify left bottom)
					(hide yes)
				)
			)
			(property "ki_keywords" "0402, SMT, RESISTOR, PASSIVE"
				(at 0 0 0)
				(effects
					(font
						(size 1.27 1.27)
					)
					(hide yes)
				)
			)
			(symbol "R_1M_0402_0_1"
				(rectangle
					(start 0.635 0.889)
					(end 4.445 -0.889)
					(stroke
						(width 0.254)
						(type default)
					)
					(fill
						(type none)
					)
				)
			)
			(symbol "R_1M_0402_1_1"
				(pin passive line
					(at 0 0 0)
					(length 0.635)
					(name "~"
						(effects
							(font
								(size 1.27 1.27)
							)
						)
					)
					(number "1"
						(effects
							(font
								(size 1.27 1.27)
							)
						)
					)
				)
				(pin passive line
					(at 5.08 0 180)
					(length 0.635)
					(name "~"
						(effects
							(font
								(size 1.27 1.27)
							)
						)
					)
					(number "2"
						(effects
							(font
								(size 1.27 1.27)
							)
						)
					)
				)
			)
		)
	(symbol "antmicroResistors0402:R_1k2_0402"
			(pin_numbers
				(hide yes)
			)
			(pin_names
				(hide yes)
			)
			(exclude_from_sim no)
			(in_bom yes)
			(on_board yes)
			(property "Reference" "R"
				(at 20.32 -5.08 0)
				(effects
					(font
						(size 1.27 1.27)
						(thickness 0.15)
					)
					(justify left bottom)
				)
			)
			(property "Value" "R_1k2_0402"
				(at 20.32 -12.7 0)
				(effects
					(font
						(size 1.27 1.27)
						(thickness 0.15)
					)
					(justify left bottom)
					(hide yes)
				)
			)
			(property "Footprint" "antmicro-footprints:R_0402_1005Metric"
				(at 20.32 -15.24 0)
				(effects
					(font
						(size 1.27 1.27)
						(thickness 0.15)
					)
					(justify left bottom)
					(hide yes)
				)
			)
			(property "Datasheet" "https://www.bourns.com/docs/product-datasheets/cr.pdf"
				(at 20.32 -17.78 0)
				(effects
					(font
						(size 1.27 1.27)
						(thickness 0.15)
					)
					(justify left bottom)
					(hide yes)
				)
			)
			(property "Description" "SMD Chip Resistor, 1.2 kohm, ± 1%, 62.5 mW, 0402 [1005 Metric], Thick Film, General Purpose"
				(at 0 0 0)
				(effects
					(font
						(size 1.27 1.27)
					)
					(hide yes)
				)
			)
			(property "MPN" "CR0402-FX-1201GLF"
				(at 20.32 -20.32 0)
				(effects
					(font
						(size 1.27 1.27)
						(thickness 0.15)
					)
					(justify left bottom)
					(hide yes)
				)
			)
			(property "Manufacturer" "Bourns"
				(at 20.32 -22.86 0)
				(effects
					(font
						(size 1.27 1.27)
						(thickness 0.15)
					)
					(justify left bottom)
					(hide yes)
				)
			)
			(property "License" "Apache-2.0"
				(at 20.32 -25.4 0)
				(effects
					(font
						(size 1.27 1.27)
						(thickness 0.15)
					)
					(justify left bottom)
					(hide yes)
				)
			)
			(property "Author" "Antmicro"
				(at 20.32 -27.94 0)
				(effects
					(font
						(size 1.27 1.27)
						(thickness 0.15)
					)
					(justify left bottom)
					(hide yes)
				)
			)
			(property "Val" "1k2"
				(at 20.32 -7.62 0)
				(effects
					(font
						(size 1.27 1.27)
						(thickness 0.15)
					)
					(justify left bottom)
				)
			)
			(property "Tolerance" "1%"
				(at 20.32 -10.16 0)
				(effects
					(font
						(size 1.27 1.27)
					)
					(justify left bottom)
					(hide yes)
				)
			)
			(property "ki_keywords" "0402, SMT, RESISTOR, PASSIVE"
				(at 0 0 0)
				(effects
					(font
						(size 1.27 1.27)
					)
					(hide yes)
				)
			)
			(symbol "R_1k2_0402_0_1"
				(rectangle
					(start 0.635 0.889)
					(end 4.445 -0.889)
					(stroke
						(width 0.254)
						(type default)
					)
					(fill
						(type none)
					)
				)
			)
			(symbol "R_1k2_0402_1_1"
				(pin passive line
					(at 0 0 0)
					(length 0.635)
					(name "~"
						(effects
							(font
								(size 1.27 1.27)
							)
						)
					)
					(number "1"
						(effects
							(font
								(size 1.27 1.27)
							)
						)
					)
				)
				(pin passive line
					(at 5.08 0 180)
					(length 0.635)
					(name "~"
						(effects
							(font
								(size 1.27 1.27)
							)
						)
					)
					(number "2"
						(effects
							(font
								(size 1.27 1.27)
							)
						)
					)
				)
			)
		)
	(symbol "antmicroResistors0402:R_1k5_0402"
			(pin_numbers
				(hide yes)
			)
			(pin_names
				(hide yes)
			)
			(exclude_from_sim no)
			(in_bom yes)
			(on_board yes)
			(property "Reference" "R"
				(at 20.32 -5.08 0)
				(effects
					(font
						(size 1.27 1.27)
						(thickness 0.15)
					)
					(justify left bottom)
				)
			)
			(property "Value" "R_1k5_0402"
				(at 20.32 -12.7 0)
				(effects
					(font
						(size 1.27 1.27)
						(thickness 0.15)
					)
					(justify left bottom)
					(hide yes)
				)
			)
			(property "Footprint" "antmicro-footprints:R_0402_1005Metric"
				(at 20.32 -15.24 0)
				(effects
					(font
						(size 1.27 1.27)
						(thickness 0.15)
					)
					(justify left bottom)
					(hide yes)
				)
			)
			(property "Datasheet" "https://www.bourns.com/docs/product-datasheets/cr.pdf"
				(at 20.32 -17.78 0)
				(effects
					(font
						(size 1.27 1.27)
						(thickness 0.15)
					)
					(justify left bottom)
					(hide yes)
				)
			)
			(property "Description" "SMD Chip Resistor, 1.5 kohm, ± 1%, 62.5 mW, 0402 [1005 Metric], Thick Film, General Purpose"
				(at 0 0 0)
				(effects
					(font
						(size 1.27 1.27)
					)
					(hide yes)
				)
			)
			(property "MPN" "CR0402-FX-1501GLF"
				(at 20.32 -20.32 0)
				(effects
					(font
						(size 1.27 1.27)
						(thickness 0.15)
					)
					(justify left bottom)
					(hide yes)
				)
			)
			(property "Manufacturer" "Bourns"
				(at 20.32 -22.86 0)
				(effects
					(font
						(size 1.27 1.27)
						(thickness 0.15)
					)
					(justify left bottom)
					(hide yes)
				)
			)
			(property "License" "Apache-2.0"
				(at 20.32 -25.4 0)
				(effects
					(font
						(size 1.27 1.27)
						(thickness 0.15)
					)
					(justify left bottom)
					(hide yes)
				)
			)
			(property "Author" "Antmicro"
				(at 20.32 -27.94 0)
				(effects
					(font
						(size 1.27 1.27)
						(thickness 0.15)
					)
					(justify left bottom)
					(hide yes)
				)
			)
			(property "Val" "1k5"
				(at 20.32 -7.62 0)
				(effects
					(font
						(size 1.27 1.27)
						(thickness 0.15)
					)
					(justify left bottom)
				)
			)
			(property "Tolerance" "1%"
				(at 20.32 -10.16 0)
				(effects
					(font
						(size 1.27 1.27)
					)
					(justify left bottom)
					(hide yes)
				)
			)
			(property "ki_keywords" "0402, SMT, RESISTOR, PASSIVE"
				(at 0 0 0)
				(effects
					(font
						(size 1.27 1.27)
					)
					(hide yes)
				)
			)
			(symbol "R_1k5_0402_0_1"
				(rectangle
					(start 0.635 0.889)
					(end 4.445 -0.889)
					(stroke
						(width 0.254)
						(type default)
					)
					(fill
						(type none)
					)
				)
			)
			(symbol "R_1k5_0402_1_1"
				(pin passive line
					(at 0 0 0)
					(length 0.635)
					(name "~"
						(effects
							(font
								(size 1.27 1.27)
							)
						)
					)
					(number "1"
						(effects
							(font
								(size 1.27 1.27)
							)
						)
					)
				)
				(pin passive line
					(at 5.08 0 180)
					(length 0.635)
					(name "~"
						(effects
							(font
								(size 1.27 1.27)
							)
						)
					)
					(number "2"
						(effects
							(font
								(size 1.27 1.27)
							)
						)
					)
				)
			)
		)
	(symbol "antmicroResistors0402:R_1k_0402"
			(pin_numbers
				(hide yes)
			)
			(pin_names
				(hide yes)
			)
			(exclude_from_sim no)
			(in_bom yes)
			(on_board yes)
			(property "Reference" "R"
				(at 20.32 -5.08 0)
				(effects
					(font
						(size 1.27 1.27)
						(thickness 0.15)
					)
					(justify left bottom)
				)
			)
			(property "Value" "R_1k_0402"
				(at 20.32 -12.7 0)
				(effects
					(font
						(size 1.27 1.27)
						(thickness 0.15)
					)
					(justify left bottom)
					(hide yes)
				)
			)
			(property "Footprint" "antmicro-footprints:R_0402_1005Metric"
				(at 20.32 -15.24 0)
				(effects
					(font
						(size 1.27 1.27)
						(thickness 0.15)
					)
					(justify left bottom)
					(hide yes)
				)
			)
			(property "Datasheet" "https://www.bourns.com/docs/product-datasheets/cr.pdf"
				(at 20.32 -17.78 0)
				(effects
					(font
						(size 1.27 1.27)
						(thickness 0.15)
					)
					(justify left bottom)
					(hide yes)
				)
			)
			(property "Description" "SMD Chip Resistor, 1 kohm, ± 1%, 63 mW, 0402 [1005 Metric], Thick Film, General Purpose"
				(at 0 0 0)
				(effects
					(font
						(size 1.27 1.27)
					)
					(hide yes)
				)
			)
			(property "MPN" "CR0402-FX-1001GLF"
				(at 20.32 -20.32 0)
				(effects
					(font
						(size 1.27 1.27)
						(thickness 0.15)
					)
					(justify left bottom)
					(hide yes)
				)
			)
			(property "Manufacturer" "Bourns"
				(at 20.32 -22.86 0)
				(effects
					(font
						(size 1.27 1.27)
						(thickness 0.15)
					)
					(justify left bottom)
					(hide yes)
				)
			)
			(property "License" "Apache-2.0"
				(at 20.32 -25.4 0)
				(effects
					(font
						(size 1.27 1.27)
						(thickness 0.15)
					)
					(justify left bottom)
					(hide yes)
				)
			)
			(property "Author" "Antmicro"
				(at 20.32 -27.94 0)
				(effects
					(font
						(size 1.27 1.27)
						(thickness 0.15)
					)
					(justify left bottom)
					(hide yes)
				)
			)
			(property "Val" "1k"
				(at 20.32 -7.62 0)
				(effects
					(font
						(size 1.27 1.27)
						(thickness 0.15)
					)
					(justify left bottom)
				)
			)
			(property "Tolerance" "1%"
				(at 20.32 -10.16 0)
				(effects
					(font
						(size 1.27 1.27)
					)
					(justify left bottom)
					(hide yes)
				)
			)
			(symbol "R_1k_0402_0_1"
				(rectangle
					(start 0.635 0.889)
					(end 4.445 -0.889)
					(stroke
						(width 0.254)
						(type default)
					)
					(fill
						(type none)
					)
				)
			)
			(symbol "R_1k_0402_1_1"
				(pin passive line
					(at 0 0 0)
					(length 0.635)
					(name "~"
						(effects
							(font
								(size 1.27 1.27)
							)
						)
					)
					(number "1"
						(effects
							(font
								(size 1.27 1.27)
							)
						)
					)
				)
				(pin passive line
					(at 5.08 0 180)
					(length 0.635)
					(name "~"
						(effects
							(font
								(size 1.27 1.27)
							)
						)
					)
					(number "2"
						(effects
							(font
								(size 1.27 1.27)
							)
						)
					)
				)
			)
		)
	(symbol "antmicroResistors0402:R_205k_0402"
			(pin_numbers
				(hide yes)
			)
			(pin_names
				(hide yes)
			)
			(exclude_from_sim no)
			(in_bom yes)
			(on_board yes)
			(property "Reference" "R"
				(at 20.32 -5.08 0)
				(effects
					(font
						(size 1.27 1.27)
						(thickness 0.15)
					)
					(justify left bottom)
				)
			)
			(property "Value" "R_205k_0402"
				(at 20.32 -12.7 0)
				(effects
					(font
						(size 1.27 1.27)
						(thickness 0.15)
					)
					(justify left bottom)
					(hide yes)
				)
			)
			(property "Footprint" "antmicro-footprints:R_0402_1005Metric"
				(at 20.32 -15.24 0)
				(effects
					(font
						(size 1.27 1.27)
						(thickness 0.15)
					)
					(justify left bottom)
					(hide yes)
				)
			)
			(property "Datasheet" "https://www.bourns.com/docs/product-datasheets/cr.pdf"
				(at 20.32 -17.78 0)
				(effects
					(font
						(size 1.27 1.27)
						(thickness 0.15)
					)
					(justify left bottom)
					(hide yes)
				)
			)
			(property "Description" "SMD Chip Resistor"
				(at 0 0 0)
				(effects
					(font
						(size 1.27 1.27)
					)
					(hide yes)
				)
			)
			(property "MPN" "CR0402-FX-2053GLF"
				(at 20.32 -20.32 0)
				(effects
					(font
						(size 1.27 1.27)
						(thickness 0.15)
					)
					(justify left bottom)
					(hide yes)
				)
			)
			(property "Manufacturer" "Bourns"
				(at 20.32 -22.86 0)
				(effects
					(font
						(size 1.27 1.27)
						(thickness 0.15)
					)
					(justify left bottom)
					(hide yes)
				)
			)
			(property "License" "Apache-2.0"
				(at 20.32 -25.4 0)
				(effects
					(font
						(size 1.27 1.27)
						(thickness 0.15)
					)
					(justify left bottom)
					(hide yes)
				)
			)
			(property "Author" "Antmicro"
				(at 20.32 -27.94 0)
				(effects
					(font
						(size 1.27 1.27)
						(thickness 0.15)
					)
					(justify left bottom)
					(hide yes)
				)
			)
			(property "Val" "205k"
				(at 20.32 -7.62 0)
				(effects
					(font
						(size 1.27 1.27)
						(thickness 0.15)
					)
					(justify left bottom)
				)
			)
			(property "Tolerance" "1%"
				(at 20.32 -10.16 0)
				(effects
					(font
						(size 1.27 1.27)
					)
					(justify left bottom)
					(hide yes)
				)
			)
			(property "ki_keywords" "0402, SMT, RESISTOR, PASSIVE"
				(at 0 0 0)
				(effects
					(font
						(size 1.27 1.27)
					)
					(hide yes)
				)
			)
			(symbol "R_205k_0402_0_1"
				(rectangle
					(start 0.635 0.889)
					(end 4.445 -0.889)
					(stroke
						(width 0.254)
						(type default)
					)
					(fill
						(type none)
					)
				)
			)
			(symbol "R_205k_0402_1_1"
				(pin passive line
					(at 0 0 0)
					(length 0.635)
					(name "~"
						(effects
							(font
								(size 1.27 1.27)
							)
						)
					)
					(number "1"
						(effects
							(font
								(size 1.27 1.27)
							)
						)
					)
				)
				(pin passive line
					(at 5.08 0 180)
					(length 0.635)
					(name "~"
						(effects
							(font
								(size 1.27 1.27)
							)
						)
					)
					(number "2"
						(effects
							(font
								(size 1.27 1.27)
							)
						)
					)
				)
			)
		)
	(symbol "antmicroResistors0402:R_22R_0402"
			(pin_numbers
				(hide yes)
			)
			(pin_names
				(hide yes)
			)
			(exclude_from_sim no)
			(in_bom yes)
			(on_board yes)
			(property "Reference" "R"
				(at 20.32 -5.08 0)
				(effects
					(font
						(size 1.27 1.27)
						(thickness 0.15)
					)
					(justify left bottom)
				)
			)
			(property "Value" "R_22R_0402"
				(at 20.32 -12.7 0)
				(effects
					(font
						(size 1.27 1.27)
						(thickness 0.15)
					)
					(justify left bottom)
					(hide yes)
				)
			)
			(property "Footprint" "antmicro-footprints:R_0402_1005Metric"
				(at 20.32 -15.24 0)
				(effects
					(font
						(size 1.27 1.27)
						(thickness 0.15)
					)
					(justify left bottom)
					(hide yes)
				)
			)
			(property "Datasheet" "https://www.bourns.com/docs/product-datasheets/cr.pdf"
				(at 20.32 -17.78 0)
				(effects
					(font
						(size 1.27 1.27)
						(thickness 0.15)
					)
					(justify left bottom)
					(hide yes)
				)
			)
			(property "Description" "SMD Chip Resistor, 22 ohm, ± 1%, 62.5 mW, 0402 [1005 Metric], Thick Film, General Purpose"
				(at 0 0 0)
				(effects
					(font
						(size 1.27 1.27)
					)
					(hide yes)
				)
			)
			(property "MPN" "CR0402-FX-22R0GLF"
				(at 20.32 -20.32 0)
				(effects
					(font
						(size 1.27 1.27)
						(thickness 0.15)
					)
					(justify left bottom)
					(hide yes)
				)
			)
			(property "Manufacturer" "Bourns"
				(at 20.32 -22.86 0)
				(effects
					(font
						(size 1.27 1.27)
						(thickness 0.15)
					)
					(justify left bottom)
					(hide yes)
				)
			)
			(property "License" "Apache-2.0"
				(at 20.32 -25.4 0)
				(effects
					(font
						(size 1.27 1.27)
						(thickness 0.15)
					)
					(justify left bottom)
					(hide yes)
				)
			)
			(property "Author" "Antmicro"
				(at 20.32 -27.94 0)
				(effects
					(font
						(size 1.27 1.27)
						(thickness 0.15)
					)
					(justify left bottom)
					(hide yes)
				)
			)
			(property "Val" "22R"
				(at 20.32 -7.62 0)
				(effects
					(font
						(size 1.27 1.27)
						(thickness 0.15)
					)
					(justify left bottom)
				)
			)
			(property "Tolerance" "1%"
				(at 20.32 -10.16 0)
				(effects
					(font
						(size 1.27 1.27)
					)
					(justify left bottom)
					(hide yes)
				)
			)
			(property "ki_keywords" "0402, SMT, RESISTOR, PASSIVE"
				(at 0 0 0)
				(effects
					(font
						(size 1.27 1.27)
					)
					(hide yes)
				)
			)
			(symbol "R_22R_0402_0_1"
				(rectangle
					(start 0.635 0.889)
					(end 4.445 -0.889)
					(stroke
						(width 0.254)
						(type default)
					)
					(fill
						(type none)
					)
				)
			)
			(symbol "R_22R_0402_1_1"
				(pin passive line
					(at 0 0 0)
					(length 0.635)
					(name "~"
						(effects
							(font
								(size 1.27 1.27)
							)
						)
					)
					(number "1"
						(effects
							(font
								(size 1.27 1.27)
							)
						)
					)
				)
				(pin passive line
					(at 5.08 0 180)
					(length 0.635)
					(name "~"
						(effects
							(font
								(size 1.27 1.27)
							)
						)
					)
					(number "2"
						(effects
							(font
								(size 1.27 1.27)
							)
						)
					)
				)
			)
		)
	(symbol "antmicroResistors0402:R_22k_0402"
			(pin_numbers
				(hide yes)
			)
			(pin_names
				(hide yes)
			)
			(exclude_from_sim no)
			(in_bom yes)
			(on_board yes)
			(property "Reference" "R"
				(at 20.32 -5.08 0)
				(effects
					(font
						(size 1.27 1.27)
						(thickness 0.15)
					)
					(justify left bottom)
				)
			)
			(property "Value" "R_22k_0402"
				(at 20.32 -12.7 0)
				(effects
					(font
						(size 1.27 1.27)
						(thickness 0.15)
					)
					(justify left bottom)
					(hide yes)
				)
			)
			(property "Footprint" "antmicro-footprints:R_0402_1005Metric"
				(at 20.32 -15.24 0)
				(effects
					(font
						(size 1.27 1.27)
						(thickness 0.15)
					)
					(justify left bottom)
					(hide yes)
				)
			)
			(property "Datasheet" "https://www.bourns.com/docs/product-datasheets/cr.pdf"
				(at 20.32 -17.78 0)
				(effects
					(font
						(size 1.27 1.27)
						(thickness 0.15)
					)
					(justify left bottom)
					(hide yes)
				)
			)
			(property "Description" "SMD Chip Resistor, 22 kohm, ± 1%, 62.5 mW, 0402 [1005 Metric], Thick Film, General Purpose"
				(at 0 0 0)
				(effects
					(font
						(size 1.27 1.27)
					)
					(hide yes)
				)
			)
			(property "MPN" "CR0402-FX-2202GLF"
				(at 20.32 -20.32 0)
				(effects
					(font
						(size 1.27 1.27)
						(thickness 0.15)
					)
					(justify left bottom)
					(hide yes)
				)
			)
			(property "Manufacturer" "Bourns"
				(at 20.32 -22.86 0)
				(effects
					(font
						(size 1.27 1.27)
						(thickness 0.15)
					)
					(justify left bottom)
					(hide yes)
				)
			)
			(property "License" "Apache-2.0"
				(at 20.32 -25.4 0)
				(effects
					(font
						(size 1.27 1.27)
						(thickness 0.15)
					)
					(justify left bottom)
					(hide yes)
				)
			)
			(property "Author" "Antmicro"
				(at 20.32 -27.94 0)
				(effects
					(font
						(size 1.27 1.27)
						(thickness 0.15)
					)
					(justify left bottom)
					(hide yes)
				)
			)
			(property "Val" "22k"
				(at 20.32 -7.62 0)
				(effects
					(font
						(size 1.27 1.27)
						(thickness 0.15)
					)
					(justify left bottom)
				)
			)
			(property "Tolerance" "1%"
				(at 20.32 -10.16 0)
				(effects
					(font
						(size 1.27 1.27)
					)
					(justify left bottom)
					(hide yes)
				)
			)
			(property "ki_keywords" "0402, SMT, RESISTOR, PASSIVE"
				(at 0 0 0)
				(effects
					(font
						(size 1.27 1.27)
					)
					(hide yes)
				)
			)
			(symbol "R_22k_0402_0_1"
				(rectangle
					(start 0.635 0.889)
					(end 4.445 -0.889)
					(stroke
						(width 0.254)
						(type default)
					)
					(fill
						(type none)
					)
				)
			)
			(symbol "R_22k_0402_1_1"
				(pin passive line
					(at 0 0 0)
					(length 0.635)
					(name "~"
						(effects
							(font
								(size 1.27 1.27)
							)
						)
					)
					(number "1"
						(effects
							(font
								(size 1.27 1.27)
							)
						)
					)
				)
				(pin passive line
					(at 5.08 0 180)
					(length 0.635)
					(name "~"
						(effects
							(font
								(size 1.27 1.27)
							)
						)
					)
					(number "2"
						(effects
							(font
								(size 1.27 1.27)
							)
						)
					)
				)
			)
		)
	(symbol "antmicroResistors0402:R_240R_0402"
			(pin_numbers
				(hide yes)
			)
			(pin_names
				(hide yes)
			)
			(exclude_from_sim no)
			(in_bom yes)
			(on_board yes)
			(property "Reference" "R"
				(at 20.32 -5.08 0)
				(effects
					(font
						(size 1.27 1.27)
						(thickness 0.15)
					)
					(justify left bottom)
				)
			)
			(property "Value" "R_240R_0402"
				(at 20.32 -12.7 0)
				(effects
					(font
						(size 1.27 1.27)
						(thickness 0.15)
					)
					(justify left bottom)
					(hide yes)
				)
			)
			(property "Footprint" "antmicro-footprints:R_0402_1005Metric"
				(at 20.32 -15.24 0)
				(effects
					(font
						(size 1.27 1.27)
						(thickness 0.15)
					)
					(justify left bottom)
					(hide yes)
				)
			)
			(property "Datasheet" "https://www.bourns.com/docs/product-datasheets/cr.pdf"
				(at 20.32 -17.78 0)
				(effects
					(font
						(size 1.27 1.27)
						(thickness 0.15)
					)
					(justify left bottom)
					(hide yes)
				)
			)
			(property "Description" "SMD Chip Resistor, 240 ohm, ± 1%, 63 mW, 0402 [1005 Metric], Thick Film, General Purpose"
				(at 0 0 0)
				(effects
					(font
						(size 1.27 1.27)
					)
					(hide yes)
				)
			)
			(property "MPN" "CR0402-FX-2400GLF"
				(at 20.32 -20.32 0)
				(effects
					(font
						(size 1.27 1.27)
						(thickness 0.15)
					)
					(justify left bottom)
					(hide yes)
				)
			)
			(property "Manufacturer" "Bourns"
				(at 20.32 -22.86 0)
				(effects
					(font
						(size 1.27 1.27)
						(thickness 0.15)
					)
					(justify left bottom)
					(hide yes)
				)
			)
			(property "License" "Apache-2.0"
				(at 20.32 -25.4 0)
				(effects
					(font
						(size 1.27 1.27)
						(thickness 0.15)
					)
					(justify left bottom)
					(hide yes)
				)
			)
			(property "Author" "Antmicro"
				(at 20.32 -27.94 0)
				(effects
					(font
						(size 1.27 1.27)
						(thickness 0.15)
					)
					(justify left bottom)
					(hide yes)
				)
			)
			(property "Val" "240R"
				(at 20.32 -7.62 0)
				(effects
					(font
						(size 1.27 1.27)
						(thickness 0.15)
					)
					(justify left bottom)
				)
			)
			(property "Tolerance" "1%"
				(at 20.32 -10.16 0)
				(effects
					(font
						(size 1.27 1.27)
					)
					(justify left bottom)
					(hide yes)
				)
			)
			(property "ki_keywords" "0402, SMT, RESISTOR, PASSIVE"
				(at 0 0 0)
				(effects
					(font
						(size 1.27 1.27)
					)
					(hide yes)
				)
			)
			(symbol "R_240R_0402_0_1"
				(rectangle
					(start 0.635 0.889)
					(end 4.445 -0.889)
					(stroke
						(width 0.254)
						(type default)
					)
					(fill
						(type none)
					)
				)
			)
			(symbol "R_240R_0402_1_1"
				(pin passive line
					(at 0 0 0)
					(length 0.635)
					(name "~"
						(effects
							(font
								(size 1.27 1.27)
							)
						)
					)
					(number "1"
						(effects
							(font
								(size 1.27 1.27)
							)
						)
					)
				)
				(pin passive line
					(at 5.08 0 180)
					(length 0.635)
					(name "~"
						(effects
							(font
								(size 1.27 1.27)
							)
						)
					)
					(number "2"
						(effects
							(font
								(size 1.27 1.27)
							)
						)
					)
				)
			)
		)
	(symbol "antmicroResistors0402:R_24k9_0402"
			(pin_numbers
				(hide yes)
			)
			(pin_names
				(hide yes)
			)
			(exclude_from_sim no)
			(in_bom yes)
			(on_board yes)
			(property "Reference" "R"
				(at 20.32 -5.08 0)
				(effects
					(font
						(size 1.27 1.27)
						(thickness 0.15)
					)
					(justify left bottom)
				)
			)
			(property "Value" "R_24k9_0402"
				(at 20.32 -12.7 0)
				(effects
					(font
						(size 1.27 1.27)
						(thickness 0.15)
					)
					(justify left bottom)
					(hide yes)
				)
			)
			(property "Footprint" "antmicro-footprints:R_0402_1005Metric"
				(at 20.32 -15.24 0)
				(effects
					(font
						(size 1.27 1.27)
						(thickness 0.15)
					)
					(justify left bottom)
					(hide yes)
				)
			)
			(property "Datasheet" "https://www.bourns.com/docs/product-datasheets/cr.pdf"
				(at 20.32 -17.78 0)
				(effects
					(font
						(size 1.27 1.27)
						(thickness 0.15)
					)
					(justify left bottom)
					(hide yes)
				)
			)
			(property "Description" "SMD Chip Resistor, 24.9 kohm, ± 1%, 63 mW, 0402 [1005 Metric], Thick Film, General Purpose"
				(at 0 0 0)
				(effects
					(font
						(size 1.27 1.27)
					)
					(hide yes)
				)
			)
			(property "MPN" "CR0402-FX-2492GLF"
				(at 20.32 -20.32 0)
				(effects
					(font
						(size 1.27 1.27)
						(thickness 0.15)
					)
					(justify left bottom)
					(hide yes)
				)
			)
			(property "Manufacturer" "Bourns"
				(at 20.32 -22.86 0)
				(effects
					(font
						(size 1.27 1.27)
						(thickness 0.15)
					)
					(justify left bottom)
					(hide yes)
				)
			)
			(property "License" "Apache-2.0"
				(at 20.32 -25.4 0)
				(effects
					(font
						(size 1.27 1.27)
						(thickness 0.15)
					)
					(justify left bottom)
					(hide yes)
				)
			)
			(property "Author" "Antmicro"
				(at 20.32 -27.94 0)
				(effects
					(font
						(size 1.27 1.27)
						(thickness 0.15)
					)
					(justify left bottom)
					(hide yes)
				)
			)
			(property "Val" "24k9"
				(at 20.32 -7.62 0)
				(effects
					(font
						(size 1.27 1.27)
						(thickness 0.15)
					)
					(justify left bottom)
				)
			)
			(property "Tolerance" "1%"
				(at 20.32 -10.16 0)
				(effects
					(font
						(size 1.27 1.27)
					)
					(justify left bottom)
					(hide yes)
				)
			)
			(property "ki_keywords" "0402, SMT, RESISTOR, PASSIVE"
				(at 0 0 0)
				(effects
					(font
						(size 1.27 1.27)
					)
					(hide yes)
				)
			)
			(symbol "R_24k9_0402_0_1"
				(rectangle
					(start 0.635 0.889)
					(end 4.445 -0.889)
					(stroke
						(width 0.254)
						(type default)
					)
					(fill
						(type none)
					)
				)
			)
			(symbol "R_24k9_0402_1_1"
				(pin passive line
					(at 0 0 0)
					(length 0.635)
					(name "~"
						(effects
							(font
								(size 1.27 1.27)
							)
						)
					)
					(number "1"
						(effects
							(font
								(size 1.27 1.27)
							)
						)
					)
				)
				(pin passive line
					(at 5.08 0 180)
					(length 0.635)
					(name "~"
						(effects
							(font
								(size 1.27 1.27)
							)
						)
					)
					(number "2"
						(effects
							(font
								(size 1.27 1.27)
							)
						)
					)
				)
			)
		)
	(symbol "antmicroResistors0402:R_2k2_0402"
			(pin_numbers
				(hide yes)
			)
			(pin_names
				(hide yes)
			)
			(exclude_from_sim no)
			(in_bom yes)
			(on_board yes)
			(property "Reference" "R"
				(at 20.32 -5.08 0)
				(effects
					(font
						(size 1.27 1.27)
						(thickness 0.15)
					)
					(justify left bottom)
				)
			)
			(property "Value" "R_2k2_0402"
				(at 20.32 -12.7 0)
				(effects
					(font
						(size 1.27 1.27)
						(thickness 0.15)
					)
					(justify left bottom)
					(hide yes)
				)
			)
			(property "Footprint" "antmicro-footprints:R_0402_1005Metric"
				(at 20.32 -15.24 0)
				(effects
					(font
						(size 1.27 1.27)
						(thickness 0.15)
					)
					(justify left bottom)
					(hide yes)
				)
			)
			(property "Datasheet" "https://www.bourns.com/docs/product-datasheets/cr.pdf"
				(at 20.32 -17.78 0)
				(effects
					(font
						(size 1.27 1.27)
						(thickness 0.15)
					)
					(justify left bottom)
					(hide yes)
				)
			)
			(property "Description" "SMD Chip Resistor, 2.2 kohm, ± 1%, 62.5 mW, 0402 [1005 Metric], Thick Film, General Purpose"
				(at 0 0 0)
				(effects
					(font
						(size 1.27 1.27)
					)
					(hide yes)
				)
			)
			(property "MPN" "CR0402-FX-2201GLF"
				(at 20.32 -20.32 0)
				(effects
					(font
						(size 1.27 1.27)
						(thickness 0.15)
					)
					(justify left bottom)
					(hide yes)
				)
			)
			(property "Manufacturer" "Bourns"
				(at 20.32 -22.86 0)
				(effects
					(font
						(size 1.27 1.27)
						(thickness 0.15)
					)
					(justify left bottom)
					(hide yes)
				)
			)
			(property "License" "Apache-2.0"
				(at 20.32 -25.4 0)
				(effects
					(font
						(size 1.27 1.27)
						(thickness 0.15)
					)
					(justify left bottom)
					(hide yes)
				)
			)
			(property "Author" "Antmicro"
				(at 20.32 -27.94 0)
				(effects
					(font
						(size 1.27 1.27)
						(thickness 0.15)
					)
					(justify left bottom)
					(hide yes)
				)
			)
			(property "Val" "2k2"
				(at 20.32 -7.62 0)
				(effects
					(font
						(size 1.27 1.27)
						(thickness 0.15)
					)
					(justify left bottom)
				)
			)
			(property "Tolerance" "1%"
				(at 20.32 -10.16 0)
				(effects
					(font
						(size 1.27 1.27)
					)
					(justify left bottom)
					(hide yes)
				)
			)
			(property "ki_keywords" "0402, SMT, RESISTOR, PASSIVE"
				(at 0 0 0)
				(effects
					(font
						(size 1.27 1.27)
					)
					(hide yes)
				)
			)
			(symbol "R_2k2_0402_0_1"
				(rectangle
					(start 0.635 0.889)
					(end 4.445 -0.889)
					(stroke
						(width 0.254)
						(type default)
					)
					(fill
						(type none)
					)
				)
			)
			(symbol "R_2k2_0402_1_1"
				(pin passive line
					(at 0 0 0)
					(length 0.635)
					(name "~"
						(effects
							(font
								(size 1.27 1.27)
							)
						)
					)
					(number "1"
						(effects
							(font
								(size 1.27 1.27)
							)
						)
					)
				)
				(pin passive line
					(at 5.08 0 180)
					(length 0.635)
					(name "~"
						(effects
							(font
								(size 1.27 1.27)
							)
						)
					)
					(number "2"
						(effects
							(font
								(size 1.27 1.27)
							)
						)
					)
				)
			)
		)
	(symbol "antmicroResistors0402:R_330R_0402"
			(pin_numbers
				(hide yes)
			)
			(pin_names
				(hide yes)
			)
			(exclude_from_sim no)
			(in_bom yes)
			(on_board yes)
			(property "Reference" "R"
				(at 20.32 -5.08 0)
				(effects
					(font
						(size 1.27 1.27)
						(thickness 0.15)
					)
					(justify left bottom)
				)
			)
			(property "Value" "R_330R_0402"
				(at 20.32 -12.7 0)
				(effects
					(font
						(size 1.27 1.27)
						(thickness 0.15)
					)
					(justify left bottom)
					(hide yes)
				)
			)
			(property "Footprint" "antmicro-footprints:R_0402_1005Metric"
				(at 20.32 -15.24 0)
				(effects
					(font
						(size 1.27 1.27)
						(thickness 0.15)
					)
					(justify left bottom)
					(hide yes)
				)
			)
			(property "Datasheet" "https://www.bourns.com/docs/product-datasheets/cr.pdf"
				(at 20.32 -17.78 0)
				(effects
					(font
						(size 1.27 1.27)
						(thickness 0.15)
					)
					(justify left bottom)
					(hide yes)
				)
			)
			(property "Description" "SMD Chip Resistor, 330 ohm, ± 1%, 62.5 mW, 0402 [1005 Metric], Thick Film, General Purpose"
				(at 0 0 0)
				(effects
					(font
						(size 1.27 1.27)
					)
					(hide yes)
				)
			)
			(property "MPN" "CR0402-FX-3300GLF"
				(at 20.32 -20.32 0)
				(effects
					(font
						(size 1.27 1.27)
						(thickness 0.15)
					)
					(justify left bottom)
					(hide yes)
				)
			)
			(property "Manufacturer" "Bourns"
				(at 20.32 -22.86 0)
				(effects
					(font
						(size 1.27 1.27)
						(thickness 0.15)
					)
					(justify left bottom)
					(hide yes)
				)
			)
			(property "License" "Apache-2.0"
				(at 20.32 -25.4 0)
				(effects
					(font
						(size 1.27 1.27)
						(thickness 0.15)
					)
					(justify left bottom)
					(hide yes)
				)
			)
			(property "Author" "Antmicro"
				(at 20.32 -27.94 0)
				(effects
					(font
						(size 1.27 1.27)
						(thickness 0.15)
					)
					(justify left bottom)
					(hide yes)
				)
			)
			(property "Val" "330R"
				(at 20.32 -7.62 0)
				(effects
					(font
						(size 1.27 1.27)
						(thickness 0.15)
					)
					(justify left bottom)
				)
			)
			(property "Tolerance" "1%"
				(at 20.32 -10.16 0)
				(effects
					(font
						(size 1.27 1.27)
					)
					(justify left bottom)
					(hide yes)
				)
			)
			(symbol "R_330R_0402_0_1"
				(rectangle
					(start 0.635 0.889)
					(end 4.445 -0.889)
					(stroke
						(width 0.254)
						(type default)
					)
					(fill
						(type none)
					)
				)
			)
			(symbol "R_330R_0402_1_1"
				(pin passive line
					(at 0 0 0)
					(length 0.635)
					(name "~"
						(effects
							(font
								(size 1.27 1.27)
							)
						)
					)
					(number "1"
						(effects
							(font
								(size 1.27 1.27)
							)
						)
					)
				)
				(pin passive line
					(at 5.08 0 180)
					(length 0.635)
					(name "~"
						(effects
							(font
								(size 1.27 1.27)
							)
						)
					)
					(number "2"
						(effects
							(font
								(size 1.27 1.27)
							)
						)
					)
				)
			)
		)
	(symbol "antmicroResistors0402:R_33R_0402"
			(pin_numbers
				(hide yes)
			)
			(pin_names
				(hide yes)
			)
			(exclude_from_sim no)
			(in_bom yes)
			(on_board yes)
			(property "Reference" "R"
				(at 20.32 -5.08 0)
				(effects
					(font
						(size 1.27 1.27)
						(thickness 0.15)
					)
					(justify left bottom)
				)
			)
			(property "Value" "R_33R_0402"
				(at 20.32 -12.7 0)
				(effects
					(font
						(size 1.27 1.27)
						(thickness 0.15)
					)
					(justify left bottom)
					(hide yes)
				)
			)
			(property "Footprint" "antmicro-footprints:R_0402_1005Metric"
				(at 20.32 -15.24 0)
				(effects
					(font
						(size 1.27 1.27)
						(thickness 0.15)
					)
					(justify left bottom)
					(hide yes)
				)
			)
			(property "Datasheet" "https://www.bourns.com/docs/product-datasheets/cr.pdf"
				(at 20.32 -17.78 0)
				(effects
					(font
						(size 1.27 1.27)
						(thickness 0.15)
					)
					(justify left bottom)
					(hide yes)
				)
			)
			(property "Description" "SMD Chip Resistor, 33 ohm, ± 1%, 62.5 mW, 0402 [1005 Metric], Thick Film, General Purpose"
				(at 0 0 0)
				(effects
					(font
						(size 1.27 1.27)
					)
					(hide yes)
				)
			)
			(property "MPN" "CR0402-FX-33R0GLF"
				(at 20.32 -20.32 0)
				(effects
					(font
						(size 1.27 1.27)
						(thickness 0.15)
					)
					(justify left bottom)
					(hide yes)
				)
			)
			(property "Manufacturer" "Bourns"
				(at 20.32 -22.86 0)
				(effects
					(font
						(size 1.27 1.27)
						(thickness 0.15)
					)
					(justify left bottom)
					(hide yes)
				)
			)
			(property "License" "Apache-2.0"
				(at 20.32 -25.4 0)
				(effects
					(font
						(size 1.27 1.27)
						(thickness 0.15)
					)
					(justify left bottom)
					(hide yes)
				)
			)
			(property "Author" "Antmicro"
				(at 20.32 -27.94 0)
				(effects
					(font
						(size 1.27 1.27)
						(thickness 0.15)
					)
					(justify left bottom)
					(hide yes)
				)
			)
			(property "Val" "33R"
				(at 20.32 -7.62 0)
				(effects
					(font
						(size 1.27 1.27)
						(thickness 0.15)
					)
					(justify left bottom)
				)
			)
			(property "Tolerance" "1%"
				(at 20.32 -10.16 0)
				(effects
					(font
						(size 1.27 1.27)
					)
					(justify left bottom)
					(hide yes)
				)
			)
			(property "ki_keywords" "0402, SMT, RESISTOR, PASSIVE"
				(at 0 0 0)
				(effects
					(font
						(size 1.27 1.27)
					)
					(hide yes)
				)
			)
			(symbol "R_33R_0402_0_1"
				(rectangle
					(start 0.635 0.889)
					(end 4.445 -0.889)
					(stroke
						(width 0.254)
						(type default)
					)
					(fill
						(type none)
					)
				)
			)
			(symbol "R_33R_0402_1_1"
				(pin passive line
					(at 0 0 0)
					(length 0.635)
					(name "~"
						(effects
							(font
								(size 1.27 1.27)
							)
						)
					)
					(number "1"
						(effects
							(font
								(size 1.27 1.27)
							)
						)
					)
				)
				(pin passive line
					(at 5.08 0 180)
					(length 0.635)
					(name "~"
						(effects
							(font
								(size 1.27 1.27)
							)
						)
					)
					(number "2"
						(effects
							(font
								(size 1.27 1.27)
							)
						)
					)
				)
			)
		)
	(symbol "antmicroResistors0402:R_40R2_0402"
			(pin_numbers
				(hide yes)
			)
			(pin_names
				(hide yes)
			)
			(exclude_from_sim no)
			(in_bom yes)
			(on_board yes)
			(property "Reference" "R"
				(at 20.32 -5.08 0)
				(effects
					(font
						(size 1.27 1.27)
						(thickness 0.15)
					)
					(justify left bottom)
				)
			)
			(property "Value" "R_40R2_0402"
				(at 20.32 -12.7 0)
				(effects
					(font
						(size 1.27 1.27)
						(thickness 0.15)
					)
					(justify left bottom)
					(hide yes)
				)
			)
			(property "Footprint" "antmicro-footprints:R_0402_1005Metric"
				(at 20.32 -15.24 0)
				(effects
					(font
						(size 1.27 1.27)
						(thickness 0.15)
					)
					(justify left bottom)
					(hide yes)
				)
			)
			(property "Datasheet" "https://www.bourns.com/docs/product-datasheets/cr.pdf"
				(at 20.32 -17.78 0)
				(effects
					(font
						(size 1.27 1.27)
						(thickness 0.15)
					)
					(justify left bottom)
					(hide yes)
				)
			)
			(property "Description" "SMD Chip Resistor, Ceramic, 40.2 ohm, ± 1%, 62.5 mW, 0402 [1005 Metric], Thick Film"
				(at 0 0 0)
				(effects
					(font
						(size 1.27 1.27)
					)
					(hide yes)
				)
			)
			(property "MPN" "CR0402-FX-40R2GLF"
				(at 20.32 -20.32 0)
				(effects
					(font
						(size 1.27 1.27)
						(thickness 0.15)
					)
					(justify left bottom)
					(hide yes)
				)
			)
			(property "Manufacturer" "Bourns"
				(at 20.32 -22.86 0)
				(effects
					(font
						(size 1.27 1.27)
						(thickness 0.15)
					)
					(justify left bottom)
					(hide yes)
				)
			)
			(property "License" "Apache-2.0"
				(at 20.32 -25.4 0)
				(effects
					(font
						(size 1.27 1.27)
						(thickness 0.15)
					)
					(justify left bottom)
					(hide yes)
				)
			)
			(property "Author" "Antmicro"
				(at 20.32 -27.94 0)
				(effects
					(font
						(size 1.27 1.27)
						(thickness 0.15)
					)
					(justify left bottom)
					(hide yes)
				)
			)
			(property "Val" "40R2"
				(at 20.32 -7.62 0)
				(effects
					(font
						(size 1.27 1.27)
						(thickness 0.15)
					)
					(justify left bottom)
				)
			)
			(property "Tolerance" "1%"
				(at 20.32 -10.16 0)
				(effects
					(font
						(size 1.27 1.27)
					)
					(justify left bottom)
					(hide yes)
				)
			)
			(property "ki_keywords" "0402, SMT, RESISTOR, PASSIVE"
				(at 0 0 0)
				(effects
					(font
						(size 1.27 1.27)
					)
					(hide yes)
				)
			)
			(symbol "R_40R2_0402_0_1"
				(rectangle
					(start 0.635 0.889)
					(end 4.445 -0.889)
					(stroke
						(width 0.254)
						(type default)
					)
					(fill
						(type none)
					)
				)
			)
			(symbol "R_40R2_0402_1_1"
				(pin passive line
					(at 0 0 0)
					(length 0.635)
					(name "~"
						(effects
							(font
								(size 1.27 1.27)
							)
						)
					)
					(number "1"
						(effects
							(font
								(size 1.27 1.27)
							)
						)
					)
				)
				(pin passive line
					(at 5.08 0 180)
					(length 0.635)
					(name "~"
						(effects
							(font
								(size 1.27 1.27)
							)
						)
					)
					(number "2"
						(effects
							(font
								(size 1.27 1.27)
							)
						)
					)
				)
			)
		)
	(symbol "antmicroResistors0402:R_47k_0402"
			(pin_numbers
				(hide yes)
			)
			(pin_names
				(hide yes)
			)
			(exclude_from_sim no)
			(in_bom yes)
			(on_board yes)
			(property "Reference" "R"
				(at 20.32 -5.08 0)
				(effects
					(font
						(size 1.27 1.27)
						(thickness 0.15)
					)
					(justify left bottom)
				)
			)
			(property "Value" "R_47k_0402"
				(at 20.32 -12.7 0)
				(effects
					(font
						(size 1.27 1.27)
						(thickness 0.15)
					)
					(justify left bottom)
					(hide yes)
				)
			)
			(property "Footprint" "antmicro-footprints:R_0402_1005Metric"
				(at 20.32 -15.24 0)
				(effects
					(font
						(size 1.27 1.27)
						(thickness 0.15)
					)
					(justify left bottom)
					(hide yes)
				)
			)
			(property "Datasheet" "https://www.bourns.com/docs/product-datasheets/cr.pdf"
				(at 20.32 -17.78 0)
				(effects
					(font
						(size 1.27 1.27)
						(thickness 0.15)
					)
					(justify left bottom)
					(hide yes)
				)
			)
			(property "Description" "SMD Chip Resistor, 47 kohm, ± 1%, 62.5 mW, 0402 [1005 Metric], Thick Film, General Purpose"
				(at 0 0 0)
				(effects
					(font
						(size 1.27 1.27)
					)
					(hide yes)
				)
			)
			(property "MPN" "CR0402-FX-4702GLF"
				(at 20.32 -20.32 0)
				(effects
					(font
						(size 1.27 1.27)
						(thickness 0.15)
					)
					(justify left bottom)
					(hide yes)
				)
			)
			(property "Manufacturer" "Bourns"
				(at 20.32 -22.86 0)
				(effects
					(font
						(size 1.27 1.27)
						(thickness 0.15)
					)
					(justify left bottom)
					(hide yes)
				)
			)
			(property "License" "Apache-2.0"
				(at 20.32 -25.4 0)
				(effects
					(font
						(size 1.27 1.27)
						(thickness 0.15)
					)
					(justify left bottom)
					(hide yes)
				)
			)
			(property "Author" "Antmicro"
				(at 20.32 -27.94 0)
				(effects
					(font
						(size 1.27 1.27)
						(thickness 0.15)
					)
					(justify left bottom)
					(hide yes)
				)
			)
			(property "Val" "47k"
				(at 20.32 -7.62 0)
				(effects
					(font
						(size 1.27 1.27)
						(thickness 0.15)
					)
					(justify left bottom)
				)
			)
			(property "Tolerance" "1%"
				(at 20.32 -10.16 0)
				(effects
					(font
						(size 1.27 1.27)
					)
					(justify left bottom)
					(hide yes)
				)
			)
			(property "ki_keywords" "0402, SMT, RESISTOR, PASSIVE"
				(at 0 0 0)
				(effects
					(font
						(size 1.27 1.27)
					)
					(hide yes)
				)
			)
			(symbol "R_47k_0402_0_1"
				(rectangle
					(start 0.635 0.889)
					(end 4.445 -0.889)
					(stroke
						(width 0.254)
						(type default)
					)
					(fill
						(type none)
					)
				)
			)
			(symbol "R_47k_0402_1_1"
				(pin passive line
					(at 0 0 0)
					(length 0.635)
					(name "~"
						(effects
							(font
								(size 1.27 1.27)
							)
						)
					)
					(number "1"
						(effects
							(font
								(size 1.27 1.27)
							)
						)
					)
				)
				(pin passive line
					(at 5.08 0 180)
					(length 0.635)
					(name "~"
						(effects
							(font
								(size 1.27 1.27)
							)
						)
					)
					(number "2"
						(effects
							(font
								(size 1.27 1.27)
							)
						)
					)
				)
			)
		)
	(symbol "antmicroResistors0402:R_49R9_0402"
			(pin_numbers
				(hide yes)
			)
			(pin_names
				(hide yes)
			)
			(exclude_from_sim no)
			(in_bom yes)
			(on_board yes)
			(property "Reference" "R"
				(at 20.32 -5.08 0)
				(effects
					(font
						(size 1.27 1.27)
						(thickness 0.15)
					)
					(justify left bottom)
				)
			)
			(property "Value" "R_49R9_0402"
				(at 20.32 -12.7 0)
				(effects
					(font
						(size 1.27 1.27)
						(thickness 0.15)
					)
					(justify left bottom)
					(hide yes)
				)
			)
			(property "Footprint" "antmicro-footprints:R_0402_1005Metric"
				(at 20.32 -15.24 0)
				(effects
					(font
						(size 1.27 1.27)
						(thickness 0.15)
					)
					(justify left bottom)
					(hide yes)
				)
			)
			(property "Datasheet" "https://www.bourns.com/docs/product-datasheets/cr.pdf"
				(at 20.32 -17.78 0)
				(effects
					(font
						(size 1.27 1.27)
						(thickness 0.15)
					)
					(justify left bottom)
					(hide yes)
				)
			)
			(property "Description" "SMD Chip Resistor, 49.9 ohm, ± 1%, 62.5 mW, 0402 [1005 Metric], Thick Film, General Purpose"
				(at 0 0 0)
				(effects
					(font
						(size 1.27 1.27)
					)
					(hide yes)
				)
			)
			(property "MPN" "CR0402-FX-49R9GLF"
				(at 20.32 -20.32 0)
				(effects
					(font
						(size 1.27 1.27)
						(thickness 0.15)
					)
					(justify left bottom)
					(hide yes)
				)
			)
			(property "Manufacturer" "Bourns"
				(at 20.32 -22.86 0)
				(effects
					(font
						(size 1.27 1.27)
						(thickness 0.15)
					)
					(justify left bottom)
					(hide yes)
				)
			)
			(property "License" "Apache-2.0"
				(at 20.32 -25.4 0)
				(effects
					(font
						(size 1.27 1.27)
						(thickness 0.15)
					)
					(justify left bottom)
					(hide yes)
				)
			)
			(property "Author" "Antmicro"
				(at 20.32 -27.94 0)
				(effects
					(font
						(size 1.27 1.27)
						(thickness 0.15)
					)
					(justify left bottom)
					(hide yes)
				)
			)
			(property "Val" "49R9"
				(at 20.32 -7.62 0)
				(effects
					(font
						(size 1.27 1.27)
						(thickness 0.15)
					)
					(justify left bottom)
				)
			)
			(property "Tolerance" "1%"
				(at 20.32 -10.16 0)
				(effects
					(font
						(size 1.27 1.27)
					)
					(justify left bottom)
					(hide yes)
				)
			)
			(property "ki_keywords" "0402, SMT, RESISTOR, PASSIVE"
				(at 0 0 0)
				(effects
					(font
						(size 1.27 1.27)
					)
					(hide yes)
				)
			)
			(symbol "R_49R9_0402_0_1"
				(rectangle
					(start 0.635 0.889)
					(end 4.445 -0.889)
					(stroke
						(width 0.254)
						(type default)
					)
					(fill
						(type none)
					)
				)
			)
			(symbol "R_49R9_0402_1_1"
				(pin passive line
					(at 0 0 0)
					(length 0.635)
					(name "~"
						(effects
							(font
								(size 1.27 1.27)
							)
						)
					)
					(number "1"
						(effects
							(font
								(size 1.27 1.27)
							)
						)
					)
				)
				(pin passive line
					(at 5.08 0 180)
					(length 0.635)
					(name "~"
						(effects
							(font
								(size 1.27 1.27)
							)
						)
					)
					(number "2"
						(effects
							(font
								(size 1.27 1.27)
							)
						)
					)
				)
			)
		)
	(symbol "antmicroResistors0402:R_49k9_0402"
			(pin_numbers
				(hide yes)
			)
			(pin_names
				(hide yes)
			)
			(exclude_from_sim no)
			(in_bom yes)
			(on_board yes)
			(property "Reference" "R"
				(at 20.32 -5.08 0)
				(effects
					(font
						(size 1.27 1.27)
						(thickness 0.15)
					)
					(justify left bottom)
				)
			)
			(property "Value" "R_49k9_0402"
				(at 20.32 -12.7 0)
				(effects
					(font
						(size 1.27 1.27)
						(thickness 0.15)
					)
					(justify left bottom)
					(hide yes)
				)
			)
			(property "Footprint" "antmicro-footprints:R_0402_1005Metric"
				(at 20.32 -15.24 0)
				(effects
					(font
						(size 1.27 1.27)
						(thickness 0.15)
					)
					(justify left bottom)
					(hide yes)
				)
			)
			(property "Datasheet" "https://www.bourns.com/docs/product-datasheets/cr.pdf"
				(at 20.32 -17.78 0)
				(effects
					(font
						(size 1.27 1.27)
						(thickness 0.15)
					)
					(justify left bottom)
					(hide yes)
				)
			)
			(property "Description" "SMD Chip Resistor, 49.9 kohm, ± 1%, 63 mW, 0402 [1005 Metric], Thick Film, General Purpose"
				(at 0 0 0)
				(effects
					(font
						(size 1.27 1.27)
					)
					(hide yes)
				)
			)
			(property "MPN" "CR0402-FX-4992GLF"
				(at 20.32 -20.32 0)
				(effects
					(font
						(size 1.27 1.27)
						(thickness 0.15)
					)
					(justify left bottom)
					(hide yes)
				)
			)
			(property "Manufacturer" "Bourns"
				(at 20.32 -22.86 0)
				(effects
					(font
						(size 1.27 1.27)
						(thickness 0.15)
					)
					(justify left bottom)
					(hide yes)
				)
			)
			(property "License" "Apache-2.0"
				(at 20.32 -25.4 0)
				(effects
					(font
						(size 1.27 1.27)
						(thickness 0.15)
					)
					(justify left bottom)
					(hide yes)
				)
			)
			(property "Author" "Antmicro"
				(at 20.32 -27.94 0)
				(effects
					(font
						(size 1.27 1.27)
						(thickness 0.15)
					)
					(justify left bottom)
					(hide yes)
				)
			)
			(property "Val" "49k9"
				(at 20.32 -7.62 0)
				(effects
					(font
						(size 1.27 1.27)
						(thickness 0.15)
					)
					(justify left bottom)
				)
			)
			(property "Tolerance" "1%"
				(at 20.32 -10.16 0)
				(effects
					(font
						(size 1.27 1.27)
					)
					(justify left bottom)
					(hide yes)
				)
			)
			(property "ki_keywords" "0402, SMT, RESISTOR, PASSIVE"
				(at 0 0 0)
				(effects
					(font
						(size 1.27 1.27)
					)
					(hide yes)
				)
			)
			(symbol "R_49k9_0402_0_1"
				(rectangle
					(start 0.635 0.889)
					(end 4.445 -0.889)
					(stroke
						(width 0.254)
						(type default)
					)
					(fill
						(type none)
					)
				)
			)
			(symbol "R_49k9_0402_1_1"
				(pin passive line
					(at 0 0 0)
					(length 0.635)
					(name "~"
						(effects
							(font
								(size 1.27 1.27)
							)
						)
					)
					(number "1"
						(effects
							(font
								(size 1.27 1.27)
							)
						)
					)
				)
				(pin passive line
					(at 5.08 0 180)
					(length 0.635)
					(name "~"
						(effects
							(font
								(size 1.27 1.27)
							)
						)
					)
					(number "2"
						(effects
							(font
								(size 1.27 1.27)
							)
						)
					)
				)
			)
		)
	(symbol "antmicroResistors0402:R_4k7_0402"
			(pin_numbers
				(hide yes)
			)
			(pin_names
				(hide yes)
			)
			(exclude_from_sim no)
			(in_bom yes)
			(on_board yes)
			(property "Reference" "R"
				(at 20.32 -5.08 0)
				(effects
					(font
						(size 1.27 1.27)
						(thickness 0.15)
					)
					(justify left bottom)
				)
			)
			(property "Value" "R_4k7_0402"
				(at 20.32 -12.7 0)
				(effects
					(font
						(size 1.27 1.27)
						(thickness 0.15)
					)
					(justify left bottom)
					(hide yes)
				)
			)
			(property "Footprint" "antmicro-footprints:R_0402_1005Metric"
				(at 20.32 -15.24 0)
				(effects
					(font
						(size 1.27 1.27)
						(thickness 0.15)
					)
					(justify left bottom)
					(hide yes)
				)
			)
			(property "Datasheet" "https://www.bourns.com/docs/product-datasheets/cr.pdf"
				(at 20.32 -17.78 0)
				(effects
					(font
						(size 1.27 1.27)
						(thickness 0.15)
					)
					(justify left bottom)
					(hide yes)
				)
			)
			(property "Description" "SMD Chip Resistor, 4.7 kohm, ± 1%, 62.5 mW, 0402 [1005 Metric], Thick Film, General Purpose"
				(at 0 0 0)
				(effects
					(font
						(size 1.27 1.27)
					)
					(hide yes)
				)
			)
			(property "MPN" "CR0402-FX-4701GLF"
				(at 20.32 -20.32 0)
				(effects
					(font
						(size 1.27 1.27)
						(thickness 0.15)
					)
					(justify left bottom)
					(hide yes)
				)
			)
			(property "Manufacturer" "Bourns"
				(at 20.32 -22.86 0)
				(effects
					(font
						(size 1.27 1.27)
						(thickness 0.15)
					)
					(justify left bottom)
					(hide yes)
				)
			)
			(property "License" "Apache-2.0"
				(at 20.32 -25.4 0)
				(effects
					(font
						(size 1.27 1.27)
						(thickness 0.15)
					)
					(justify left bottom)
					(hide yes)
				)
			)
			(property "Author" "Antmicro"
				(at 20.32 -27.94 0)
				(effects
					(font
						(size 1.27 1.27)
						(thickness 0.15)
					)
					(justify left bottom)
					(hide yes)
				)
			)
			(property "Val" "4k7"
				(at 20.32 -7.62 0)
				(effects
					(font
						(size 1.27 1.27)
						(thickness 0.15)
					)
					(justify left bottom)
				)
			)
			(property "Tolerance" "1%"
				(at 20.32 -10.16 0)
				(effects
					(font
						(size 1.27 1.27)
					)
					(justify left bottom)
					(hide yes)
				)
			)
			(property "ki_keywords" "0402, SMT, RESISTOR, PASSIVE"
				(at 0 0 0)
				(effects
					(font
						(size 1.27 1.27)
					)
					(hide yes)
				)
			)
			(symbol "R_4k7_0402_0_1"
				(rectangle
					(start 0.635 0.889)
					(end 4.445 -0.889)
					(stroke
						(width 0.254)
						(type default)
					)
					(fill
						(type none)
					)
				)
			)
			(symbol "R_4k7_0402_1_1"
				(pin passive line
					(at 0 0 0)
					(length 0.635)
					(name "~"
						(effects
							(font
								(size 1.27 1.27)
							)
						)
					)
					(number "1"
						(effects
							(font
								(size 1.27 1.27)
							)
						)
					)
				)
				(pin passive line
					(at 5.08 0 180)
					(length 0.635)
					(name "~"
						(effects
							(font
								(size 1.27 1.27)
							)
						)
					)
					(number "2"
						(effects
							(font
								(size 1.27 1.27)
							)
						)
					)
				)
			)
		)
	(symbol "antmicroResistors0402:R_5k1_0402"
			(pin_numbers
				(hide yes)
			)
			(pin_names
				(hide yes)
			)
			(exclude_from_sim no)
			(in_bom yes)
			(on_board yes)
			(property "Reference" "R"
				(at 20.32 -5.08 0)
				(effects
					(font
						(size 1.27 1.27)
						(thickness 0.15)
					)
					(justify left bottom)
				)
			)
			(property "Value" "R_5k1_0402"
				(at 20.32 -12.7 0)
				(effects
					(font
						(size 1.27 1.27)
						(thickness 0.15)
					)
					(justify left bottom)
					(hide yes)
				)
			)
			(property "Footprint" "antmicro-footprints:R_0402_1005Metric"
				(at 20.32 -15.24 0)
				(effects
					(font
						(size 1.27 1.27)
						(thickness 0.15)
					)
					(justify left bottom)
					(hide yes)
				)
			)
			(property "Datasheet" "https://www.bourns.com/docs/product-datasheets/cr.pdf"
				(at 20.32 -17.78 0)
				(effects
					(font
						(size 1.27 1.27)
						(thickness 0.15)
					)
					(justify left bottom)
					(hide yes)
				)
			)
			(property "Description" "SMD Chip Resistor, 5.1 kohm, ± 1%, 63 mW, 0402 [1005 Metric], Thick Film, General Purpose"
				(at 0 0 0)
				(effects
					(font
						(size 1.27 1.27)
					)
					(hide yes)
				)
			)
			(property "MPN" "CR0402-FX-5101GLF"
				(at 20.32 -20.32 0)
				(effects
					(font
						(size 1.27 1.27)
						(thickness 0.15)
					)
					(justify left bottom)
					(hide yes)
				)
			)
			(property "Manufacturer" "Bourns"
				(at 20.32 -22.86 0)
				(effects
					(font
						(size 1.27 1.27)
						(thickness 0.15)
					)
					(justify left bottom)
					(hide yes)
				)
			)
			(property "License" "Apache-2.0"
				(at 20.32 -25.4 0)
				(effects
					(font
						(size 1.27 1.27)
						(thickness 0.15)
					)
					(justify left bottom)
					(hide yes)
				)
			)
			(property "Author" "Antmicro"
				(at 20.32 -27.94 0)
				(effects
					(font
						(size 1.27 1.27)
						(thickness 0.15)
					)
					(justify left bottom)
					(hide yes)
				)
			)
			(property "Val" "5k1"
				(at 20.32 -7.62 0)
				(effects
					(font
						(size 1.27 1.27)
						(thickness 0.15)
					)
					(justify left bottom)
				)
			)
			(property "Tolerance" "1%"
				(at 20.32 -10.16 0)
				(effects
					(font
						(size 1.27 1.27)
					)
					(justify left bottom)
					(hide yes)
				)
			)
			(property "ki_keywords" "0402, SMT, RESISTOR, PASSIVE"
				(at 0 0 0)
				(effects
					(font
						(size 1.27 1.27)
					)
					(hide yes)
				)
			)
			(symbol "R_5k1_0402_0_1"
				(rectangle
					(start 0.635 0.889)
					(end 4.445 -0.889)
					(stroke
						(width 0.254)
						(type default)
					)
					(fill
						(type none)
					)
				)
			)
			(symbol "R_5k1_0402_1_1"
				(pin passive line
					(at 0 0 0)
					(length 0.635)
					(name "~"
						(effects
							(font
								(size 1.27 1.27)
							)
						)
					)
					(number "1"
						(effects
							(font
								(size 1.27 1.27)
							)
						)
					)
				)
				(pin passive line
					(at 5.08 0 180)
					(length 0.635)
					(name "~"
						(effects
							(font
								(size 1.27 1.27)
							)
						)
					)
					(number "2"
						(effects
							(font
								(size 1.27 1.27)
							)
						)
					)
				)
			)
		)
	(symbol "antmicroResistors0402:R_80R6_0402_EIA"
			(pin_numbers
				(hide yes)
			)
			(pin_names
				(hide yes)
			)
			(exclude_from_sim no)
			(in_bom yes)
			(on_board yes)
			(property "Reference" "R"
				(at 20.32 -5.08 0)
				(effects
					(font
						(size 1.27 1.27)
						(thickness 0.15)
					)
					(justify left bottom)
				)
			)
			(property "Value" "R_80R6_0402_EIA"
				(at 20.32 -12.7 0)
				(effects
					(font
						(size 1.27 1.27)
						(thickness 0.15)
					)
					(justify left bottom)
					(hide yes)
				)
			)
			(property "Footprint" "antmicro-footprints:R_0402_1005Metric_EIA"
				(at 20.32 -15.24 0)
				(effects
					(font
						(size 1.27 1.27)
						(thickness 0.15)
					)
					(justify left bottom)
					(hide yes)
				)
			)
			(property "Datasheet" "https://www.bourns.com/docs/product-datasheets/cr.pdf"
				(at 20.32 -17.78 0)
				(effects
					(font
						(size 1.27 1.27)
						(thickness 0.15)
					)
					(justify left bottom)
					(hide yes)
				)
			)
			(property "Description" "SMD Chip Resistor, 80.6 ohm, ± 1%, 62.5 mW, 0402 [1005 Metric], Thick Film, General Purpose"
				(at 0 0 0)
				(effects
					(font
						(size 1.27 1.27)
					)
					(hide yes)
				)
			)
			(property "MPN" "MC00625W0402180R6"
				(at 20.32 -20.32 0)
				(effects
					(font
						(size 1.27 1.27)
						(thickness 0.15)
					)
					(justify left bottom)
					(hide yes)
				)
			)
			(property "Manufacturer" "Multicomp Pro"
				(at 20.32 -22.86 0)
				(effects
					(font
						(size 1.27 1.27)
						(thickness 0.15)
					)
					(justify left bottom)
					(hide yes)
				)
			)
			(property "License" "Apache-2.0"
				(at 20.32 -25.4 0)
				(effects
					(font
						(size 1.27 1.27)
						(thickness 0.15)
					)
					(justify left bottom)
					(hide yes)
				)
			)
			(property "Author" "Antmicro"
				(at 20.32 -27.94 0)
				(effects
					(font
						(size 1.27 1.27)
						(thickness 0.15)
					)
					(justify left bottom)
					(hide yes)
				)
			)
			(property "Val" "80R6"
				(at 20.32 -7.62 0)
				(effects
					(font
						(size 1.27 1.27)
						(thickness 0.15)
					)
					(justify left bottom)
				)
			)
			(property "Tolerance" "1%"
				(at 20.32 -10.16 0)
				(effects
					(font
						(size 1.27 1.27)
					)
					(justify left bottom)
					(hide yes)
				)
			)
			(symbol "R_80R6_0402_EIA_0_1"
				(rectangle
					(start 0.635 0.889)
					(end 4.445 -0.889)
					(stroke
						(width 0.254)
						(type default)
					)
					(fill
						(type none)
					)
				)
			)
			(symbol "R_80R6_0402_EIA_1_1"
				(pin passive line
					(at 0 0 0)
					(length 0.635)
					(name "~"
						(effects
							(font
								(size 1.27 1.27)
							)
						)
					)
					(number "1"
						(effects
							(font
								(size 1.27 1.27)
							)
						)
					)
				)
				(pin passive line
					(at 5.08 0 180)
					(length 0.635)
					(name "~"
						(effects
							(font
								(size 1.27 1.27)
							)
						)
					)
					(number "2"
						(effects
							(font
								(size 1.27 1.27)
							)
						)
					)
				)
			)
		)
	(symbol "antmicroResistors0402:R_80k6_0402"
			(pin_numbers
				(hide yes)
			)
			(pin_names
				(hide yes)
			)
			(exclude_from_sim no)
			(in_bom yes)
			(on_board yes)
			(property "Reference" "R"
				(at 20.32 -5.08 0)
				(effects
					(font
						(size 1.27 1.27)
						(thickness 0.15)
					)
					(justify left bottom)
				)
			)
			(property "Value" "R_80k6_0402"
				(at 20.32 -12.7 0)
				(effects
					(font
						(size 1.27 1.27)
						(thickness 0.15)
					)
					(justify left bottom)
					(hide yes)
				)
			)
			(property "Footprint" "antmicro-footprints:R_0402_1005Metric"
				(at 20.32 -15.24 0)
				(effects
					(font
						(size 1.27 1.27)
						(thickness 0.15)
					)
					(justify left bottom)
					(hide yes)
				)
			)
			(property "Datasheet" "https://www.bourns.com/docs/product-datasheets/cr.pdf"
				(at 20.32 -17.78 0)
				(effects
					(font
						(size 1.27 1.27)
						(thickness 0.15)
					)
					(justify left bottom)
					(hide yes)
				)
			)
			(property "Description" "SMD Chip Resistor, 80.6 kohm, ± 1%, 100 mW, 0402 [1005 Metric], Thick Film, Precision"
				(at 0 0 0)
				(effects
					(font
						(size 1.27 1.27)
					)
					(hide yes)
				)
			)
			(property "MPN" "CR0402-FX-8062GLF"
				(at 20.32 -20.32 0)
				(effects
					(font
						(size 1.27 1.27)
						(thickness 0.15)
					)
					(justify left bottom)
					(hide yes)
				)
			)
			(property "Manufacturer" "Bourns"
				(at 20.32 -22.86 0)
				(effects
					(font
						(size 1.27 1.27)
						(thickness 0.15)
					)
					(justify left bottom)
					(hide yes)
				)
			)
			(property "License" "Apache-2.0"
				(at 20.32 -25.4 0)
				(effects
					(font
						(size 1.27 1.27)
						(thickness 0.15)
					)
					(justify left bottom)
					(hide yes)
				)
			)
			(property "Author" "Antmicro"
				(at 20.32 -27.94 0)
				(effects
					(font
						(size 1.27 1.27)
						(thickness 0.15)
					)
					(justify left bottom)
					(hide yes)
				)
			)
			(property "Val" "80k6"
				(at 20.32 -7.62 0)
				(effects
					(font
						(size 1.27 1.27)
						(thickness 0.15)
					)
					(justify left bottom)
				)
			)
			(property "Tolerance" "1%"
				(at 20.32 -10.16 0)
				(effects
					(font
						(size 1.27 1.27)
					)
					(justify left bottom)
					(hide yes)
				)
			)
			(property "ki_keywords" "0402, SMT, RESISTOR, PASSIVE"
				(at 0 0 0)
				(effects
					(font
						(size 1.27 1.27)
					)
					(hide yes)
				)
			)
			(symbol "R_80k6_0402_0_1"
				(rectangle
					(start 0.635 0.889)
					(end 4.445 -0.889)
					(stroke
						(width 0.254)
						(type default)
					)
					(fill
						(type none)
					)
				)
			)
			(symbol "R_80k6_0402_1_1"
				(pin passive line
					(at 0 0 0)
					(length 0.635)
					(name "~"
						(effects
							(font
								(size 1.27 1.27)
							)
						)
					)
					(number "1"
						(effects
							(font
								(size 1.27 1.27)
							)
						)
					)
				)
				(pin passive line
					(at 5.08 0 180)
					(length 0.635)
					(name "~"
						(effects
							(font
								(size 1.27 1.27)
							)
						)
					)
					(number "2"
						(effects
							(font
								(size 1.27 1.27)
							)
						)
					)
				)
			)
		)
	(symbol "antmicroResistors0603:R_0R_22.4A_0603"
			(pin_numbers
				(hide yes)
			)
			(pin_names
				(hide yes)
			)
			(exclude_from_sim no)
			(in_bom yes)
			(on_board yes)
			(property "Reference" "R"
				(at 15.24 -2.54 0)
				(effects
					(font
						(size 1.27 1.27)
						(thickness 0.15)
					)
					(justify left bottom)
				)
			)
			(property "Value" "R_0R_22.4A_0603"
				(at 15.24 -5.08 0)
				(effects
					(font
						(size 1.27 1.27)
						(thickness 0.15)
					)
					(justify left bottom)
				)
			)
			(property "Footprint" "antmicro-footprints:R_0603_1608Metric"
				(at 15.24 -10.16 0)
				(effects
					(font
						(size 1.27 1.27)
						(thickness 0.15)
					)
					(justify left bottom)
					(hide yes)
				)
			)
			(property "Datasheet" "https://fscdn.rohm.com/en/products/databook/datasheet/passive/resistor/chip_resistor/pmr-jpw-e.pdf"
				(at 15.24 -12.7 0)
				(effects
					(font
						(size 1.27 1.27)
						(thickness 0.15)
					)
					(justify left bottom)
					(hide yes)
				)
			)
			(property "Description" "SMD Chip Resistor"
				(at 0 0 0)
				(effects
					(font
						(size 1.27 1.27)
					)
					(hide yes)
				)
			)
			(property "MPN" "PMR03EZPJ000"
				(at 15.24 -15.24 0)
				(effects
					(font
						(size 1.27 1.27)
						(thickness 0.15)
					)
					(justify left bottom)
					(hide yes)
				)
			)
			(property "Manufacturer" "ROHM Semiconductor"
				(at 15.24 -17.78 0)
				(effects
					(font
						(size 1.27 1.27)
						(thickness 0.15)
					)
					(justify left bottom)
					(hide yes)
				)
			)
			(property "Val" "0R"
				(at 15.24 -7.62 0)
				(effects
					(font
						(size 1.27 1.27)
						(thickness 0.15)
					)
					(justify left bottom)
				)
			)
			(property "Max. Curr." "22.4A"
				(at 15.24 -20.32 0)
				(effects
					(font
						(size 1.27 1.27)
						(thickness 0.15)
					)
					(justify left bottom)
				)
			)
			(property "Author" "Antmicro"
				(at 15.24 -22.86 0)
				(effects
					(font
						(size 1.27 1.27)
						(thickness 0.15)
					)
					(justify left bottom)
					(hide yes)
				)
			)
			(property "License" "Apache-2.0"
				(at 15.24 -25.4 0)
				(effects
					(font
						(size 1.27 1.27)
						(thickness 0.15)
					)
					(justify left bottom)
					(hide yes)
				)
			)
			(property "Tolerance" "template_tolerance"
				(at 20.32 -10.16 0)
				(effects
					(font
						(size 1.27 1.27)
					)
					(justify left bottom)
					(hide yes)
				)
			)
			(property "ki_keywords" "0603, SMT, RESISTOR, PASSIVE"
				(at 0 0 0)
				(effects
					(font
						(size 1.27 1.27)
					)
					(hide yes)
				)
			)
			(symbol "R_0R_22.4A_0603_0_1"
				(rectangle
					(start 0.635 0.889)
					(end 4.445 -0.889)
					(stroke
						(width 0.254)
						(type default)
					)
					(fill
						(type none)
					)
				)
			)
			(symbol "R_0R_22.4A_0603_1_1"
				(pin passive line
					(at 0 0 0)
					(length 0.635)
					(name "~"
						(effects
							(font
								(size 1.27 1.27)
							)
						)
					)
					(number "1"
						(effects
							(font
								(size 1.27 1.27)
							)
						)
					)
				)
				(pin passive line
					(at 5.08 0 180)
					(length 0.635)
					(name "~"
						(effects
							(font
								(size 1.27 1.27)
							)
						)
					)
					(number "2"
						(effects
							(font
								(size 1.27 1.27)
							)
						)
					)
				)
			)
		)
	(symbol "antmicroResistors0603:R_220R_0603"
			(pin_numbers
				(hide yes)
			)
			(pin_names
				(hide yes)
			)
			(exclude_from_sim no)
			(in_bom yes)
			(on_board yes)
			(property "Reference" "R"
				(at 20.32 -5.08 0)
				(effects
					(font
						(size 1.27 1.27)
						(thickness 0.15)
					)
					(justify left bottom)
				)
			)
			(property "Value" "R_220R_0603"
				(at 20.32 -12.7 0)
				(effects
					(font
						(size 1.27 1.27)
						(thickness 0.15)
					)
					(justify left bottom)
					(hide yes)
				)
			)
			(property "Footprint" "antmicro-footprints:R_0603_1608Metric"
				(at 20.32 -15.24 0)
				(effects
					(font
						(size 1.27 1.27)
						(thickness 0.15)
					)
					(justify left bottom)
					(hide yes)
				)
			)
			(property "Datasheet" "https://www.bourns.com/docs/product-datasheets/cr.pdf"
				(at 20.32 -17.78 0)
				(effects
					(font
						(size 1.27 1.27)
						(thickness 0.15)
					)
					(justify left bottom)
					(hide yes)
				)
			)
			(property "Description" "SMD Chip Resistor, 220 ohm, ± 1%, 100 mW, 0603 [1608 Metric], Thick Film, General Purpose"
				(at 0 0 0)
				(effects
					(font
						(size 1.27 1.27)
					)
					(hide yes)
				)
			)
			(property "MPN" "CR0603-FX-2200ELF"
				(at 20.32 -20.32 0)
				(effects
					(font
						(size 1.27 1.27)
						(thickness 0.15)
					)
					(justify left bottom)
					(hide yes)
				)
			)
			(property "Manufacturer" "Bourns"
				(at 20.32 -22.86 0)
				(effects
					(font
						(size 1.27 1.27)
						(thickness 0.15)
					)
					(justify left bottom)
					(hide yes)
				)
			)
			(property "License" "Apache-2.0"
				(at 20.32 -25.4 0)
				(effects
					(font
						(size 1.27 1.27)
						(thickness 0.15)
					)
					(justify left bottom)
					(hide yes)
				)
			)
			(property "Author" "Antmicro"
				(at 20.32 -27.94 0)
				(effects
					(font
						(size 1.27 1.27)
						(thickness 0.15)
					)
					(justify left bottom)
					(hide yes)
				)
			)
			(property "Val" "220R"
				(at 20.32 -7.62 0)
				(effects
					(font
						(size 1.27 1.27)
						(thickness 0.15)
					)
					(justify left bottom)
				)
			)
			(property "Tolerance" "1%"
				(at 20.32 -10.16 0)
				(effects
					(font
						(size 1.27 1.27)
					)
					(justify left bottom)
					(hide yes)
				)
			)
			(property "ki_keywords" "0603, SMT, RESISTOR, PASSIVE"
				(at 0 0 0)
				(effects
					(font
						(size 1.27 1.27)
					)
					(hide yes)
				)
			)
			(symbol "R_220R_0603_0_1"
				(rectangle
					(start 0.635 0.889)
					(end 4.445 -0.889)
					(stroke
						(width 0.254)
						(type default)
					)
					(fill
						(type none)
					)
				)
			)
			(symbol "R_220R_0603_1_1"
				(pin passive line
					(at 0 0 0)
					(length 0.635)
					(name "~"
						(effects
							(font
								(size 1.27 1.27)
							)
						)
					)
					(number "1"
						(effects
							(font
								(size 1.27 1.27)
							)
						)
					)
				)
				(pin passive line
					(at 5.08 0 180)
					(length 0.635)
					(name "~"
						(effects
							(font
								(size 1.27 1.27)
							)
						)
					)
					(number "2"
						(effects
							(font
								(size 1.27 1.27)
							)
						)
					)
				)
			)
		)
	(symbol "antmicroResistors0603:R_63R4_0603"
			(pin_numbers
				(hide yes)
			)
			(pin_names
				(hide yes)
			)
			(exclude_from_sim no)
			(in_bom yes)
			(on_board yes)
			(property "Reference" "R"
				(at 20.32 -5.08 0)
				(effects
					(font
						(size 1.27 1.27)
						(thickness 0.15)
					)
					(justify left bottom)
				)
			)
			(property "Value" "R_63R4_0603"
				(at 20.32 -12.7 0)
				(effects
					(font
						(size 1.27 1.27)
						(thickness 0.15)
					)
					(justify left bottom)
					(hide yes)
				)
			)
			(property "Footprint" "antmicro-footprints:R_0603_1608Metric"
				(at 20.32 -15.24 0)
				(effects
					(font
						(size 1.27 1.27)
						(thickness 0.15)
					)
					(justify left bottom)
					(hide yes)
				)
			)
			(property "Datasheet" "https://www.bourns.com/docs/product-datasheets/cr.pdf"
				(at 20.32 -17.78 0)
				(effects
					(font
						(size 1.27 1.27)
						(thickness 0.15)
					)
					(justify left bottom)
					(hide yes)
				)
			)
			(property "Description" "SMD Chip Resistor"
				(at 0 0 0)
				(effects
					(font
						(size 1.27 1.27)
					)
					(hide yes)
				)
			)
			(property "MPN" "CR0603-FX-63R4ELF"
				(at 20.32 -20.32 0)
				(effects
					(font
						(size 1.27 1.27)
						(thickness 0.15)
					)
					(justify left bottom)
					(hide yes)
				)
			)
			(property "Manufacturer" "Bourns"
				(at 20.32 -22.86 0)
				(effects
					(font
						(size 1.27 1.27)
						(thickness 0.15)
					)
					(justify left bottom)
					(hide yes)
				)
			)
			(property "License" "Apache-2.0"
				(at 20.32 -25.4 0)
				(effects
					(font
						(size 1.27 1.27)
						(thickness 0.15)
					)
					(justify left bottom)
					(hide yes)
				)
			)
			(property "Author" "Antmicro"
				(at 20.32 -27.94 0)
				(effects
					(font
						(size 1.27 1.27)
						(thickness 0.15)
					)
					(justify left bottom)
					(hide yes)
				)
			)
			(property "Val" "63R4"
				(at 20.32 -7.62 0)
				(effects
					(font
						(size 1.27 1.27)
						(thickness 0.15)
					)
					(justify left bottom)
				)
			)
			(property "Tolerance" "1%"
				(at 20.32 -10.16 0)
				(effects
					(font
						(size 1.27 1.27)
					)
					(justify left bottom)
					(hide yes)
				)
			)
			(property "ki_keywords" "0603, SMT, RESISTOR, PASSIVE"
				(at 0 0 0)
				(effects
					(font
						(size 1.27 1.27)
					)
					(hide yes)
				)
			)
			(symbol "R_63R4_0603_0_1"
				(rectangle
					(start 0.635 0.889)
					(end 4.445 -0.889)
					(stroke
						(width 0.254)
						(type default)
					)
					(fill
						(type none)
					)
				)
			)
			(symbol "R_63R4_0603_1_1"
				(pin passive line
					(at 0 0 0)
					(length 0.635)
					(name "~"
						(effects
							(font
								(size 1.27 1.27)
							)
						)
					)
					(number "1"
						(effects
							(font
								(size 1.27 1.27)
							)
						)
					)
				)
				(pin passive line
					(at 5.08 0 180)
					(length 0.635)
					(name "~"
						(effects
							(font
								(size 1.27 1.27)
							)
						)
					)
					(number "2"
						(effects
							(font
								(size 1.27 1.27)
							)
						)
					)
				)
			)
		)
	(symbol "antmicroResistorsmisc:R_1k3_1206"
			(pin_numbers
				(hide yes)
			)
			(pin_names
				(hide yes)
			)
			(exclude_from_sim no)
			(in_bom yes)
			(on_board yes)
			(property "Reference" "R"
				(at 20.32 -5.08 0)
				(effects
					(font
						(size 1.27 1.27)
						(thickness 0.15)
					)
					(justify left bottom)
				)
			)
			(property "Value" "R_1k3_1206"
				(at 20.32 -12.7 0)
				(effects
					(font
						(size 1.27 1.27)
						(thickness 0.15)
					)
					(justify left bottom)
					(hide yes)
				)
			)
			(property "Footprint" "antmicro-footprints:R_1206_3216Metric"
				(at 20.32 -15.24 0)
				(effects
					(font
						(size 1.27 1.27)
						(thickness 0.15)
					)
					(justify left bottom)
					(hide yes)
				)
			)
			(property "Datasheet" "https://www.bourns.com/docs/product-datasheets/cr.pdf"
				(at 20.32 -17.78 0)
				(effects
					(font
						(size 1.27 1.27)
						(thickness 0.15)
					)
					(justify left bottom)
					(hide yes)
				)
			)
			(property "Description" "SMT Chip Resistor, 1.3 kohm, ± 1%, 250 mW, 1206 [3216 Metric], Thick Film, General Purpose"
				(at 0 0 0)
				(effects
					(font
						(size 1.27 1.27)
					)
					(hide yes)
				)
			)
			(property "MPN" "CR1206-JW-132ELF"
				(at 20.32 -20.32 0)
				(effects
					(font
						(size 1.27 1.27)
						(thickness 0.15)
					)
					(justify left bottom)
					(hide yes)
				)
			)
			(property "Manufacturer" "Bourns"
				(at 20.32 -22.86 0)
				(effects
					(font
						(size 1.27 1.27)
						(thickness 0.15)
					)
					(justify left bottom)
					(hide yes)
				)
			)
			(property "License" "Apache-2.0"
				(at 20.32 -25.4 0)
				(effects
					(font
						(size 1.27 1.27)
						(thickness 0.15)
					)
					(justify left bottom)
					(hide yes)
				)
			)
			(property "Author" "Antmicro"
				(at 20.32 -27.94 0)
				(effects
					(font
						(size 1.27 1.27)
						(thickness 0.15)
					)
					(justify left bottom)
					(hide yes)
				)
			)
			(property "Val" "1k3"
				(at 20.32 -7.62 0)
				(effects
					(font
						(size 1.27 1.27)
						(thickness 0.15)
					)
					(justify left bottom)
				)
			)
			(property "Tolerance" "1%"
				(at 20.32 -10.16 0)
				(effects
					(font
						(size 1.27 1.27)
					)
					(justify left bottom)
					(hide yes)
				)
			)
			(property "ki_keywords" "1206, SMT, RESISTOR, PASSIVE"
				(at 0 0 0)
				(effects
					(font
						(size 1.27 1.27)
					)
					(hide yes)
				)
			)
			(symbol "R_1k3_1206_0_1"
				(rectangle
					(start 0.635 0.889)
					(end 4.445 -0.889)
					(stroke
						(width 0.254)
						(type default)
					)
					(fill
						(type none)
					)
				)
			)
			(symbol "R_1k3_1206_1_1"
				(pin passive line
					(at 0 0 0)
					(length 0.635)
					(name "~"
						(effects
							(font
								(size 1.27 1.27)
							)
						)
					)
					(number "1"
						(effects
							(font
								(size 1.27 1.27)
							)
						)
					)
				)
				(pin passive line
					(at 5.08 0 180)
					(length 0.635)
					(name "~"
						(effects
							(font
								(size 1.27 1.27)
							)
						)
					)
					(number "2"
						(effects
							(font
								(size 1.27 1.27)
							)
						)
					)
				)
			)
		)
	(symbol "antmicroResonators:Resonator_12MHz_ABM8G"
			(pin_names
				(hide yes)
			)
			(exclude_from_sim no)
			(in_bom yes)
			(on_board yes)
			(property "Reference" "Y"
				(at 15.24 -5.08 0)
				(effects
					(font
						(size 1.27 1.27)
						(thickness 0.15)
					)
					(justify left bottom)
				)
			)
			(property "Value" "Resonator_12MHz_ABM8G"
				(at 15.24 -12.7 0)
				(effects
					(font
						(size 1.27 1.27)
						(thickness 0.15)
					)
					(justify left bottom)
					(hide yes)
				)
			)
			(property "Footprint" "antmicro-footprints:Resonator_SMD_Abracon_ABM8G_3.2x2.5mm"
				(at 15.24 -15.24 0)
				(effects
					(font
						(size 1.27 1.27)
						(thickness 0.15)
					)
					(justify left bottom)
					(hide yes)
				)
			)
			(property "Datasheet" "https://abracon.com/Resonators/ABM8G.pdf"
				(at 15.24 -17.78 0)
				(effects
					(font
						(size 1.27 1.27)
						(thickness 0.15)
					)
					(justify left bottom)
					(hide yes)
				)
			)
			(property "Description" "Crystal, 12 MHz, SMT, 3.2mm x 2.5mm, 30 ppm, 18 pF, 20 ppm, ABM8G"
				(at 0 0 0)
				(effects
					(font
						(size 1.27 1.27)
					)
					(hide yes)
				)
			)
			(property "MPN" "ABM8G-12.000MHZ-18-D2Y-T"
				(at 15.24 -7.62 0)
				(effects
					(font
						(size 1.27 1.27)
						(thickness 0.15)
					)
					(justify left bottom)
					(hide yes)
				)
			)
			(property "Manufacturer" "Abracon"
				(at 15.24 -20.32 0)
				(effects
					(font
						(size 1.27 1.27)
						(thickness 0.15)
					)
					(justify left bottom)
					(hide yes)
				)
			)
			(property "Author" "Antmicro"
				(at 15.24 -22.86 0)
				(effects
					(font
						(size 1.27 1.27)
						(thickness 0.15)
					)
					(justify left bottom)
					(hide yes)
				)
			)
			(property "License" "Apache-2.0"
				(at 15.24 -25.4 0)
				(effects
					(font
						(size 1.27 1.27)
						(thickness 0.15)
					)
					(justify left bottom)
					(hide yes)
				)
			)
			(property "Val" "12 MHz"
				(at 15.24 -10.16 0)
				(effects
					(font
						(size 1.27 1.27)
						(thickness 0.15)
					)
					(justify left bottom)
				)
			)
			(property "ki_keywords" "SMT, CERAMIC, OSCILLATOR"
				(at 0 0 0)
				(effects
					(font
						(size 1.27 1.27)
					)
					(hide yes)
				)
			)
			(symbol "Resonator_12MHz_ABM8G_1_1"
				(polyline
					(pts
						(xy 1.905 1.905) (xy 1.905 2.54) (xy 5.715 2.54) (xy 5.715 1.905)
					)
					(stroke
						(width 0.254)
						(type default)
					)
					(fill
						(type none)
					)
				)
				(polyline
					(pts
						(xy 1.905 -1.905) (xy 1.905 -2.54) (xy 5.715 -2.54) (xy 5.715 -1.905)
					)
					(stroke
						(width 0.254)
						(type default)
					)
					(fill
						(type none)
					)
				)
				(polyline
					(pts
						(xy 2.54 1.27) (xy 2.54 -1.27)
					)
					(stroke
						(width 0.254)
						(type default)
					)
					(fill
						(type background)
					)
				)
				(rectangle
					(start 3.175 1.905)
					(end 4.445 -1.905)
					(stroke
						(width 0.254)
						(type default)
					)
					(fill
						(type background)
					)
				)
				(polyline
					(pts
						(xy 5.08 1.27) (xy 5.08 -1.27)
					)
					(stroke
						(width 0.254)
						(type default)
					)
					(fill
						(type background)
					)
				)
				(pin passive line
					(at 0 0 0)
					(length 2.54)
					(name "~"
						(effects
							(font
								(size 1.27 1.27)
							)
						)
					)
					(number "1"
						(effects
							(font
								(size 1.27 1.27)
							)
						)
					)
				)
				(pin passive line
					(at 3.81 -5.08 90)
					(length 2.54)
					(name "SH"
						(effects
							(font
								(size 1.27 1.27)
							)
						)
					)
					(number "2"
						(effects
							(font
								(size 1.27 1.27)
							)
						)
					)
				)
				(pin passive line
					(at 3.81 -5.08 90)
					(length 2.54)
					(hide yes)
					(name "SH"
						(effects
							(font
								(size 1.27 1.27)
							)
						)
					)
					(number "4"
						(effects
							(font
								(size 1.27 1.27)
							)
						)
					)
				)
				(pin passive line
					(at 7.62 0 180)
					(length 2.54)
					(name "~"
						(effects
							(font
								(size 1.27 1.27)
							)
						)
					)
					(number "3"
						(effects
							(font
								(size 1.27 1.27)
							)
						)
					)
				)
			)
		)
	(symbol "antmicroResonators:Resonator_25MHz_ABM8G"
			(pin_names
				(hide yes)
			)
			(exclude_from_sim no)
			(in_bom yes)
			(on_board yes)
			(property "Reference" "Y"
				(at 15.24 -5.08 0)
				(effects
					(font
						(size 1.27 1.27)
						(thickness 0.15)
					)
					(justify left bottom)
				)
			)
			(property "Value" "Resonator_25MHz_ABM8G"
				(at 15.24 -12.7 0)
				(effects
					(font
						(size 1.27 1.27)
						(thickness 0.15)
					)
					(justify left bottom)
					(hide yes)
				)
			)
			(property "Footprint" "antmicro-footprints:Resonator_SMD_Abracon_ABM8G_3.2x2.5mm"
				(at 15.24 -15.24 0)
				(effects
					(font
						(size 1.27 1.27)
						(thickness 0.15)
					)
					(justify left bottom)
					(hide yes)
				)
			)
			(property "Datasheet" "https://abracon.com/Resonators/ABM8G.pdf"
				(at 15.24 -17.78 0)
				(effects
					(font
						(size 1.27 1.27)
						(thickness 0.15)
					)
					(justify left bottom)
					(hide yes)
				)
			)
			(property "Description" "Crystal, 25 MHz, SMD, 3.2mm x 2.5mm, 30 ppm, 18 pF, 20 ppm, ABM8G"
				(at 0 0 0)
				(effects
					(font
						(size 1.27 1.27)
					)
					(hide yes)
				)
			)
			(property "MPN" "ABM8G-25.000MHZ-18-D2Y-T3"
				(at 15.24 -7.62 0)
				(effects
					(font
						(size 1.27 1.27)
						(thickness 0.15)
					)
					(justify left bottom)
					(hide yes)
				)
			)
			(property "Manufacturer" "Abracon"
				(at 15.24 -20.32 0)
				(effects
					(font
						(size 1.27 1.27)
						(thickness 0.15)
					)
					(justify left bottom)
					(hide yes)
				)
			)
			(property "Author" "Antmicro"
				(at 15.24 -22.86 0)
				(effects
					(font
						(size 1.27 1.27)
						(thickness 0.15)
					)
					(justify left bottom)
					(hide yes)
				)
			)
			(property "License" "Apache-2.0"
				(at 15.24 -25.4 0)
				(effects
					(font
						(size 1.27 1.27)
						(thickness 0.15)
					)
					(justify left bottom)
					(hide yes)
				)
			)
			(property "Val" "25 MHz"
				(at 15.24 -10.16 0)
				(effects
					(font
						(size 1.27 1.27)
						(thickness 0.15)
					)
					(justify left bottom)
				)
			)
			(property "ki_keywords" "SMT, CERAMIC, OSCILLATOR"
				(at 0 0 0)
				(effects
					(font
						(size 1.27 1.27)
					)
					(hide yes)
				)
			)
			(symbol "Resonator_25MHz_ABM8G_1_1"
				(polyline
					(pts
						(xy 1.905 1.905) (xy 1.905 2.54) (xy 5.715 2.54) (xy 5.715 1.905)
					)
					(stroke
						(width 0.254)
						(type default)
					)
					(fill
						(type none)
					)
				)
				(polyline
					(pts
						(xy 1.905 -1.905) (xy 1.905 -2.54) (xy 5.715 -2.54) (xy 5.715 -1.905)
					)
					(stroke
						(width 0.254)
						(type default)
					)
					(fill
						(type none)
					)
				)
				(polyline
					(pts
						(xy 2.54 1.27) (xy 2.54 -1.27)
					)
					(stroke
						(width 0.254)
						(type default)
					)
					(fill
						(type background)
					)
				)
				(rectangle
					(start 3.175 1.905)
					(end 4.445 -1.905)
					(stroke
						(width 0.254)
						(type default)
					)
					(fill
						(type background)
					)
				)
				(polyline
					(pts
						(xy 5.08 1.27) (xy 5.08 -1.27)
					)
					(stroke
						(width 0.254)
						(type default)
					)
					(fill
						(type background)
					)
				)
				(pin passive line
					(at 0 0 0)
					(length 2.54)
					(name "~"
						(effects
							(font
								(size 1.27 1.27)
							)
						)
					)
					(number "1"
						(effects
							(font
								(size 1.27 1.27)
							)
						)
					)
				)
				(pin passive line
					(at 3.81 -5.08 90)
					(length 2.54)
					(name "SH"
						(effects
							(font
								(size 1.27 1.27)
							)
						)
					)
					(number "2"
						(effects
							(font
								(size 1.27 1.27)
							)
						)
					)
				)
				(pin passive line
					(at 3.81 -5.08 90)
					(length 2.54)
					(hide yes)
					(name "SH"
						(effects
							(font
								(size 1.27 1.27)
							)
						)
					)
					(number "4"
						(effects
							(font
								(size 1.27 1.27)
							)
						)
					)
				)
				(pin passive line
					(at 7.62 0 180)
					(length 2.54)
					(name "~"
						(effects
							(font
								(size 1.27 1.27)
							)
						)
					)
					(number "3"
						(effects
							(font
								(size 1.27 1.27)
							)
						)
					)
				)
			)
		)
	(symbol "antmicroSlideSwitches:CVS-03B"
			(pin_names
				(hide yes)
			)
			(exclude_from_sim no)
			(in_bom yes)
			(on_board yes)
			(property "Reference" "SW"
				(at 26.67 -2.54 0)
				(effects
					(font
						(size 1.27 1.27)
						(thickness 0.15)
					)
					(justify left bottom)
				)
			)
			(property "Value" "CVS-03B"
				(at 26.67 -5.08 0)
				(effects
					(font
						(size 1.27 1.27)
						(thickness 0.15)
					)
					(justify left bottom)
				)
			)
			(property "Footprint" "antmicro-footprints:SW_DIP_SPSTx03_Slide_Copal_CVS-03xB_W5.9mm_P1mm"
				(at 26.67 -7.62 0)
				(effects
					(font
						(size 1.27 1.27)
						(thickness 0.15)
					)
					(justify left bottom)
					(hide yes)
				)
			)
			(property "Datasheet" "https://www.mouser.com/datasheet/2/972/cvs-1827291.pdf"
				(at 26.67 -10.16 0)
				(effects
					(font
						(size 1.27 1.27)
						(thickness 0.15)
					)
					(justify left bottom)
					(hide yes)
				)
			)
			(property "Description" "Slide switch"
				(at 0 0 0)
				(effects
					(font
						(size 1.27 1.27)
					)
					(hide yes)
				)
			)
			(property "MPN" "CVS-03B"
				(at 26.67 -12.7 0)
				(effects
					(font
						(size 1.27 1.27)
						(thickness 0.15)
					)
					(justify left bottom)
					(hide yes)
				)
			)
			(property "Manufacturer" "Nidec Components"
				(at 26.67 -15.24 0)
				(effects
					(font
						(size 1.27 1.27)
						(thickness 0.15)
					)
					(justify left bottom)
					(hide yes)
				)
			)
			(property "Author" "Antmicro"
				(at 26.67 -17.78 0)
				(effects
					(font
						(size 1.27 1.27)
						(thickness 0.15)
					)
					(justify left bottom)
					(hide yes)
				)
			)
			(property "License" "Apache-2.0"
				(at 26.67 -20.32 0)
				(effects
					(font
						(size 1.27 1.27)
						(thickness 0.15)
					)
					(justify left bottom)
					(hide yes)
				)
			)
			(property "ki_keywords" "HORIZONTAL, SMT, SWITCH, MECHANICAL"
				(at 0 0 0)
				(effects
					(font
						(size 1.27 1.27)
					)
					(hide yes)
				)
			)
			(property "ki_fp_filters" "SW?DIP?x2*"
				(at 0 0 0)
				(effects
					(font
						(size 1.27 1.27)
					)
					(hide yes)
				)
			)
			(symbol "CVS-03B_1_1"
				(rectangle
					(start 2.54 2.54)
					(end 10.16 -8.89)
					(stroke
						(width 0.254)
						(type default)
					)
					(fill
						(type background)
					)
				)
				(polyline
					(pts
						(xy 3.81 0) (xy 2.54 0)
					)
					(stroke
						(width 0.254)
						(type default)
					)
					(fill
						(type none)
					)
				)
				(polyline
					(pts
						(xy 3.81 -2.54) (xy 2.54 -2.54)
					)
					(stroke
						(width 0.254)
						(type default)
					)
					(fill
						(type none)
					)
				)
				(polyline
					(pts
						(xy 3.827 -5.0976) (xy 2.557 -5.0976)
					)
					(stroke
						(width 0.254)
						(type default)
					)
					(fill
						(type none)
					)
				)
				(circle
					(center 4.318 0)
					(radius 0.508)
					(stroke
						(width 0.254)
						(type default)
					)
					(fill
						(type none)
					)
				)
				(circle
					(center 4.318 -2.54)
					(radius 0.508)
					(stroke
						(width 0.254)
						(type default)
					)
					(fill
						(type none)
					)
				)
				(circle
					(center 4.318 -5.08)
					(radius 0.508)
					(stroke
						(width 0.254)
						(type default)
					)
					(fill
						(type none)
					)
				)
				(polyline
					(pts
						(xy 4.826 0.127) (xy 8.7122 1.1684)
					)
					(stroke
						(width 0.254)
						(type default)
					)
					(fill
						(type none)
					)
				)
				(polyline
					(pts
						(xy 4.826 -2.413) (xy 8.7122 -1.3716)
					)
					(stroke
						(width 0.254)
						(type default)
					)
					(fill
						(type none)
					)
				)
				(polyline
					(pts
						(xy 4.826 -4.953) (xy 8.7122 -3.9116)
					)
					(stroke
						(width 0.254)
						(type default)
					)
					(fill
						(type none)
					)
				)
				(circle
					(center 8.382 0)
					(radius 0.508)
					(stroke
						(width 0.254)
						(type default)
					)
					(fill
						(type none)
					)
				)
				(circle
					(center 8.382 -2.54)
					(radius 0.508)
					(stroke
						(width 0.254)
						(type default)
					)
					(fill
						(type none)
					)
				)
				(circle
					(center 8.382 -5.08)
					(radius 0.508)
					(stroke
						(width 0.254)
						(type default)
					)
					(fill
						(type none)
					)
				)
				(polyline
					(pts
						(xy 10.16 0) (xy 8.89 0)
					)
					(stroke
						(width 0.254)
						(type default)
					)
					(fill
						(type none)
					)
				)
				(polyline
					(pts
						(xy 10.16 -2.54) (xy 8.89 -2.54)
					)
					(stroke
						(width 0.254)
						(type default)
					)
					(fill
						(type none)
					)
				)
				(polyline
					(pts
						(xy 10.16 -5.08) (xy 8.89 -5.08)
					)
					(stroke
						(width 0.254)
						(type default)
					)
					(fill
						(type none)
					)
				)
				(text "SH"
					(at 8.255 -7.62 0)
					(effects
						(font
							(size 1.27 1.27)
							(thickness 0.15)
						)
					)
				)
				(pin passive line
					(at 0 0 0)
					(length 2.54)
					(name "1"
						(effects
							(font
								(size 1.27 1.27)
							)
						)
					)
					(number "1"
						(effects
							(font
								(size 1.27 1.27)
							)
						)
					)
				)
				(pin passive line
					(at 0 -2.54 0)
					(length 2.54)
					(name "2"
						(effects
							(font
								(size 1.27 1.27)
							)
						)
					)
					(number "2"
						(effects
							(font
								(size 1.27 1.27)
							)
						)
					)
				)
				(pin passive line
					(at 0 -5.08 0)
					(length 2.54)
					(name "3"
						(effects
							(font
								(size 1.27 1.27)
							)
						)
					)
					(number "3"
						(effects
							(font
								(size 1.27 1.27)
							)
						)
					)
				)
				(pin passive line
					(at 12.7 0 180)
					(length 2.54)
					(name "6"
						(effects
							(font
								(size 1.27 1.27)
							)
						)
					)
					(number "6"
						(effects
							(font
								(size 1.27 1.27)
							)
						)
					)
				)
				(pin passive line
					(at 12.7 -2.54 180)
					(length 2.54)
					(name "5"
						(effects
							(font
								(size 1.27 1.27)
							)
						)
					)
					(number "5"
						(effects
							(font
								(size 1.27 1.27)
							)
						)
					)
				)
				(pin passive line
					(at 12.7 -5.08 180)
					(length 2.54)
					(name "4"
						(effects
							(font
								(size 1.27 1.27)
							)
						)
					)
					(number "4"
						(effects
							(font
								(size 1.27 1.27)
							)
						)
					)
				)
				(pin power_in line
					(at 12.7 -7.62 180)
					(length 2.54)
					(name "7"
						(effects
							(font
								(size 1.27 1.27)
							)
						)
					)
					(number "7"
						(effects
							(font
								(size 1.27 1.27)
							)
						)
					)
				)
			)
		)
	(symbol "antmicroSlideSwitches:SW_CVS-08TB"
			(pin_names
				(hide yes)
			)
			(exclude_from_sim no)
			(in_bom yes)
			(on_board yes)
			(property "Reference" "SW"
				(at 26.67 -2.54 0)
				(effects
					(font
						(size 1.27 1.27)
						(thickness 0.15)
					)
					(justify left bottom)
				)
			)
			(property "Value" "SW_CVS-08TB"
				(at 26.67 -5.08 0)
				(effects
					(font
						(size 1.27 1.27)
						(thickness 0.15)
					)
					(justify left bottom)
				)
			)
			(property "Footprint" "antmicro-footprints:SW_DIP_SPSTx08_Slide_Copal_CVS-08xB_W5.9mm_P1mm"
				(at 26.67 -7.62 0)
				(effects
					(font
						(size 1.27 1.27)
						(thickness 0.15)
					)
					(justify left bottom)
					(hide yes)
				)
			)
			(property "Datasheet" "https://www.mouser.com/datasheet/2/972/cvs-1827291.pdf"
				(at 26.67 -10.16 0)
				(effects
					(font
						(size 1.27 1.27)
						(thickness 0.15)
					)
					(justify left bottom)
					(hide yes)
				)
			)
			(property "Description" "DIP / SIP Switch, 8 Circuits, Slide, Surface Mount, SPST, 6 V, 100 mA"
				(at 0 0 0)
				(effects
					(font
						(size 1.27 1.27)
					)
					(hide yes)
				)
			)
			(property "MPN" "CVS-08TB"
				(at 26.67 -12.7 0)
				(effects
					(font
						(size 1.27 1.27)
						(thickness 0.15)
					)
					(justify left bottom)
					(hide yes)
				)
			)
			(property "Manufacturer" "Nidec Components"
				(at 26.67 -15.24 0)
				(effects
					(font
						(size 1.27 1.27)
						(thickness 0.15)
					)
					(justify left bottom)
					(hide yes)
				)
			)
			(property "Author" "Antmicro"
				(at 26.67 -17.78 0)
				(effects
					(font
						(size 1.27 1.27)
						(thickness 0.15)
					)
					(justify left bottom)
					(hide yes)
				)
			)
			(property "License" "Apache-2.0"
				(at 26.67 -20.32 0)
				(effects
					(font
						(size 1.27 1.27)
						(thickness 0.15)
					)
					(justify left bottom)
					(hide yes)
				)
			)
			(property "ki_keywords" "SWITCH, SLIDE, SPST"
				(at 0 0 0)
				(effects
					(font
						(size 1.27 1.27)
					)
					(hide yes)
				)
			)
			(property "ki_fp_filters" "SW?DIP?x2*"
				(at 0 0 0)
				(effects
					(font
						(size 1.27 1.27)
					)
					(hide yes)
				)
			)
			(symbol "SW_CVS-08TB_1_1"
				(rectangle
					(start 2.54 2.54)
					(end 10.16 -21.59)
					(stroke
						(width 0.254)
						(type default)
					)
					(fill
						(type background)
					)
				)
				(polyline
					(pts
						(xy 2.54 0) (xy 3.81 0)
					)
					(stroke
						(width 0.254)
						(type default)
					)
					(fill
						(type none)
					)
				)
				(polyline
					(pts
						(xy 2.54 -2.54) (xy 3.81 -2.54)
					)
					(stroke
						(width 0.254)
						(type default)
					)
					(fill
						(type none)
					)
				)
				(polyline
					(pts
						(xy 2.54 -5.08) (xy 3.81 -5.08)
					)
					(stroke
						(width 0.254)
						(type default)
					)
					(fill
						(type none)
					)
				)
				(polyline
					(pts
						(xy 2.54 -7.62) (xy 3.81 -7.62)
					)
					(stroke
						(width 0.254)
						(type default)
					)
					(fill
						(type none)
					)
				)
				(polyline
					(pts
						(xy 2.54 -10.16) (xy 3.81 -10.16)
					)
					(stroke
						(width 0.254)
						(type default)
					)
					(fill
						(type none)
					)
				)
				(polyline
					(pts
						(xy 2.54 -12.7) (xy 3.81 -12.7)
					)
					(stroke
						(width 0.254)
						(type default)
					)
					(fill
						(type none)
					)
				)
				(polyline
					(pts
						(xy 2.54 -17.78) (xy 3.81 -17.78)
					)
					(stroke
						(width 0.254)
						(type default)
					)
					(fill
						(type none)
					)
				)
				(polyline
					(pts
						(xy 2.5435 -15.235) (xy 3.8135 -15.235)
					)
					(stroke
						(width 0.254)
						(type default)
					)
					(fill
						(type none)
					)
				)
				(circle
					(center 4.318 0)
					(radius 0.508)
					(stroke
						(width 0.254)
						(type default)
					)
					(fill
						(type none)
					)
				)
				(circle
					(center 4.318 -2.54)
					(radius 0.508)
					(stroke
						(width 0.254)
						(type default)
					)
					(fill
						(type none)
					)
				)
				(circle
					(center 4.318 -5.08)
					(radius 0.508)
					(stroke
						(width 0.254)
						(type default)
					)
					(fill
						(type none)
					)
				)
				(circle
					(center 4.318 -7.62)
					(radius 0.508)
					(stroke
						(width 0.254)
						(type default)
					)
					(fill
						(type none)
					)
				)
				(circle
					(center 4.318 -10.16)
					(radius 0.508)
					(stroke
						(width 0.254)
						(type default)
					)
					(fill
						(type none)
					)
				)
				(circle
					(center 4.318 -12.7)
					(radius 0.508)
					(stroke
						(width 0.254)
						(type default)
					)
					(fill
						(type none)
					)
				)
				(circle
					(center 4.318 -15.24)
					(radius 0.508)
					(stroke
						(width 0.254)
						(type default)
					)
					(fill
						(type none)
					)
				)
				(circle
					(center 4.318 -17.78)
					(radius 0.508)
					(stroke
						(width 0.254)
						(type default)
					)
					(fill
						(type none)
					)
				)
				(polyline
					(pts
						(xy 4.826 0.127) (xy 8.7122 1.1684)
					)
					(stroke
						(width 0.254)
						(type default)
					)
					(fill
						(type none)
					)
				)
				(polyline
					(pts
						(xy 4.826 -2.413) (xy 8.7122 -1.3716)
					)
					(stroke
						(width 0.254)
						(type default)
					)
					(fill
						(type none)
					)
				)
				(polyline
					(pts
						(xy 4.826 -4.953) (xy 8.7122 -3.9116)
					)
					(stroke
						(width 0.254)
						(type default)
					)
					(fill
						(type none)
					)
				)
				(polyline
					(pts
						(xy 4.826 -7.493) (xy 8.7122 -6.4516)
					)
					(stroke
						(width 0.254)
						(type default)
					)
					(fill
						(type none)
					)
				)
				(polyline
					(pts
						(xy 4.826 -10.033) (xy 8.7122 -8.9916)
					)
					(stroke
						(width 0.254)
						(type default)
					)
					(fill
						(type none)
					)
				)
				(polyline
					(pts
						(xy 4.826 -12.573) (xy 8.7122 -11.5316)
					)
					(stroke
						(width 0.254)
						(type default)
					)
					(fill
						(type none)
					)
				)
				(polyline
					(pts
						(xy 4.826 -15.113) (xy 8.7122 -14.0716)
					)
					(stroke
						(width 0.254)
						(type default)
					)
					(fill
						(type none)
					)
				)
				(polyline
					(pts
						(xy 4.826 -17.653) (xy 8.7122 -16.6116)
					)
					(stroke
						(width 0.254)
						(type default)
					)
					(fill
						(type none)
					)
				)
				(circle
					(center 8.382 0)
					(radius 0.508)
					(stroke
						(width 0.254)
						(type default)
					)
					(fill
						(type none)
					)
				)
				(circle
					(center 8.382 -2.54)
					(radius 0.508)
					(stroke
						(width 0.254)
						(type default)
					)
					(fill
						(type none)
					)
				)
				(circle
					(center 8.382 -5.08)
					(radius 0.508)
					(stroke
						(width 0.254)
						(type default)
					)
					(fill
						(type none)
					)
				)
				(circle
					(center 8.382 -7.62)
					(radius 0.508)
					(stroke
						(width 0.254)
						(type default)
					)
					(fill
						(type none)
					)
				)
				(circle
					(center 8.382 -10.16)
					(radius 0.508)
					(stroke
						(width 0.254)
						(type default)
					)
					(fill
						(type none)
					)
				)
				(circle
					(center 8.382 -12.7)
					(radius 0.508)
					(stroke
						(width 0.254)
						(type default)
					)
					(fill
						(type none)
					)
				)
				(circle
					(center 8.382 -15.24)
					(radius 0.508)
					(stroke
						(width 0.254)
						(type default)
					)
					(fill
						(type none)
					)
				)
				(circle
					(center 8.382 -17.78)
					(radius 0.508)
					(stroke
						(width 0.254)
						(type default)
					)
					(fill
						(type none)
					)
				)
				(polyline
					(pts
						(xy 8.89 0) (xy 10.16 0)
					)
					(stroke
						(width 0.254)
						(type default)
					)
					(fill
						(type none)
					)
				)
				(polyline
					(pts
						(xy 8.89 -2.54) (xy 10.16 -2.54)
					)
					(stroke
						(width 0.254)
						(type default)
					)
					(fill
						(type none)
					)
				)
				(polyline
					(pts
						(xy 8.89 -5.08) (xy 10.16 -5.08)
					)
					(stroke
						(width 0.254)
						(type default)
					)
					(fill
						(type none)
					)
				)
				(polyline
					(pts
						(xy 8.89 -7.62) (xy 10.16 -7.62)
					)
					(stroke
						(width 0.254)
						(type default)
					)
					(fill
						(type none)
					)
				)
				(polyline
					(pts
						(xy 8.89 -10.16) (xy 10.16 -10.16)
					)
					(stroke
						(width 0.254)
						(type default)
					)
					(fill
						(type none)
					)
				)
				(polyline
					(pts
						(xy 8.89 -12.7) (xy 10.16 -12.7)
					)
					(stroke
						(width 0.254)
						(type default)
					)
					(fill
						(type none)
					)
				)
				(polyline
					(pts
						(xy 8.89 -17.78) (xy 10.16 -17.78)
					)
					(stroke
						(width 0.254)
						(type default)
					)
					(fill
						(type none)
					)
				)
				(polyline
					(pts
						(xy 8.8935 -15.235) (xy 10.1635 -15.235)
					)
					(stroke
						(width 0.254)
						(type default)
					)
					(fill
						(type none)
					)
				)
				(text "SH"
					(at 6.985 -20.955 0)
					(effects
						(font
							(size 1.27 1.27)
							(thickness 0.15)
						)
						(justify left bottom)
					)
				)
				(pin passive line
					(at 0 0 0)
					(length 2.54)
					(name "1"
						(effects
							(font
								(size 1.27 1.27)
							)
						)
					)
					(number "1"
						(effects
							(font
								(size 1.27 1.27)
							)
						)
					)
				)
				(pin passive line
					(at 0 -2.54 0)
					(length 2.54)
					(name "2"
						(effects
							(font
								(size 1.27 1.27)
							)
						)
					)
					(number "2"
						(effects
							(font
								(size 1.27 1.27)
							)
						)
					)
				)
				(pin passive line
					(at 0 -5.08 0)
					(length 2.54)
					(name "3"
						(effects
							(font
								(size 1.27 1.27)
							)
						)
					)
					(number "3"
						(effects
							(font
								(size 1.27 1.27)
							)
						)
					)
				)
				(pin passive line
					(at 0 -7.62 0)
					(length 2.54)
					(name "4"
						(effects
							(font
								(size 1.27 1.27)
							)
						)
					)
					(number "4"
						(effects
							(font
								(size 1.27 1.27)
							)
						)
					)
				)
				(pin passive line
					(at 0 -10.16 0)
					(length 2.54)
					(name "5"
						(effects
							(font
								(size 1.27 1.27)
							)
						)
					)
					(number "5"
						(effects
							(font
								(size 1.27 1.27)
							)
						)
					)
				)
				(pin passive line
					(at 0 -12.7 0)
					(length 2.54)
					(name "6"
						(effects
							(font
								(size 1.27 1.27)
							)
						)
					)
					(number "6"
						(effects
							(font
								(size 1.27 1.27)
							)
						)
					)
				)
				(pin passive line
					(at 0 -15.24 0)
					(length 2.54)
					(name "7"
						(effects
							(font
								(size 1.27 1.27)
							)
						)
					)
					(number "7"
						(effects
							(font
								(size 1.27 1.27)
							)
						)
					)
				)
				(pin passive line
					(at 0 -17.78 0)
					(length 2.54)
					(name "8"
						(effects
							(font
								(size 1.27 1.27)
							)
						)
					)
					(number "8"
						(effects
							(font
								(size 1.27 1.27)
							)
						)
					)
				)
				(pin passive line
					(at 12.7 0 180)
					(length 2.54)
					(name "16"
						(effects
							(font
								(size 1.27 1.27)
							)
						)
					)
					(number "16"
						(effects
							(font
								(size 1.27 1.27)
							)
						)
					)
				)
				(pin passive line
					(at 12.7 -2.54 180)
					(length 2.54)
					(name "15"
						(effects
							(font
								(size 1.27 1.27)
							)
						)
					)
					(number "15"
						(effects
							(font
								(size 1.27 1.27)
							)
						)
					)
				)
				(pin passive line
					(at 12.7 -5.08 180)
					(length 2.54)
					(name "14"
						(effects
							(font
								(size 1.27 1.27)
							)
						)
					)
					(number "14"
						(effects
							(font
								(size 1.27 1.27)
							)
						)
					)
				)
				(pin passive line
					(at 12.7 -7.62 180)
					(length 2.54)
					(name "13"
						(effects
							(font
								(size 1.27 1.27)
							)
						)
					)
					(number "13"
						(effects
							(font
								(size 1.27 1.27)
							)
						)
					)
				)
				(pin passive line
					(at 12.7 -10.16 180)
					(length 2.54)
					(name "12"
						(effects
							(font
								(size 1.27 1.27)
							)
						)
					)
					(number "12"
						(effects
							(font
								(size 1.27 1.27)
							)
						)
					)
				)
				(pin passive line
					(at 12.7 -12.7 180)
					(length 2.54)
					(name "11"
						(effects
							(font
								(size 1.27 1.27)
							)
						)
					)
					(number "11"
						(effects
							(font
								(size 1.27 1.27)
							)
						)
					)
				)
				(pin passive line
					(at 12.7 -15.24 180)
					(length 2.54)
					(name "10"
						(effects
							(font
								(size 1.27 1.27)
							)
						)
					)
					(number "10"
						(effects
							(font
								(size 1.27 1.27)
							)
						)
					)
				)
				(pin passive line
					(at 12.7 -17.78 180)
					(length 2.54)
					(name "9"
						(effects
							(font
								(size 1.27 1.27)
							)
						)
					)
					(number "9"
						(effects
							(font
								(size 1.27 1.27)
							)
						)
					)
				)
				(pin power_in line
					(at 12.7 -20.32 180)
					(length 2.54)
					(name "17"
						(effects
							(font
								(size 1.27 1.27)
							)
						)
					)
					(number "17"
						(effects
							(font
								(size 1.27 1.27)
							)
						)
					)
				)
			)
		)
	(symbol "antmicroTVSDiodes:CD-MMBL110S"
			(pin_names
				(hide yes)
			)
			(exclude_from_sim no)
			(in_bom yes)
			(on_board yes)
			(property "Reference" "D"
				(at 26.67 -2.54 0)
				(effects
					(font
						(size 1.27 1.27)
						(thickness 0.15)
					)
					(justify left bottom)
				)
			)
			(property "Value" "CD-MMBL110S"
				(at 26.67 -5.08 0)
				(effects
					(font
						(size 1.27 1.27)
						(thickness 0.15)
					)
					(justify left bottom)
				)
			)
			(property "Footprint" "antmicro-footprints:DFN3538"
				(at 26.67 -7.62 0)
				(effects
					(font
						(size 1.27 1.27)
						(thickness 0.15)
					)
					(justify left bottom)
					(hide yes)
				)
			)
			(property "Datasheet" "https://www.bourns.com/docs/product-datasheets/CD-MMBL110S.pdf"
				(at 26.67 -10.16 0)
				(effects
					(font
						(size 1.27 1.27)
						(thickness 0.15)
					)
					(justify left bottom)
					(hide yes)
				)
			)
			(property "Description" "TVS diode"
				(at 0 0 0)
				(effects
					(font
						(size 1.27 1.27)
					)
					(hide yes)
				)
			)
			(property "MPN" "CD-MMBL110S"
				(at 26.67 -12.7 0)
				(effects
					(font
						(size 1.27 1.27)
						(thickness 0.15)
					)
					(justify left bottom)
					(hide yes)
				)
			)
			(property "Manufacturer" "Bourns"
				(at 26.67 -15.24 0)
				(effects
					(font
						(size 1.27 1.27)
						(thickness 0.15)
					)
					(justify left bottom)
					(hide yes)
				)
			)
			(property "Author" "Antmicro"
				(at 26.67 -17.78 0)
				(effects
					(font
						(size 1.27 1.27)
						(thickness 0.15)
					)
					(justify left bottom)
					(hide yes)
				)
			)
			(property "License" "Apache-2.0"
				(at 26.67 -20.32 0)
				(effects
					(font
						(size 1.27 1.27)
						(thickness 0.15)
					)
					(justify left bottom)
					(hide yes)
				)
			)
			(property "ki_keywords" "SMT, RECTIFIER, SEMICONDUCTOR, DIODE, BRIDGE"
				(at 0 0 0)
				(effects
					(font
						(size 1.27 1.27)
					)
					(hide yes)
				)
			)
			(symbol "CD-MMBL110S_1_1"
				(rectangle
					(start 2.54 1.27)
					(end 15.24 -11.43)
					(stroke
						(width 0.254)
						(type default)
					)
					(fill
						(type background)
					)
				)
				(polyline
					(pts
						(xy 2.54 -5.08) (xy 3.81 -5.08)
					)
					(stroke
						(width 0.254)
						(type default)
					)
					(fill
						(type none)
					)
				)
				(polyline
					(pts
						(xy 3.81 0) (xy 2.54 0)
					)
					(stroke
						(width 0.254)
						(type default)
					)
					(fill
						(type none)
					)
				)
				(polyline
					(pts
						(xy 3.81 -2.54) (xy 3.81 -3.81)
					)
					(stroke
						(width 0.254)
						(type default)
					)
					(fill
						(type none)
					)
				)
				(polyline
					(pts
						(xy 3.81 -3.81) (xy 3.81 -7.62)
					)
					(stroke
						(width 0.254)
						(type default)
					)
					(fill
						(type none)
					)
				)
				(polyline
					(pts
						(xy 3.81 -10.16) (xy 2.54 -10.16)
					)
					(stroke
						(width 0.254)
						(type default)
					)
					(fill
						(type none)
					)
				)
				(polyline
					(pts
						(xy 5.08 -1.27) (xy 5.08 -3.81) (xy 7.62 -2.54) (xy 5.08 -1.27)
					)
					(stroke
						(width 0.254)
						(type default)
					)
					(fill
						(type outline)
					)
				)
				(polyline
					(pts
						(xy 5.08 -2.54) (xy 3.81 -2.54)
					)
					(stroke
						(width 0.254)
						(type default)
					)
					(fill
						(type none)
					)
				)
				(polyline
					(pts
						(xy 5.08 -6.35) (xy 5.08 -8.89) (xy 7.62 -7.62) (xy 5.08 -6.35)
					)
					(stroke
						(width 0.254)
						(type default)
					)
					(fill
						(type outline)
					)
				)
				(polyline
					(pts
						(xy 5.08 -7.62) (xy 3.81 -7.62)
					)
					(stroke
						(width 0.254)
						(type default)
					)
					(fill
						(type none)
					)
				)
				(polyline
					(pts
						(xy 7.62 -1.27) (xy 7.62 -3.81)
					)
					(stroke
						(width 0.254)
						(type default)
					)
					(fill
						(type none)
					)
				)
				(polyline
					(pts
						(xy 7.62 -6.35) (xy 7.62 -8.89)
					)
					(stroke
						(width 0.254)
						(type default)
					)
					(fill
						(type none)
					)
				)
				(polyline
					(pts
						(xy 8.89 -2.54) (xy 7.62 -2.54)
					)
					(stroke
						(width 0.254)
						(type default)
					)
					(fill
						(type none)
					)
				)
				(polyline
					(pts
						(xy 8.89 -2.54) (xy 8.89 0) (xy 3.81 0)
					)
					(stroke
						(width 0.254)
						(type default)
					)
					(fill
						(type none)
					)
				)
				(polyline
					(pts
						(xy 8.89 -7.62) (xy 7.62 -7.62)
					)
					(stroke
						(width 0.254)
						(type default)
					)
					(fill
						(type none)
					)
				)
				(polyline
					(pts
						(xy 8.89 -7.62) (xy 8.89 -10.16) (xy 3.81 -10.16)
					)
					(stroke
						(width 0.254)
						(type default)
					)
					(fill
						(type none)
					)
				)
				(polyline
					(pts
						(xy 10.16 -1.27) (xy 10.16 -3.81) (xy 12.7 -2.54) (xy 10.16 -1.27)
					)
					(stroke
						(width 0.254)
						(type default)
					)
					(fill
						(type outline)
					)
				)
				(polyline
					(pts
						(xy 10.16 -2.54) (xy 6.35 -2.54)
					)
					(stroke
						(width 0.254)
						(type default)
					)
					(fill
						(type none)
					)
				)
				(polyline
					(pts
						(xy 10.16 -6.35) (xy 10.16 -8.89) (xy 12.7 -7.62) (xy 10.16 -6.35)
					)
					(stroke
						(width 0.254)
						(type default)
					)
					(fill
						(type outline)
					)
				)
				(polyline
					(pts
						(xy 10.16 -7.62) (xy 6.35 -7.62)
					)
					(stroke
						(width 0.254)
						(type default)
					)
					(fill
						(type none)
					)
				)
				(polyline
					(pts
						(xy 12.7 -1.27) (xy 12.7 -3.81)
					)
					(stroke
						(width 0.254)
						(type default)
					)
					(fill
						(type none)
					)
				)
				(polyline
					(pts
						(xy 12.7 -2.54) (xy 13.97 -2.54)
					)
					(stroke
						(width 0.254)
						(type default)
					)
					(fill
						(type none)
					)
				)
				(polyline
					(pts
						(xy 12.7 -6.35) (xy 12.7 -8.89)
					)
					(stroke
						(width 0.254)
						(type default)
					)
					(fill
						(type none)
					)
				)
				(polyline
					(pts
						(xy 12.7 -7.62) (xy 13.97 -7.62)
					)
					(stroke
						(width 0.254)
						(type default)
					)
					(fill
						(type none)
					)
				)
				(polyline
					(pts
						(xy 13.97 -2.54) (xy 13.97 -3.81)
					)
					(stroke
						(width 0.254)
						(type default)
					)
					(fill
						(type none)
					)
				)
				(polyline
					(pts
						(xy 13.97 -3.81) (xy 13.97 -7.62)
					)
					(stroke
						(width 0.254)
						(type default)
					)
					(fill
						(type none)
					)
				)
				(polyline
					(pts
						(xy 13.97 -5.08) (xy 15.24 -5.08)
					)
					(stroke
						(width 0.254)
						(type default)
					)
					(fill
						(type none)
					)
				)
				(pin input line
					(at 0 0 0)
					(length 2.54)
					(name "3"
						(effects
							(font
								(size 1.27 1.27)
							)
						)
					)
					(number "3"
						(effects
							(font
								(size 1.27 1.27)
							)
						)
					)
				)
				(pin output line
					(at 0 -5.08 0)
					(length 2.54)
					(name "1"
						(effects
							(font
								(size 1.27 1.27)
							)
						)
					)
					(number "1"
						(effects
							(font
								(size 1.27 1.27)
							)
						)
					)
				)
				(pin input line
					(at 0 -10.16 0)
					(length 2.54)
					(name "4"
						(effects
							(font
								(size 1.27 1.27)
							)
						)
					)
					(number "4"
						(effects
							(font
								(size 1.27 1.27)
							)
						)
					)
				)
				(pin output line
					(at 17.78 -5.08 180)
					(length 2.54)
					(name "2"
						(effects
							(font
								(size 1.27 1.27)
							)
						)
					)
					(number "2"
						(effects
							(font
								(size 1.27 1.27)
							)
						)
					)
				)
			)
		)
	(symbol "antmicroTVSDiodes:ESDA25P35-1U1M"
			(pin_numbers
				(hide yes)
			)
			(pin_names
				(hide yes)
			)
			(exclude_from_sim no)
			(in_bom yes)
			(on_board yes)
			(property "Reference" "D"
				(at 24.13 -5.08 0)
				(effects
					(font
						(size 1.27 1.27)
						(thickness 0.15)
					)
					(justify left bottom)
				)
			)
			(property "Value" "ESDA25P35-1U1M"
				(at 24.13 -15.24 0)
				(effects
					(font
						(size 1.27 1.27)
						(thickness 0.15)
					)
					(justify left bottom)
					(hide yes)
				)
			)
			(property "Footprint" "antmicro-footprints:QFN-2L_1.6x1x0.55mm"
				(at 24.13 -10.16 0)
				(effects
					(font
						(size 1.27 1.27)
						(thickness 0.15)
					)
					(justify left bottom)
					(hide yes)
				)
			)
			(property "Datasheet" "https://www.st.com/resource/en/datasheet/esda25p35-1u1m.pdf"
				(at 24.13 -12.7 0)
				(effects
					(font
						(size 1.27 1.27)
						(thickness 0.15)
					)
					(justify left bottom)
					(hide yes)
				)
			)
			(property "Description" "Unidirectional TVS, 30 kV, QFN-2L, 22 V, 195 pF"
				(at 0 0 0)
				(effects
					(font
						(size 1.27 1.27)
					)
					(hide yes)
				)
			)
			(property "MPN" "ESDA25P35-1U1M"
				(at 24.13 -7.62 0)
				(effects
					(font
						(size 1.27 1.27)
						(thickness 0.15)
					)
					(justify left bottom)
				)
			)
			(property "Manufacturer" "STMicroelectronics"
				(at 24.13 -17.78 0)
				(effects
					(font
						(size 1.27 1.27)
						(thickness 0.15)
					)
					(justify left bottom)
					(hide yes)
				)
			)
			(property "Author" "Antmicro"
				(at 24.13 -20.32 0)
				(effects
					(font
						(size 1.27 1.27)
						(thickness 0.15)
					)
					(justify left bottom)
					(hide yes)
				)
			)
			(property "Public" "False"
				(at 20.32 -17.78 0)
				(effects
					(font
						(size 1.27 1.27)
					)
					(justify left bottom)
					(hide yes)
				)
			)
			(property "License" "Apache-2.0"
				(at 24.13 -22.86 0)
				(effects
					(font
						(size 1.27 1.27)
						(thickness 0.15)
					)
					(justify left bottom)
					(hide yes)
				)
			)
			(property "ki_keywords" "DIODE, SEMICONDUCTOR, TVS, ESD"
				(at 0 0 0)
				(effects
					(font
						(size 1.27 1.27)
					)
					(hide yes)
				)
			)
			(symbol "ESDA25P35-1U1M_0_1"
				(polyline
					(pts
						(xy 1.905 0) (xy 0.635 0)
					)
					(stroke
						(width 0)
						(type default)
					)
					(fill
						(type none)
					)
				)
				(polyline
					(pts
						(xy 4.445 0) (xy 3.175 0)
					)
					(stroke
						(width 0)
						(type default)
					)
					(fill
						(type none)
					)
				)
			)
			(symbol "ESDA25P35-1U1M_1_1"
				(polyline
					(pts
						(xy 1.778 1.016) (xy 1.397 1.016)
					)
					(stroke
						(width 0.254)
						(type default)
					)
					(fill
						(type none)
					)
				)
				(polyline
					(pts
						(xy 1.778 1.016) (xy 1.778 -1.016)
					)
					(stroke
						(width 0.254)
						(type default)
					)
					(fill
						(type none)
					)
				)
				(polyline
					(pts
						(xy 2.159 -1.016) (xy 1.778 -1.016)
					)
					(stroke
						(width 0.254)
						(type default)
					)
					(fill
						(type none)
					)
				)
				(polyline
					(pts
						(xy 3.302 1.016) (xy 3.302 -1.016) (xy 1.778 0) (xy 3.302 1.016)
					)
					(stroke
						(width 0.254)
						(type default)
					)
					(fill
						(type outline)
					)
				)
				(pin passive line
					(at 0 0 0)
					(length 0.635)
					(name "C"
						(effects
							(font
								(size 1.27 1.27)
							)
						)
					)
					(number "1"
						(effects
							(font
								(size 1.27 1.27)
							)
						)
					)
				)
				(pin passive line
					(at 5.08 0 180)
					(length 0.635)
					(name "A"
						(effects
							(font
								(size 1.27 1.27)
							)
						)
					)
					(number "2"
						(effects
							(font
								(size 1.27 1.27)
							)
						)
					)
				)
			)
		)
	(symbol "antmicroTVSDiodes:PTVS58VS1UR,115"
			(pin_numbers
				(hide yes)
			)
			(pin_names
				(hide yes)
			)
			(exclude_from_sim no)
			(in_bom yes)
			(on_board yes)
			(property "Reference" "D"
				(at 21.59 -5.08 0)
				(effects
					(font
						(size 1.27 1.27)
						(thickness 0.15)
					)
					(justify left bottom)
				)
			)
			(property "Value" "PTVS58VS1UR,115"
				(at 21.59 -15.24 0)
				(effects
					(font
						(size 1.27 1.27)
						(thickness 0.15)
					)
					(justify left bottom)
					(hide yes)
				)
			)
			(property "Footprint" "antmicro-footprints:D_SOD-123F"
				(at 21.59 -10.16 0)
				(effects
					(font
						(size 1.27 1.27)
						(thickness 0.15)
					)
					(justify left bottom)
					(hide yes)
				)
			)
			(property "Datasheet" "https://assets.nexperia.com/documents/data-sheet/PTVSXS1UR_SER.pdf"
				(at 21.59 -12.7 0)
				(effects
					(font
						(size 1.27 1.27)
						(thickness 0.15)
					)
					(justify left bottom)
					(hide yes)
				)
			)
			(property "Description" "Unidirectional TVS, 8 kV,  SOD-123F, 58 V"
				(at 0 0 0)
				(effects
					(font
						(size 1.27 1.27)
					)
					(hide yes)
				)
			)
			(property "MPN" "PTVS58VS1UR,115"
				(at 21.59 -7.62 0)
				(effects
					(font
						(size 1.27 1.27)
						(thickness 0.15)
					)
					(justify left bottom)
				)
			)
			(property "Manufacturer" "Nexperia"
				(at 21.59 -17.78 0)
				(effects
					(font
						(size 1.27 1.27)
						(thickness 0.15)
					)
					(justify left bottom)
					(hide yes)
				)
			)
			(property "Author" "Antmicro"
				(at 21.59 -20.32 0)
				(effects
					(font
						(size 1.27 1.27)
						(thickness 0.15)
					)
					(justify left bottom)
					(hide yes)
				)
			)
			(property "Public" "False"
				(at 20.32 -17.78 0)
				(effects
					(font
						(size 1.27 1.27)
					)
					(justify left bottom)
					(hide yes)
				)
			)
			(property "License" "Apache-2.0"
				(at 21.59 -22.86 0)
				(effects
					(font
						(size 1.27 1.27)
						(thickness 0.15)
					)
					(justify left bottom)
					(hide yes)
				)
			)
			(property "ki_keywords" "DIODE, SEMICONDUCTOR, TVS, ESD"
				(at 0 0 0)
				(effects
					(font
						(size 1.27 1.27)
					)
					(hide yes)
				)
			)
			(symbol "PTVS58VS1UR,115_0_1"
				(polyline
					(pts
						(xy 1.905 0) (xy 0.635 0)
					)
					(stroke
						(width 0)
						(type default)
					)
					(fill
						(type none)
					)
				)
				(polyline
					(pts
						(xy 4.445 0) (xy 3.175 0)
					)
					(stroke
						(width 0)
						(type default)
					)
					(fill
						(type none)
					)
				)
			)
			(symbol "PTVS58VS1UR,115_1_1"
				(polyline
					(pts
						(xy 1.778 1.016) (xy 1.397 1.016)
					)
					(stroke
						(width 0.254)
						(type default)
					)
					(fill
						(type none)
					)
				)
				(polyline
					(pts
						(xy 1.778 1.016) (xy 1.778 -1.016)
					)
					(stroke
						(width 0.254)
						(type default)
					)
					(fill
						(type none)
					)
				)
				(polyline
					(pts
						(xy 2.159 -1.016) (xy 1.778 -1.016)
					)
					(stroke
						(width 0.254)
						(type default)
					)
					(fill
						(type none)
					)
				)
				(polyline
					(pts
						(xy 3.302 1.016) (xy 3.302 -1.016) (xy 1.778 0) (xy 3.302 1.016)
					)
					(stroke
						(width 0.254)
						(type default)
					)
					(fill
						(type outline)
					)
				)
				(pin passive line
					(at 0 0 0)
					(length 0.635)
					(name "C"
						(effects
							(font
								(size 1.27 1.27)
							)
						)
					)
					(number "1"
						(effects
							(font
								(size 1.27 1.27)
							)
						)
					)
				)
				(pin passive line
					(at 5.08 0 180)
					(length 0.635)
					(name "A"
						(effects
							(font
								(size 1.27 1.27)
							)
						)
					)
					(number "2"
						(effects
							(font
								(size 1.27 1.27)
							)
						)
					)
				)
			)
		)
	(symbol "antmicroTVSDiodes:TPD4E05U06QDQARQ1"
			(exclude_from_sim no)
			(in_bom yes)
			(on_board yes)
			(property "Reference" "U"
				(at 24.13 0 0)
				(effects
					(font
						(size 1.27 1.27)
						(thickness 0.15)
					)
					(justify left bottom)
				)
			)
			(property "Value" "TPD4E05U06QDQARQ1"
				(at 24.13 -2.54 0)
				(effects
					(font
						(size 1.27 1.27)
						(thickness 0.15)
					)
					(justify left bottom)
				)
			)
			(property "Footprint" "antmicro-footprints:USON-10_2.5x1mm_P0.5mm"
				(at 24.13 -5.08 0)
				(effects
					(font
						(size 1.27 1.27)
						(thickness 0.15)
					)
					(justify left bottom)
					(hide yes)
				)
			)
			(property "Datasheet" "https://www.ti.com/lit/ds/symlink/tpd4e05u06-q1.pdf?HQS=dis-mous-null-mousermode-dsf-pf-null-wwe&ts=1663591265741&ref_url=https%253A%252F%252Fwww.mouser.com%252F"
				(at 24.13 -7.62 0)
				(effects
					(font
						(size 1.27 1.27)
						(thickness 0.15)
					)
					(justify left bottom)
					(hide yes)
				)
			)
			(property "Description" "ESD protection"
				(at 0 0 0)
				(effects
					(font
						(size 1.27 1.27)
					)
					(hide yes)
				)
			)
			(property "Manufacturer" "Texas Instruments"
				(at 24.13 -10.16 0)
				(effects
					(font
						(size 1.27 1.27)
						(thickness 0.15)
					)
					(justify left bottom)
					(hide yes)
				)
			)
			(property "MPN" "TPD4E05U06QDQARQ1"
				(at 24.13 -12.7 0)
				(effects
					(font
						(size 1.27 1.27)
						(thickness 0.15)
					)
					(justify left bottom)
					(hide yes)
				)
			)
			(property "Author" "Antmicro"
				(at 24.13 -15.24 0)
				(effects
					(font
						(size 1.27 1.27)
						(thickness 0.15)
					)
					(justify left bottom)
					(hide yes)
				)
			)
			(property "License" "Apache-2.0"
				(at 24.13 -17.78 0)
				(effects
					(font
						(size 1.27 1.27)
						(thickness 0.15)
					)
					(justify left bottom)
					(hide yes)
				)
			)
			(symbol "TPD4E05U06QDQARQ1_1_1"
				(rectangle
					(start 2.54 2.54)
					(end 8.89 -11.43)
					(stroke
						(width 0.254)
						(type default)
					)
					(fill
						(type background)
					)
				)
				(polyline
					(pts
						(xy 2.54 0) (xy 7.62 0)
					)
					(stroke
						(width 0.254)
						(type default)
					)
					(fill
						(type background)
					)
				)
				(polyline
					(pts
						(xy 2.54 -2.54) (xy 7.62 -2.54)
					)
					(stroke
						(width 0.254)
						(type default)
					)
					(fill
						(type background)
					)
				)
				(polyline
					(pts
						(xy 2.54 -5.08) (xy 7.62 -5.08)
					)
					(stroke
						(width 0.254)
						(type default)
					)
					(fill
						(type background)
					)
				)
				(polyline
					(pts
						(xy 2.54 -7.62) (xy 7.62 -7.62)
					)
					(stroke
						(width 0.254)
						(type default)
					)
					(fill
						(type background)
					)
				)
				(polyline
					(pts
						(xy 4.826 -0.635) (xy 5.08 -0.381) (xy 5.08 0.381) (xy 5.334 0.635)
					)
					(stroke
						(width 0.254)
						(type default)
					)
					(fill
						(type background)
					)
				)
				(polyline
					(pts
						(xy 4.826 -3.175) (xy 5.08 -2.921) (xy 5.08 -2.159) (xy 5.334 -1.905)
					)
					(stroke
						(width 0.254)
						(type default)
					)
					(fill
						(type background)
					)
				)
				(polyline
					(pts
						(xy 4.826 -5.715) (xy 5.08 -5.461) (xy 5.08 -4.699) (xy 5.334 -4.445)
					)
					(stroke
						(width 0.254)
						(type default)
					)
					(fill
						(type background)
					)
				)
				(polyline
					(pts
						(xy 4.826 -8.255) (xy 5.08 -8.001) (xy 5.08 -7.239) (xy 5.334 -6.985)
					)
					(stroke
						(width 0.254)
						(type default)
					)
					(fill
						(type background)
					)
				)
				(polyline
					(pts
						(xy 5.08 0) (xy 3.81 -0.635) (xy 3.81 0.635) (xy 5.08 0)
					)
					(stroke
						(width 0.254)
						(type default)
					)
					(fill
						(type background)
					)
				)
				(polyline
					(pts
						(xy 5.08 0) (xy 6.35 -0.635) (xy 6.35 0.635) (xy 5.08 0)
					)
					(stroke
						(width 0.254)
						(type default)
					)
					(fill
						(type background)
					)
				)
				(polyline
					(pts
						(xy 5.08 -2.54) (xy 3.81 -3.175) (xy 3.81 -1.905) (xy 5.08 -2.54)
					)
					(stroke
						(width 0.254)
						(type default)
					)
					(fill
						(type background)
					)
				)
				(polyline
					(pts
						(xy 5.08 -2.54) (xy 6.35 -3.175) (xy 6.35 -1.905) (xy 5.08 -2.54)
					)
					(stroke
						(width 0.254)
						(type default)
					)
					(fill
						(type background)
					)
				)
				(polyline
					(pts
						(xy 5.08 -5.08) (xy 3.81 -5.715) (xy 3.81 -4.445) (xy 5.08 -5.08)
					)
					(stroke
						(width 0.254)
						(type default)
					)
					(fill
						(type background)
					)
				)
				(polyline
					(pts
						(xy 5.08 -5.08) (xy 6.35 -4.445) (xy 6.35 -5.715) (xy 5.08 -5.08)
					)
					(stroke
						(width 0.254)
						(type default)
					)
					(fill
						(type background)
					)
				)
				(polyline
					(pts
						(xy 5.08 -7.62) (xy 3.81 -8.255) (xy 3.81 -6.985) (xy 5.08 -7.62)
					)
					(stroke
						(width 0.254)
						(type default)
					)
					(fill
						(type background)
					)
				)
				(polyline
					(pts
						(xy 6.35 -6.985) (xy 6.35 -8.255) (xy 5.08 -7.62) (xy 6.35 -6.985)
					)
					(stroke
						(width 0.254)
						(type default)
					)
					(fill
						(type background)
					)
				)
				(polyline
					(pts
						(xy 7.62 0) (xy 7.62 -10.16)
					)
					(stroke
						(width 0.254)
						(type default)
					)
					(fill
						(type background)
					)
				)
				(circle
					(center 7.62 -2.54)
					(radius 0.254)
					(stroke
						(width 0.254)
						(type default)
					)
					(fill
						(type background)
					)
				)
				(circle
					(center 7.62 -5.08)
					(radius 0.254)
					(stroke
						(width 0.254)
						(type default)
					)
					(fill
						(type background)
					)
				)
				(circle
					(center 7.62 -5.08)
					(radius 0.254)
					(stroke
						(width 0.254)
						(type default)
					)
					(fill
						(type background)
					)
				)
				(circle
					(center 7.62 -7.62)
					(radius 0.254)
					(stroke
						(width 0.254)
						(type default)
					)
					(fill
						(type background)
					)
				)
				(polyline
					(pts
						(xy 7.62 -10.16) (xy 2.54 -10.16)
					)
					(stroke
						(width 0.254)
						(type default)
					)
					(fill
						(type background)
					)
				)
				(pin passive line
					(at 0 0 0)
					(length 2.54)
					(name "~"
						(effects
							(font
								(size 1.27 1.27)
							)
						)
					)
					(number "1"
						(effects
							(font
								(size 1.27 1.27)
							)
						)
					)
				)
				(pin passive line
					(at 0 0 0)
					(length 2.54)
					(hide yes)
					(name "~"
						(effects
							(font
								(size 1.27 1.27)
							)
						)
					)
					(number "10"
						(effects
							(font
								(size 1.27 1.27)
							)
						)
					)
				)
				(pin passive line
					(at 0 -2.54 0)
					(length 2.54)
					(name "~"
						(effects
							(font
								(size 1.27 1.27)
							)
						)
					)
					(number "2"
						(effects
							(font
								(size 1.27 1.27)
							)
						)
					)
				)
				(pin passive line
					(at 0 -2.54 0)
					(length 2.54)
					(hide yes)
					(name "~"
						(effects
							(font
								(size 1.27 1.27)
							)
						)
					)
					(number "9"
						(effects
							(font
								(size 1.27 1.27)
							)
						)
					)
				)
				(pin passive line
					(at 0 -5.08 0)
					(length 2.54)
					(name "~"
						(effects
							(font
								(size 1.27 1.27)
							)
						)
					)
					(number "4"
						(effects
							(font
								(size 1.27 1.27)
							)
						)
					)
				)
				(pin passive line
					(at 0 -5.08 0)
					(length 2.54)
					(hide yes)
					(name "~"
						(effects
							(font
								(size 1.27 1.27)
							)
						)
					)
					(number "7"
						(effects
							(font
								(size 1.27 1.27)
							)
						)
					)
				)
				(pin passive line
					(at 0 -7.62 0)
					(length 2.54)
					(name "~"
						(effects
							(font
								(size 1.27 1.27)
							)
						)
					)
					(number "5"
						(effects
							(font
								(size 1.27 1.27)
							)
						)
					)
				)
				(pin passive line
					(at 0 -7.62 0)
					(length 2.54)
					(hide yes)
					(name "~"
						(effects
							(font
								(size 1.27 1.27)
							)
						)
					)
					(number "6"
						(effects
							(font
								(size 1.27 1.27)
							)
						)
					)
				)
				(pin power_in line
					(at 0 -10.16 0)
					(length 2.54)
					(name "~"
						(effects
							(font
								(size 1.27 1.27)
							)
						)
					)
					(number "3"
						(effects
							(font
								(size 1.27 1.27)
							)
						)
					)
				)
				(pin passive line
					(at 0 -10.16 0)
					(length 2.54)
					(hide yes)
					(name "~"
						(effects
							(font
								(size 1.27 1.27)
							)
						)
					)
					(number "8"
						(effects
							(font
								(size 1.27 1.27)
							)
						)
					)
				)
			)
		)
	(symbol "antmicroTemperatureSensorsAnalogandDigitalOutput:MAX1617AMEE+T"
			(exclude_from_sim no)
			(in_bom yes)
			(on_board yes)
			(property "Reference" "U"
				(at 35.56 -7.62 0)
				(effects
					(font
						(size 1.27 1.27)
						(thickness 0.15)
					)
					(justify left bottom)
				)
			)
			(property "Value" "MAX1617AMEE+T"
				(at 35.56 -10.16 0)
				(effects
					(font
						(size 1.27 1.27)
						(thickness 0.15)
					)
					(justify left bottom)
				)
			)
			(property "Footprint" "antmicro-footprints:QSOP-16_3.9x4.9mm_P0.635mm"
				(at 35.56 -12.7 0)
				(effects
					(font
						(size 1.27 1.27)
						(thickness 0.15)
					)
					(justify left bottom)
					(hide yes)
				)
			)
			(property "Datasheet" "https://www.analog.com/media/en/technical-documentation/data-sheets/MAX1617.pdf"
				(at 35.56 -15.24 0)
				(effects
					(font
						(size 1.27 1.27)
						(thickness 0.15)
					)
					(justify left bottom)
					(hide yes)
				)
			)
			(property "Description" "Temperature sensor"
				(at 0 0 0)
				(effects
					(font
						(size 1.27 1.27)
					)
					(hide yes)
				)
			)
			(property "MPN" "MAX1617AMEE+T"
				(at 35.56 -17.78 0)
				(effects
					(font
						(size 1.27 1.27)
						(thickness 0.15)
					)
					(justify left bottom)
					(hide yes)
				)
			)
			(property "Manufacturer" "Maxim Integrated Products"
				(at 35.56 -20.32 0)
				(effects
					(font
						(size 1.27 1.27)
						(thickness 0.15)
					)
					(justify left bottom)
					(hide yes)
				)
			)
			(property "Author" "Antmicro"
				(at 35.56 -22.86 0)
				(effects
					(font
						(size 1.27 1.27)
						(thickness 0.15)
					)
					(justify left bottom)
					(hide yes)
				)
			)
			(property "License" "Apache-2.0"
				(at 35.56 -25.4 0)
				(effects
					(font
						(size 1.27 1.27)
						(thickness 0.15)
					)
					(justify left bottom)
					(hide yes)
				)
			)
			(property "ki_keywords" "SMT, SENSOR, IC"
				(at 0 0 0)
				(effects
					(font
						(size 1.27 1.27)
					)
					(hide yes)
				)
			)
			(symbol "MAX1617AMEE+T_1_1"
				(rectangle
					(start 2.54 -2.54)
					(end 17.78 -24.13)
					(stroke
						(width 0.254)
						(type default)
					)
					(fill
						(type background)
					)
				)
				(pin input line
					(at 0 -6.35 0)
					(length 2.54)
					(name "STBY"
						(effects
							(font
								(size 1.27 1.27)
							)
						)
					)
					(number "15"
						(effects
							(font
								(size 1.27 1.27)
							)
						)
					)
				)
				(pin input line
					(at 0 -10.16 0)
					(length 2.54)
					(name "DXP"
						(effects
							(font
								(size 1.27 1.27)
							)
						)
					)
					(number "3"
						(effects
							(font
								(size 1.27 1.27)
							)
						)
					)
				)
				(pin input line
					(at 0 -12.7 0)
					(length 2.54)
					(name "DXN"
						(effects
							(font
								(size 1.27 1.27)
							)
						)
					)
					(number "4"
						(effects
							(font
								(size 1.27 1.27)
							)
						)
					)
				)
				(pin input line
					(at 0 -16.51 0)
					(length 2.54)
					(name "ADD0"
						(effects
							(font
								(size 1.27 1.27)
							)
						)
					)
					(number "10"
						(effects
							(font
								(size 1.27 1.27)
							)
						)
					)
				)
				(pin input line
					(at 0 -19.05 0)
					(length 2.54)
					(name "ADD1"
						(effects
							(font
								(size 1.27 1.27)
							)
						)
					)
					(number "6"
						(effects
							(font
								(size 1.27 1.27)
							)
						)
					)
				)
				(pin power_in line
					(at 10.16 0 270)
					(length 2.54)
					(name "VCC"
						(effects
							(font
								(size 1.27 1.27)
							)
						)
					)
					(number "2"
						(effects
							(font
								(size 1.27 1.27)
							)
						)
					)
				)
				(pin power_in line
					(at 10.16 -26.67 90)
					(length 2.54)
					(name "GND"
						(effects
							(font
								(size 1.27 1.27)
							)
						)
					)
					(number "7"
						(effects
							(font
								(size 1.27 1.27)
							)
						)
					)
				)
				(pin passive line
					(at 10.16 -26.67 90)
					(length 2.54)
					(hide yes)
					(name "GND"
						(effects
							(font
								(size 1.27 1.27)
							)
						)
					)
					(number "8"
						(effects
							(font
								(size 1.27 1.27)
							)
						)
					)
				)
				(pin bidirectional line
					(at 20.32 -10.16 180)
					(length 2.54)
					(name "SMBDATA"
						(effects
							(font
								(size 1.27 1.27)
							)
						)
					)
					(number "12"
						(effects
							(font
								(size 1.27 1.27)
							)
						)
					)
				)
				(pin input clock
					(at 20.32 -12.7 180)
					(length 2.54)
					(name "SMBCLK"
						(effects
							(font
								(size 1.27 1.27)
							)
						)
					)
					(number "14"
						(effects
							(font
								(size 1.27 1.27)
							)
						)
					)
				)
				(pin output line
					(at 20.32 -16.51 180)
					(length 2.54)
					(name "~{ALERT}"
						(effects
							(font
								(size 1.27 1.27)
							)
						)
					)
					(number "11"
						(effects
							(font
								(size 1.27 1.27)
							)
						)
					)
				)
				(pin no_connect line
					(at 20.32 -21.59 180)
					(length 2.54)
					(hide yes)
					(name "NC"
						(effects
							(font
								(size 1.27 1.27)
							)
						)
					)
					(number "1"
						(effects
							(font
								(size 1.27 1.27)
							)
						)
					)
				)
				(pin no_connect line
					(at 20.32 -21.59 180)
					(length 2.54)
					(hide yes)
					(name "NC"
						(effects
							(font
								(size 1.27 1.27)
							)
						)
					)
					(number "13"
						(effects
							(font
								(size 1.27 1.27)
							)
						)
					)
				)
				(pin no_connect line
					(at 20.32 -21.59 180)
					(length 2.54)
					(hide yes)
					(name "NC"
						(effects
							(font
								(size 1.27 1.27)
							)
						)
					)
					(number "16"
						(effects
							(font
								(size 1.27 1.27)
							)
						)
					)
				)
				(pin no_connect line
					(at 20.32 -21.59 180)
					(length 2.54)
					(hide yes)
					(name "NC"
						(effects
							(font
								(size 1.27 1.27)
							)
						)
					)
					(number "5"
						(effects
							(font
								(size 1.27 1.27)
							)
						)
					)
				)
				(pin no_connect line
					(at 20.32 -21.59 180)
					(length 2.54)
					(hide yes)
					(name "NC"
						(effects
							(font
								(size 1.27 1.27)
							)
						)
					)
					(number "9"
						(effects
							(font
								(size 1.27 1.27)
							)
						)
					)
				)
			)
		)
	(symbol "antmicroTestPoints:TP_0.75mm_SMD"
			(pin_names
				(hide yes)
			)
			(exclude_from_sim no)
			(in_bom no)
			(on_board yes)
			(property "Reference" "TP"
				(at 10.795 -1.27 0)
				(effects
					(font
						(size 1.27 1.27)
						(thickness 0.15)
					)
					(justify left bottom)
				)
			)
			(property "Value" "TP_0.75mm_SMD"
				(at 10.795 -3.81 0)
				(effects
					(font
						(size 1.27 1.27)
						(thickness 0.15)
					)
					(justify left bottom)
					(hide yes)
				)
			)
			(property "Footprint" "antmicro-footprints:TP_SMD_0.75mm"
				(at 10.795 -6.35 0)
				(effects
					(font
						(size 1.27 1.27)
						(thickness 0.15)
					)
					(justify left bottom)
					(hide yes)
				)
			)
			(property "Datasheet" ""
				(at 17.78 -12.7 0)
				(effects
					(font
						(size 1.27 1.27)
						(thickness 0.15)
					)
					(justify left bottom)
					(hide yes)
				)
			)
			(property "Description" "SMT test point"
				(at 0 0 0)
				(effects
					(font
						(size 1.27 1.27)
					)
					(hide yes)
				)
			)
			(property "MPN" ""
				(at 10.795 -11.43 0)
				(effects
					(font
						(size 1.27 1.27)
						(thickness 0.15)
					)
					(justify left bottom)
					(hide yes)
				)
			)
			(property "Manufacturer" ""
				(at 10.795 -6.35 0)
				(effects
					(font
						(size 1.27 1.27)
						(thickness 0.15)
					)
					(justify left bottom)
					(hide yes)
				)
			)
			(property "Author" "Antmicro"
				(at 10.795 -8.89 0)
				(effects
					(font
						(size 1.27 1.27)
						(thickness 0.15)
					)
					(justify left bottom)
					(hide yes)
				)
			)
			(property "License" "Apache-2.0"
				(at 10.795 -11.43 0)
				(effects
					(font
						(size 1.27 1.27)
						(thickness 0.15)
					)
					(justify left bottom)
					(hide yes)
				)
			)
			(property "ki_keywords" "TESTPOINT"
				(at 0 0 0)
				(effects
					(font
						(size 1.27 1.27)
					)
					(hide yes)
				)
			)
			(symbol "TP_0.75mm_SMD_1_1"
				(circle
					(center 3.175 0)
					(radius 0.635)
					(stroke
						(width 0.254)
						(type default)
					)
					(fill
						(type none)
					)
				)
				(pin passive line
					(at 0 0 0)
					(length 2.54)
					(name "1"
						(effects
							(font
								(size 1.27 1.27)
							)
						)
					)
					(number "1"
						(effects
							(font
								(size 1.27 1.27)
							)
						)
					)
				)
			)
		)
	(symbol "antmicroTestPoints:TP_1206_SMD_RCW-0C"
			(pin_names
				(hide yes)
			)
			(exclude_from_sim no)
			(in_bom yes)
			(on_board yes)
			(property "Reference" "TP"
				(at 17.78 -5.08 0)
				(effects
					(font
						(size 1.27 1.27)
						(thickness 0.15)
					)
					(justify left bottom)
				)
			)
			(property "Value" "TP_1206_SMD_RCW-0C"
				(at 17.78 -7.62 0)
				(effects
					(font
						(size 1.27 1.27)
						(thickness 0.15)
					)
					(justify left bottom)
				)
			)
			(property "Footprint" "antmicro-footprints:TP_1206_SMD_RCW-0C"
				(at 17.78 -10.16 0)
				(effects
					(font
						(size 1.27 1.27)
						(thickness 0.15)
					)
					(justify left bottom)
					(hide yes)
				)
			)
			(property "Datasheet" "https://www.te.com/commerce/DocumentDelivery/DDEController?Action=srchrtrv&DocNm=1773266&DocType=DS&DocLang=English"
				(at 17.78 -12.7 0)
				(effects
					(font
						(size 1.27 1.27)
						(thickness 0.15)
					)
					(justify left bottom)
					(hide yes)
				)
			)
			(property "Description" "Circuit Probe Pad, SMD, Test Point, 1206"
				(at 0 0 0)
				(effects
					(font
						(size 1.27 1.27)
					)
					(hide yes)
				)
			)
			(property "MPN" "RCW-0C"
				(at 17.78 -15.24 0)
				(effects
					(font
						(size 1.27 1.27)
						(thickness 0.15)
					)
					(justify left bottom)
					(hide yes)
				)
			)
			(property "Manufacturer" "TE Connectivity"
				(at 17.78 -17.78 0)
				(effects
					(font
						(size 1.27 1.27)
						(thickness 0.15)
					)
					(justify left bottom)
					(hide yes)
				)
			)
			(property "Author" "Antmicro"
				(at 17.78 -20.32 0)
				(effects
					(font
						(size 1.27 1.27)
						(thickness 0.15)
					)
					(justify left bottom)
					(hide yes)
				)
			)
			(property "License" "Apache-2.0"
				(at 17.78 -22.86 0)
				(effects
					(font
						(size 1.27 1.27)
						(thickness 0.15)
					)
					(justify left bottom)
					(hide yes)
				)
			)
			(symbol "TP_1206_SMD_RCW-0C_1_1"
				(circle
					(center 3.048 0)
					(radius 0.5588)
					(stroke
						(width 0.254)
						(type default)
					)
					(fill
						(type none)
					)
				)
				(pin passive line
					(at 0 0 0)
					(length 2.54)
					(name "1"
						(effects
							(font
								(size 1.27 1.27)
							)
						)
					)
					(number "1"
						(effects
							(font
								(size 1.27 1.27)
							)
						)
					)
				)
			)
		)
	(symbol "antmicroTransistorsFETsMOSFETsSingle:BSS138PW"
			(pin_names
				(offset 0)
			)
			(exclude_from_sim no)
			(in_bom yes)
			(on_board yes)
			(property "Reference" "Q"
				(at 3.81 -6.35 0)
				(effects
					(font
						(size 1.27 1.27)
						(thickness 0.15)
					)
					(justify left bottom)
				)
			)
			(property "Value" "BSS138PW"
				(at 22.86 -8.89 0)
				(effects
					(font
						(size 1.27 1.27)
						(thickness 0.15)
					)
					(justify left bottom)
				)
			)
			(property "Footprint" "antmicro-footprints:SC70-3"
				(at 22.86 -11.43 0)
				(effects
					(font
						(size 1.27 1.27)
						(thickness 0.15)
					)
					(justify left bottom)
					(hide yes)
				)
			)
			(property "Datasheet" "https://assets.nexperia.com/documents/data-sheet/BSS138PW.pdf"
				(at 22.86 -13.97 0)
				(effects
					(font
						(size 1.27 1.27)
						(thickness 0.15)
					)
					(justify left bottom)
					(hide yes)
				)
			)
			(property "Description" "Power MOSFET, N Channel, 60 V, 320 mA, 0.9 ohm, SOT-323, Surface Mount"
				(at 0 0 0)
				(effects
					(font
						(size 1.27 1.27)
					)
					(hide yes)
				)
			)
			(property "MPN" "BSS138PW"
				(at 22.86 -16.51 0)
				(effects
					(font
						(size 1.27 1.27)
						(thickness 0.15)
					)
					(justify left bottom)
					(hide yes)
				)
			)
			(property "Manufacturer" "Nexperia"
				(at 22.86 -19.05 0)
				(effects
					(font
						(size 1.27 1.27)
						(thickness 0.15)
					)
					(justify left bottom)
					(hide yes)
				)
			)
			(property "Author" "Antmicro"
				(at 22.86 -21.59 0)
				(effects
					(font
						(size 1.27 1.27)
						(thickness 0.15)
					)
					(justify left bottom)
					(hide yes)
				)
			)
			(property "License" "Apache-2.0"
				(at 22.86 -24.13 0)
				(effects
					(font
						(size 1.27 1.27)
						(thickness 0.15)
					)
					(justify left bottom)
					(hide yes)
				)
			)
			(property "ki_keywords" "SMT, TRANSISTOR, SEMICONDUCTOR, MOSFET, NMOS"
				(at 0 0 0)
				(effects
					(font
						(size 1.27 1.27)
					)
					(hide yes)
				)
			)
			(symbol "BSS138PW_1_1"
				(polyline
					(pts
						(xy 2.54 0) (xy 4.572 0) (xy 4.572 3.937)
					)
					(stroke
						(width 0.254)
						(type default)
					)
					(fill
						(type none)
					)
				)
				(polyline
					(pts
						(xy 5.08 4.445) (xy 5.08 3.429)
					)
					(stroke
						(width 0.254)
						(type default)
					)
					(fill
						(type background)
					)
				)
				(polyline
					(pts
						(xy 5.08 2.54) (xy 5.08 3.048)
					)
					(stroke
						(width 0.254)
						(type default)
					)
					(fill
						(type background)
					)
				)
				(polyline
					(pts
						(xy 5.08 2.54) (xy 5.08 2.032)
					)
					(stroke
						(width 0.254)
						(type default)
					)
					(fill
						(type background)
					)
				)
				(polyline
					(pts
						(xy 5.08 2.54) (xy 5.842 3.048) (xy 5.842 2.032) (xy 5.08 2.54)
					)
					(stroke
						(width 0.254)
						(type default)
					)
					(fill
						(type outline)
					)
				)
				(polyline
					(pts
						(xy 5.08 1.143) (xy 5.08 1.651)
					)
					(stroke
						(width 0.254)
						(type default)
					)
					(fill
						(type background)
					)
				)
				(polyline
					(pts
						(xy 5.08 1.143) (xy 5.08 0.635)
					)
					(stroke
						(width 0.254)
						(type default)
					)
					(fill
						(type background)
					)
				)
				(circle
					(center 6.35 2.54)
					(radius 3.302)
					(stroke
						(width 0.254)
						(type default)
					)
					(fill
						(type background)
					)
				)
				(polyline
					(pts
						(xy 7.493 0.635) (xy 8.636 0.635) (xy 8.636 3.937) (xy 8.636 4.445) (xy 7.493 4.445)
					)
					(stroke
						(width 0.254)
						(type default)
					)
					(fill
						(type background)
					)
				)
				(polyline
					(pts
						(xy 7.62 6.35) (xy 7.62 3.937) (xy 5.08 3.937)
					)
					(stroke
						(width 0.254)
						(type default)
					)
					(fill
						(type background)
					)
				)
				(circle
					(center 7.62 4.445)
					(radius 0.127)
					(stroke
						(width 0.254)
						(type default)
					)
					(fill
						(type background)
					)
				)
				(polyline
					(pts
						(xy 7.62 1.143) (xy 5.08 1.143)
					)
					(stroke
						(width 0.254)
						(type default)
					)
					(fill
						(type background)
					)
				)
				(circle
					(center 7.62 1.143)
					(radius 0.127)
					(stroke
						(width 0.254)
						(type default)
					)
					(fill
						(type background)
					)
				)
				(circle
					(center 7.62 0.635)
					(radius 0.127)
					(stroke
						(width 0.254)
						(type default)
					)
					(fill
						(type background)
					)
				)
				(polyline
					(pts
						(xy 7.62 -1.27) (xy 7.62 2.54) (xy 5.08 2.54)
					)
					(stroke
						(width 0.254)
						(type default)
					)
					(fill
						(type background)
					)
				)
				(polyline
					(pts
						(xy 8.636 3.048) (xy 8.128 2.286) (xy 9.144 2.286) (xy 8.636 3.048)
					)
					(stroke
						(width 0.254)
						(type default)
					)
					(fill
						(type outline)
					)
				)
				(polyline
					(pts
						(xy 9.144 3.048) (xy 8.128 3.048)
					)
					(stroke
						(width 0.254)
						(type default)
					)
					(fill
						(type background)
					)
				)
				(pin bidirectional line
					(at 0 0 0)
					(length 2.54)
					(name "G"
						(effects
							(font
								(size 1.27 1.27)
							)
						)
					)
					(number "1"
						(effects
							(font
								(size 1.27 1.27)
							)
						)
					)
				)
				(pin bidirectional line
					(at 7.62 8.89 270)
					(length 2.54)
					(name "D"
						(effects
							(font
								(size 1.27 1.27)
							)
						)
					)
					(number "3"
						(effects
							(font
								(size 1.27 1.27)
							)
						)
					)
				)
				(pin bidirectional line
					(at 7.62 -3.81 90)
					(length 2.54)
					(name "S"
						(effects
							(font
								(size 1.27 1.27)
							)
						)
					)
					(number "2"
						(effects
							(font
								(size 1.27 1.27)
							)
						)
					)
				)
			)
		)
	(symbol "antmicroTransistorsFETsMOSFETsSingle:IRLML6344TRPBF"
			(exclude_from_sim no)
			(in_bom yes)
			(on_board yes)
			(property "Reference" "Q"
				(at 22.86 -6.35 0)
				(effects
					(font
						(size 1.27 1.27)
						(thickness 0.15)
					)
					(justify left bottom)
				)
			)
			(property "Value" "IRLML6344TRPBF"
				(at 22.86 -8.89 0)
				(effects
					(font
						(size 1.27 1.27)
						(thickness 0.15)
					)
					(justify left bottom)
				)
			)
			(property "Footprint" "antmicro-footprints:SOT-23-3"
				(at 22.86 -11.43 0)
				(effects
					(font
						(size 1.27 1.27)
						(thickness 0.15)
					)
					(justify left bottom)
					(hide yes)
				)
			)
			(property "Datasheet" "https://www.infineon.com/dgdl/irlml6344pbf.pdf?fileId=5546d462533600a4015356689c44262c"
				(at 22.86 -13.97 0)
				(effects
					(font
						(size 1.27 1.27)
						(thickness 0.15)
					)
					(justify left bottom)
					(hide yes)
				)
			)
			(property "Description" "Power MOSFET, N Channel, 30 V, 5 A, 0.022 ohm, SOT-23, Surface Mount"
				(at 0 0 0)
				(effects
					(font
						(size 1.27 1.27)
					)
					(hide yes)
				)
			)
			(property "MPN" "IRLML6344TRPBF"
				(at 22.86 -16.51 0)
				(effects
					(font
						(size 1.27 1.27)
						(thickness 0.15)
					)
					(justify left bottom)
					(hide yes)
				)
			)
			(property "Manufacturer" "Infineon"
				(at 22.86 -19.05 0)
				(effects
					(font
						(size 1.27 1.27)
						(thickness 0.15)
					)
					(justify left bottom)
					(hide yes)
				)
			)
			(property "Author" "Antmicro"
				(at 22.86 -21.59 0)
				(effects
					(font
						(size 1.27 1.27)
						(thickness 0.15)
					)
					(justify left bottom)
					(hide yes)
				)
			)
			(property "License" "Apache-2.0"
				(at 22.86 -24.13 0)
				(effects
					(font
						(size 1.27 1.27)
						(thickness 0.15)
					)
					(justify left bottom)
					(hide yes)
				)
			)
			(property "ki_keywords" "SMT, TRANSISTOR, SEMICONDUCTOR, NMOS, MOSFET"
				(at 0 0 0)
				(effects
					(font
						(size 1.27 1.27)
					)
					(hide yes)
				)
			)
			(symbol "IRLML6344TRPBF_1_1"
				(polyline
					(pts
						(xy 2.54 0) (xy 4.572 0) (xy 4.572 3.937)
					)
					(stroke
						(width 0.254)
						(type default)
					)
					(fill
						(type none)
					)
				)
				(polyline
					(pts
						(xy 5.08 4.445) (xy 5.08 3.429)
					)
					(stroke
						(width 0.254)
						(type default)
					)
					(fill
						(type background)
					)
				)
				(polyline
					(pts
						(xy 5.08 2.54) (xy 5.08 3.048)
					)
					(stroke
						(width 0.254)
						(type default)
					)
					(fill
						(type background)
					)
				)
				(polyline
					(pts
						(xy 5.08 2.54) (xy 5.08 2.032)
					)
					(stroke
						(width 0.254)
						(type default)
					)
					(fill
						(type background)
					)
				)
				(polyline
					(pts
						(xy 5.08 2.54) (xy 5.842 3.048) (xy 5.842 2.032) (xy 5.08 2.54)
					)
					(stroke
						(width 0.254)
						(type default)
					)
					(fill
						(type outline)
					)
				)
				(polyline
					(pts
						(xy 5.08 1.143) (xy 5.08 1.651)
					)
					(stroke
						(width 0.254)
						(type default)
					)
					(fill
						(type background)
					)
				)
				(polyline
					(pts
						(xy 5.08 1.143) (xy 5.08 0.635)
					)
					(stroke
						(width 0.254)
						(type default)
					)
					(fill
						(type background)
					)
				)
				(circle
					(center 6.35 2.54)
					(radius 3.302)
					(stroke
						(width 0.254)
						(type default)
					)
					(fill
						(type background)
					)
				)
				(polyline
					(pts
						(xy 7.493 0.635) (xy 8.636 0.635) (xy 8.636 3.937) (xy 8.636 4.445) (xy 7.493 4.445)
					)
					(stroke
						(width 0.254)
						(type default)
					)
					(fill
						(type background)
					)
				)
				(polyline
					(pts
						(xy 7.62 6.35) (xy 7.62 3.937) (xy 5.08 3.937)
					)
					(stroke
						(width 0.254)
						(type default)
					)
					(fill
						(type background)
					)
				)
				(circle
					(center 7.62 4.445)
					(radius 0.127)
					(stroke
						(width 0.254)
						(type default)
					)
					(fill
						(type background)
					)
				)
				(polyline
					(pts
						(xy 7.62 1.143) (xy 5.08 1.143)
					)
					(stroke
						(width 0.254)
						(type default)
					)
					(fill
						(type background)
					)
				)
				(circle
					(center 7.62 1.143)
					(radius 0.127)
					(stroke
						(width 0.254)
						(type default)
					)
					(fill
						(type background)
					)
				)
				(circle
					(center 7.62 0.635)
					(radius 0.127)
					(stroke
						(width 0.254)
						(type default)
					)
					(fill
						(type background)
					)
				)
				(polyline
					(pts
						(xy 7.62 -1.27) (xy 7.62 2.54) (xy 5.08 2.54)
					)
					(stroke
						(width 0.254)
						(type default)
					)
					(fill
						(type background)
					)
				)
				(polyline
					(pts
						(xy 8.636 3.048) (xy 8.128 2.286) (xy 9.144 2.286) (xy 8.636 3.048)
					)
					(stroke
						(width 0.254)
						(type default)
					)
					(fill
						(type outline)
					)
				)
				(polyline
					(pts
						(xy 9.144 3.048) (xy 8.128 3.048)
					)
					(stroke
						(width 0.254)
						(type default)
					)
					(fill
						(type background)
					)
				)
				(pin bidirectional line
					(at 0 0 0)
					(length 2.54)
					(name "G"
						(effects
							(font
								(size 1.27 1.27)
							)
						)
					)
					(number "1"
						(effects
							(font
								(size 1.27 1.27)
							)
						)
					)
				)
				(pin bidirectional line
					(at 7.62 8.89 270)
					(length 2.54)
					(name "D"
						(effects
							(font
								(size 1.27 1.27)
							)
						)
					)
					(number "3"
						(effects
							(font
								(size 1.27 1.27)
							)
						)
					)
				)
				(pin bidirectional line
					(at 7.62 -3.81 90)
					(length 2.54)
					(name "S"
						(effects
							(font
								(size 1.27 1.27)
							)
						)
					)
					(number "2"
						(effects
							(font
								(size 1.27 1.27)
							)
						)
					)
				)
			)
		)
	(symbol "antmicroTransistorsFETsMOSFETsSingle:SI7613DN-T1-GE3"
			(pin_names
				(offset 0)
			)
			(exclude_from_sim no)
			(in_bom yes)
			(on_board yes)
			(property "Reference" "Q"
				(at 15.24 5.08 0)
				(effects
					(font
						(size 1.27 1.27)
						(thickness 0.15)
					)
					(justify left bottom)
				)
			)
			(property "Value" "SI7613DN-T1-GE3"
				(at 15.24 2.54 0)
				(effects
					(font
						(size 1.27 1.27)
						(thickness 0.15)
					)
					(justify left bottom)
				)
			)
			(property "Footprint" "antmicro-footprints:Vishay_PowerPAK_1212-8_Single"
				(at 15.24 1.27 0)
				(effects
					(font
						(size 1.27 1.27)
						(thickness 0.15)
					)
					(justify left bottom)
					(hide yes)
				)
			)
			(property "Datasheet" "https://www.vishay.com/docs/64809/si7613dn.pdf"
				(at 15.24 -1.27 0)
				(effects
					(font
						(size 1.27 1.27)
						(thickness 0.15)
					)
					(justify left bottom)
					(hide yes)
				)
			)
			(property "Description" "Power MOSFET, P Channel, 20 V, 35 A, 0.0072 ohm, PowerPAK 1212, Surface Mount"
				(at 0 0 0)
				(effects
					(font
						(size 1.27 1.27)
					)
					(hide yes)
				)
			)
			(property "MPN" "SI7613DN-T1-GE3"
				(at 15.24 -5.08 0)
				(effects
					(font
						(size 1.27 1.27)
						(thickness 0.15)
					)
					(justify left bottom)
					(hide yes)
				)
			)
			(property "Manufacturer" "Vishay"
				(at 15.24 -7.62 0)
				(effects
					(font
						(size 1.27 1.27)
						(thickness 0.15)
					)
					(justify left bottom)
					(hide yes)
				)
			)
			(property "Author" "Antmicro"
				(at 15.24 -10.16 0)
				(effects
					(font
						(size 1.27 1.27)
						(thickness 0.15)
					)
					(justify left bottom)
					(hide yes)
				)
			)
			(property "License" "Apache-2.0"
				(at 15.24 -12.7 0)
				(effects
					(font
						(size 1.27 1.27)
						(thickness 0.15)
					)
					(justify left bottom)
					(hide yes)
				)
			)
			(property "ki_keywords" "SMT, TRANSISTOR, SEMICONDUCTOR, MOSFET, PMOS"
				(at 0 0 0)
				(effects
					(font
						(size 1.27 1.27)
					)
					(hide yes)
				)
			)
			(symbol "SI7613DN-T1-GE3_1_1"
				(polyline
					(pts
						(xy 2.54 0) (xy 4.572 0) (xy 4.572 3.937)
					)
					(stroke
						(width 0.254)
						(type default)
					)
					(fill
						(type none)
					)
				)
				(polyline
					(pts
						(xy 5.08 4.445) (xy 5.08 3.429)
					)
					(stroke
						(width 0.254)
						(type default)
					)
					(fill
						(type background)
					)
				)
				(polyline
					(pts
						(xy 5.08 2.54) (xy 5.08 3.048)
					)
					(stroke
						(width 0.254)
						(type default)
					)
					(fill
						(type background)
					)
				)
				(polyline
					(pts
						(xy 5.08 2.54) (xy 5.08 2.032)
					)
					(stroke
						(width 0.254)
						(type default)
					)
					(fill
						(type background)
					)
				)
				(polyline
					(pts
						(xy 5.08 1.143) (xy 5.08 1.651)
					)
					(stroke
						(width 0.254)
						(type default)
					)
					(fill
						(type background)
					)
				)
				(polyline
					(pts
						(xy 5.08 1.143) (xy 5.08 0.635)
					)
					(stroke
						(width 0.254)
						(type default)
					)
					(fill
						(type background)
					)
				)
				(circle
					(center 6.35 2.54)
					(radius 3.302)
					(stroke
						(width 0.254)
						(type default)
					)
					(fill
						(type background)
					)
				)
				(polyline
					(pts
						(xy 7.239 2.54) (xy 6.477 3.048) (xy 6.477 2.032) (xy 7.239 2.54)
					)
					(stroke
						(width 0.254)
						(type default)
					)
					(fill
						(type outline)
					)
				)
				(polyline
					(pts
						(xy 7.493 0.635) (xy 8.636 0.635) (xy 8.636 3.937) (xy 8.636 4.445) (xy 7.493 4.445)
					)
					(stroke
						(width 0.254)
						(type default)
					)
					(fill
						(type background)
					)
				)
				(polyline
					(pts
						(xy 7.62 6.35) (xy 7.62 3.937) (xy 5.08 3.937)
					)
					(stroke
						(width 0.254)
						(type default)
					)
					(fill
						(type none)
					)
				)
				(circle
					(center 7.62 4.445)
					(radius 0.127)
					(stroke
						(width 0.254)
						(type default)
					)
					(fill
						(type background)
					)
				)
				(polyline
					(pts
						(xy 7.62 1.143) (xy 5.08 1.143)
					)
					(stroke
						(width 0.254)
						(type default)
					)
					(fill
						(type background)
					)
				)
				(circle
					(center 7.62 1.143)
					(radius 0.127)
					(stroke
						(width 0.254)
						(type default)
					)
					(fill
						(type background)
					)
				)
				(circle
					(center 7.62 0.635)
					(radius 0.127)
					(stroke
						(width 0.254)
						(type default)
					)
					(fill
						(type background)
					)
				)
				(polyline
					(pts
						(xy 7.62 -1.27) (xy 7.62 2.54) (xy 5.08 2.54)
					)
					(stroke
						(width 0.254)
						(type default)
					)
					(fill
						(type none)
					)
				)
				(polyline
					(pts
						(xy 8.636 2.286) (xy 8.128 3.048) (xy 9.144 3.048) (xy 8.636 2.286)
					)
					(stroke
						(width 0.254)
						(type default)
					)
					(fill
						(type outline)
					)
				)
				(polyline
					(pts
						(xy 9.144 2.2352) (xy 8.128 2.2352)
					)
					(stroke
						(width 0.254)
						(type default)
					)
					(fill
						(type background)
					)
				)
				(pin passive line
					(at 0 0 0)
					(length 2.54)
					(name "G"
						(effects
							(font
								(size 1.27 1.27)
							)
						)
					)
					(number "4"
						(effects
							(font
								(size 1.27 1.27)
							)
						)
					)
				)
				(pin passive line
					(at 7.62 8.89 270)
					(length 2.54)
					(name "D"
						(effects
							(font
								(size 1.27 1.27)
							)
						)
					)
					(number "5"
						(effects
							(font
								(size 1.27 1.27)
							)
						)
					)
				)
				(pin passive line
					(at 7.62 -3.81 90)
					(length 2.54)
					(name "S"
						(effects
							(font
								(size 1.27 1.27)
							)
						)
					)
					(number "1"
						(effects
							(font
								(size 1.27 1.27)
							)
						)
					)
				)
				(pin passive line
					(at 7.62 -3.81 90)
					(length 2.54)
					(hide yes)
					(name "S"
						(effects
							(font
								(size 1.27 1.27)
							)
						)
					)
					(number "2"
						(effects
							(font
								(size 1.27 1.27)
							)
						)
					)
				)
				(pin passive line
					(at 7.62 -3.81 90)
					(length 2.54)
					(hide yes)
					(name "S"
						(effects
							(font
								(size 1.27 1.27)
							)
						)
					)
					(number "3"
						(effects
							(font
								(size 1.27 1.27)
							)
						)
					)
				)
			)
		)
	(symbol "antmicroUSBConnectors:USB-A_WE_614004184726"
			(exclude_from_sim no)
			(in_bom yes)
			(on_board yes)
			(property "Reference" "J"
				(at 15.24 -5.08 0)
				(effects
					(font
						(size 1.27 1.27)
						(thickness 0.15)
					)
					(justify left bottom)
				)
			)
			(property "Value" "USB-A_WE_614004184726"
				(at 15.24 -7.62 0)
				(effects
					(font
						(size 1.27 1.27)
						(thickness 0.15)
					)
					(justify left bottom)
				)
			)
			(property "Footprint" "antmicro-footprints:USB-A_Receptacle_WE_614004184726"
				(at 15.24 -10.16 0)
				(effects
					(font
						(size 1.27 1.27)
						(thickness 0.15)
					)
					(justify left bottom)
					(hide yes)
				)
			)
			(property "Datasheet" "https://www.we-online.com/katalog/datasheet/614004184726.pdf"
				(at 15.24 -12.7 0)
				(effects
					(font
						(size 1.27 1.27)
						(thickness 0.15)
					)
					(justify left bottom)
					(hide yes)
				)
			)
			(property "Description" "USB-A (USB TYPE-A) USB 2.0 Receptacle Connector 4 Position Through Hole, Right Angle"
				(at 0 0 0)
				(effects
					(font
						(size 1.27 1.27)
					)
					(hide yes)
				)
			)
			(property "MPN" "614004184726"
				(at 15.24 -15.24 0)
				(effects
					(font
						(size 1.27 1.27)
						(thickness 0.15)
					)
					(justify left bottom)
					(hide yes)
				)
			)
			(property "Manufacturer" "Würth Elektronik"
				(at 15.24 -17.78 0)
				(effects
					(font
						(size 1.27 1.27)
						(thickness 0.15)
					)
					(justify left bottom)
					(hide yes)
				)
			)
			(property "Author" "Antmicro"
				(at 15.24 -20.32 0)
				(effects
					(font
						(size 1.27 1.27)
						(thickness 0.15)
					)
					(justify left bottom)
					(hide yes)
				)
			)
			(property "License" "Apache-2.0"
				(at 15.24 -22.86 0)
				(effects
					(font
						(size 1.27 1.27)
						(thickness 0.15)
					)
					(justify left bottom)
					(hide yes)
				)
			)
			(property "ki_keywords" "USB, CONNECTOR, THT, HORIZONTAL"
				(at 0 0 0)
				(effects
					(font
						(size 1.27 1.27)
					)
					(hide yes)
				)
			)
			(symbol "USB-A_WE_614004184726_1_1"
				(rectangle
					(start -12.7 2.54)
					(end -2.54 -15.24)
					(stroke
						(width 0.254)
						(type default)
					)
					(fill
						(type background)
					)
				)
				(rectangle
					(start -11.811 -0.508)
					(end -9.271 -0.762)
					(stroke
						(width 0.254)
						(type default)
					)
					(fill
						(type background)
					)
				)
				(circle
					(center -11.43 -3.556)
					(radius 0.635)
					(stroke
						(width 0.254)
						(type default)
					)
					(fill
						(type outline)
					)
				)
				(polyline
					(pts
						(xy -10.795 -3.556) (xy -10.16 -3.556) (xy -8.89 -2.286) (xy -8.255 -2.286)
					)
					(stroke
						(width 0.254)
						(type default)
					)
					(fill
						(type background)
					)
				)
				(polyline
					(pts
						(xy -10.16 -3.556) (xy -9.525 -3.556) (xy -8.89 -4.826) (xy -7.62 -4.826)
					)
					(stroke
						(width 0.254)
						(type default)
					)
					(fill
						(type background)
					)
				)
				(polyline
					(pts
						(xy -9.525 -3.556) (xy -6.985 -3.556)
					)
					(stroke
						(width 0.254)
						(type default)
					)
					(fill
						(type background)
					)
				)
				(rectangle
					(start -8.89 -1.143)
					(end -12.192 0.127)
					(stroke
						(width 0.254)
						(type default)
					)
					(fill
						(type background)
					)
				)
				(circle
					(center -8.255 -2.286)
					(radius 0.381)
					(stroke
						(width 0.254)
						(type default)
					)
					(fill
						(type outline)
					)
				)
				(rectangle
					(start -7.366 -4.445)
					(end -8.128 -5.207)
					(stroke
						(width 0.254)
						(type default)
					)
					(fill
						(type outline)
					)
				)
				(polyline
					(pts
						(xy -6.985 -2.921) (xy -6.985 -4.191) (xy -5.715 -3.556) (xy -6.985 -2.921)
					)
					(stroke
						(width 0.254)
						(type default)
					)
					(fill
						(type outline)
					)
				)
				(pin passive line
					(at 0 0 180)
					(length 2.54)
					(name "VBUS"
						(effects
							(font
								(size 1.27 1.27)
							)
						)
					)
					(number "1"
						(effects
							(font
								(size 1.27 1.27)
							)
						)
					)
				)
				(pin bidirectional line
					(at 0 -5.08 180)
					(length 2.54)
					(name "D+"
						(effects
							(font
								(size 1.27 1.27)
							)
						)
					)
					(number "3"
						(effects
							(font
								(size 1.27 1.27)
							)
						)
					)
				)
				(pin bidirectional line
					(at 0 -7.62 180)
					(length 2.54)
					(name "D-"
						(effects
							(font
								(size 1.27 1.27)
							)
						)
					)
					(number "2"
						(effects
							(font
								(size 1.27 1.27)
							)
						)
					)
				)
				(pin power_in line
					(at 0 -10.16 180)
					(length 2.54)
					(name "GND"
						(effects
							(font
								(size 1.27 1.27)
							)
						)
					)
					(number "4"
						(effects
							(font
								(size 1.27 1.27)
							)
						)
					)
				)
				(pin passive line
					(at 0 -12.7 180)
					(length 2.54)
					(name "SH"
						(effects
							(font
								(size 1.27 1.27)
							)
						)
					)
					(number "SH"
						(effects
							(font
								(size 1.27 1.27)
							)
						)
					)
				)
			)
		)
	(symbol "antmicroUSBConnectors:USB-C_GCT_USB4105-GF-A"
			(exclude_from_sim no)
			(in_bom yes)
			(on_board yes)
			(property "Reference" "J"
				(at 38.1 -2.54 0)
				(effects
					(font
						(size 1.27 1.27)
						(thickness 0.15)
					)
					(justify left bottom)
				)
			)
			(property "Value" "USB-C_GCT_USB4105-GF-A"
				(at 38.1 -5.08 0)
				(effects
					(font
						(size 1.27 1.27)
						(thickness 0.15)
					)
					(justify left bottom)
				)
			)
			(property "Footprint" "antmicro-footprints:USB-C_Receptacle_GCT_USB4105-GF-A"
				(at 38.1 -7.62 0)
				(effects
					(font
						(size 1.27 1.27)
						(thickness 0.15)
					)
					(justify left bottom)
					(hide yes)
				)
			)
			(property "Datasheet" "https://gct.co/files/drawings/usb4105.pdf"
				(at 38.1 -10.16 0)
				(effects
					(font
						(size 1.27 1.27)
						(thickness 0.15)
					)
					(justify left bottom)
					(hide yes)
				)
			)
			(property "Description" "USB-C (USB TYPE-C) USB 2.0 Receptacle Connector 24 (16+8 Dummy) Position Surface Mount, Right Angle"
				(at 0 0 0)
				(effects
					(font
						(size 1.27 1.27)
					)
					(hide yes)
				)
			)
			(property "Manufacturer" "GCT"
				(at 38.1 -12.7 0)
				(effects
					(font
						(size 1.27 1.27)
						(thickness 0.15)
					)
					(justify left bottom)
					(hide yes)
				)
			)
			(property "MPN" "USB4105-GF-A"
				(at 38.1 -15.24 0)
				(effects
					(font
						(size 1.27 1.27)
						(thickness 0.15)
					)
					(justify left bottom)
					(hide yes)
				)
			)
			(property "Author" "Antmicro"
				(at 38.1 -17.78 0)
				(effects
					(font
						(size 1.27 1.27)
						(thickness 0.15)
					)
					(justify left bottom)
					(hide yes)
				)
			)
			(property "License" "Apache-2.0"
				(at 38.1 -20.32 0)
				(effects
					(font
						(size 1.27 1.27)
						(thickness 0.15)
					)
					(justify left bottom)
					(hide yes)
				)
			)
			(property "VSD_Class" "USB-C"
				(at 38.1 -22.86 0)
				(effects
					(font
						(size 1.27 1.27)
					)
					(justify left bottom)
					(hide yes)
				)
			)
			(property "ki_keywords" "USB, CONNECTOR, SMT, HORIZONTAL"
				(at 0 0 0)
				(effects
					(font
						(size 1.27 1.27)
					)
					(hide yes)
				)
			)
			(symbol "USB-C_GCT_USB4105-GF-A_1_1"
				(rectangle
					(start -22.86 2.54)
					(end -3.81 -38.1)
					(stroke
						(width 0.254)
						(type default)
					)
					(fill
						(type background)
					)
				)
				(circle
					(center -20.066 -18.034)
					(radius 0.284)
					(stroke
						(width 0.254)
						(type default)
					)
					(fill
						(type outline)
					)
				)
				(polyline
					(pts
						(xy -19.812 -16.383) (xy -19.177 -15.24) (xy -18.542 -16.383) (xy -19.812 -16.383)
					)
					(stroke
						(width 0.254)
						(type default)
					)
					(fill
						(type outline)
					)
				)
				(polyline
					(pts
						(xy -19.177 -19.558) (xy -18.288 -18.669) (xy -18.288 -18.034)
					)
					(stroke
						(width 0.254)
						(type default)
					)
					(fill
						(type background)
					)
				)
				(polyline
					(pts
						(xy -19.177 -19.939) (xy -20.066 -19.05) (xy -20.066 -18.415)
					)
					(stroke
						(width 0.254)
						(type default)
					)
					(fill
						(type background)
					)
				)
				(polyline
					(pts
						(xy -19.177 -20.701) (xy -19.177 -16.383)
					)
					(stroke
						(width 0.254)
						(type default)
					)
					(fill
						(type background)
					)
				)
				(circle
					(center -19.177 -20.828)
					(radius 0.5236)
					(stroke
						(width 0.254)
						(type default)
					)
					(fill
						(type outline)
					)
				)
				(rectangle
					(start -18.669 -18.034)
					(end -17.907 -17.272)
					(stroke
						(width 0.254)
						(type default)
					)
					(fill
						(type outline)
					)
				)
				(polyline
					(pts
						(xy -16.51 -21.59) (xy -16.51 -13.97)
					)
					(stroke
						(width 0.254)
						(type default)
					)
					(fill
						(type background)
					)
				)
				(rectangle
					(start -15.24 -21.59)
					(end -13.97 -13.97)
					(stroke
						(width 0.254)
						(type default)
					)
					(fill
						(type outline)
					)
				)
				(arc
					(start -15.24 -13.97)
					(mid -14.605 -13.3377)
					(end -13.97 -13.97)
					(stroke
						(width 0.254)
						(type default)
					)
					(fill
						(type outline)
					)
				)
				(arc
					(start -15.24 -13.97)
					(mid -14.605 -13.3377)
					(end -13.97 -13.97)
					(stroke
						(width 0.254)
						(type default)
					)
					(fill
						(type background)
					)
				)
				(arc
					(start -16.51 -13.97)
					(mid -14.605 -12.0733)
					(end -12.7 -13.97)
					(stroke
						(width 0.254)
						(type default)
					)
					(fill
						(type background)
					)
				)
				(arc
					(start -12.7 -21.59)
					(mid -14.605 -23.4867)
					(end -16.51 -21.59)
					(stroke
						(width 0.254)
						(type default)
					)
					(fill
						(type background)
					)
				)
				(arc
					(start -13.97 -21.59)
					(mid -14.605 -22.2223)
					(end -15.24 -21.59)
					(stroke
						(width 0.254)
						(type default)
					)
					(fill
						(type outline)
					)
				)
				(arc
					(start -13.97 -21.59)
					(mid -14.605 -22.2223)
					(end -15.24 -21.59)
					(stroke
						(width 0.254)
						(type default)
					)
					(fill
						(type background)
					)
				)
				(polyline
					(pts
						(xy -12.7 -13.97) (xy -12.7 -21.59)
					)
					(stroke
						(width 0.254)
						(type default)
					)
					(fill
						(type background)
					)
				)
				(pin passive line
					(at 0 0 180)
					(length 3.81)
					(name "VBUS"
						(effects
							(font
								(size 1.27 1.27)
							)
						)
					)
					(number "A4"
						(effects
							(font
								(size 1.27 1.27)
							)
						)
					)
				)
				(pin passive line
					(at 0 0 180)
					(length 3.81)
					(hide yes)
					(name "VBUS"
						(effects
							(font
								(size 1.27 1.27)
							)
						)
					)
					(number "A9"
						(effects
							(font
								(size 1.27 1.27)
							)
						)
					)
				)
				(pin passive line
					(at 0 0 180)
					(length 3.81)
					(hide yes)
					(name "VBUS"
						(effects
							(font
								(size 1.27 1.27)
							)
						)
					)
					(number "B4"
						(effects
							(font
								(size 1.27 1.27)
							)
						)
					)
				)
				(pin passive line
					(at 0 0 180)
					(length 3.81)
					(hide yes)
					(name "VBUS"
						(effects
							(font
								(size 1.27 1.27)
							)
						)
					)
					(number "B9"
						(effects
							(font
								(size 1.27 1.27)
							)
						)
					)
				)
				(pin bidirectional line
					(at 0 -5.08 180)
					(length 3.81)
					(name "CC_{1}"
						(effects
							(font
								(size 1.27 1.27)
							)
						)
					)
					(number "A5"
						(effects
							(font
								(size 1.27 1.27)
							)
						)
					)
				)
				(pin bidirectional line
					(at 0 -7.62 180)
					(length 3.81)
					(name "CC_{2}"
						(effects
							(font
								(size 1.27 1.27)
							)
						)
					)
					(number "B5"
						(effects
							(font
								(size 1.27 1.27)
							)
						)
					)
				)
				(pin bidirectional line
					(at 0 -12.7 180)
					(length 3.81)
					(name "D_{A}+"
						(effects
							(font
								(size 1.27 1.27)
							)
						)
					)
					(number "A6"
						(effects
							(font
								(size 1.27 1.27)
							)
						)
					)
				)
				(pin bidirectional line
					(at 0 -15.24 180)
					(length 3.81)
					(name "D_{A}-"
						(effects
							(font
								(size 1.27 1.27)
							)
						)
					)
					(number "A7"
						(effects
							(font
								(size 1.27 1.27)
							)
						)
					)
				)
				(pin bidirectional line
					(at 0 -17.78 180)
					(length 3.81)
					(name "D_{B}+"
						(effects
							(font
								(size 1.27 1.27)
							)
						)
					)
					(number "B6"
						(effects
							(font
								(size 1.27 1.27)
							)
						)
					)
				)
				(pin bidirectional line
					(at 0 -20.32 180)
					(length 3.81)
					(name "D_{B}-"
						(effects
							(font
								(size 1.27 1.27)
							)
						)
					)
					(number "B7"
						(effects
							(font
								(size 1.27 1.27)
							)
						)
					)
				)
				(pin bidirectional line
					(at 0 -25.4 180)
					(length 3.81)
					(name "SBU_{1}"
						(effects
							(font
								(size 1.27 1.27)
							)
						)
					)
					(number "A8"
						(effects
							(font
								(size 1.27 1.27)
							)
						)
					)
				)
				(pin bidirectional line
					(at 0 -27.94 180)
					(length 3.81)
					(name "SBU_{2}"
						(effects
							(font
								(size 1.27 1.27)
							)
						)
					)
					(number "B8"
						(effects
							(font
								(size 1.27 1.27)
							)
						)
					)
				)
				(pin power_in line
					(at 0 -33.02 180)
					(length 3.81)
					(name "GND"
						(effects
							(font
								(size 1.27 1.27)
							)
						)
					)
					(number "A1"
						(effects
							(font
								(size 1.27 1.27)
							)
						)
					)
				)
				(pin passive line
					(at 0 -33.02 180)
					(length 3.81)
					(hide yes)
					(name "GND"
						(effects
							(font
								(size 1.27 1.27)
							)
						)
					)
					(number "A12"
						(effects
							(font
								(size 1.27 1.27)
							)
						)
					)
				)
				(pin passive line
					(at 0 -33.02 180)
					(length 3.81)
					(hide yes)
					(name "GND"
						(effects
							(font
								(size 1.27 1.27)
							)
						)
					)
					(number "B1"
						(effects
							(font
								(size 1.27 1.27)
							)
						)
					)
				)
				(pin passive line
					(at 0 -33.02 180)
					(length 3.81)
					(hide yes)
					(name "GND"
						(effects
							(font
								(size 1.27 1.27)
							)
						)
					)
					(number "B12"
						(effects
							(font
								(size 1.27 1.27)
							)
						)
					)
				)
				(pin passive line
					(at 0 -35.56 180)
					(length 3.81)
					(name "SH"
						(effects
							(font
								(size 1.27 1.27)
							)
						)
					)
					(number "SH"
						(effects
							(font
								(size 1.27 1.27)
							)
						)
					)
				)
			)
		)
	(symbol "antmicroVideoConnectors:HDMI-A_TE_2007435-1"
			(exclude_from_sim no)
			(in_bom yes)
			(on_board yes)
			(property "Reference" "J"
				(at 35.56 -2.54 0)
				(effects
					(font
						(size 1.27 1.27)
						(thickness 0.15)
					)
					(justify left bottom)
				)
			)
			(property "Value" "HDMI-A_TE_2007435-1"
				(at 35.56 -5.08 0)
				(effects
					(font
						(size 1.27 1.27)
						(thickness 0.15)
					)
					(justify left bottom)
				)
			)
			(property "Footprint" "antmicro-footprints:HDMI-A_Receptacle_TE_2007435-1"
				(at 35.56 -7.62 0)
				(effects
					(font
						(size 1.27 1.27)
						(thickness 0.15)
					)
					(justify left bottom)
					(hide yes)
				)
			)
			(property "Datasheet" "https://www.te.com/usa-en/product-2007435-1.html"
				(at 35.56 -10.16 0)
				(effects
					(font
						(size 1.27 1.27)
						(thickness 0.15)
					)
					(justify left bottom)
					(hide yes)
				)
			)
			(property "Description" "HDMI Receptacle Connector 19 Position Panel Mount, Through Hole, Right Angle"
				(at 0 0 0)
				(effects
					(font
						(size 1.27 1.27)
					)
					(hide yes)
				)
			)
			(property "MPN" "2007435-1"
				(at 35.56 -12.7 0)
				(effects
					(font
						(size 1.27 1.27)
						(thickness 0.15)
					)
					(justify left bottom)
					(hide yes)
				)
			)
			(property "Manufacturer" "TE Connectivity"
				(at 35.56 -15.24 0)
				(effects
					(font
						(size 1.27 1.27)
						(thickness 0.15)
					)
					(justify left bottom)
					(hide yes)
				)
			)
			(property "Author" "Antmicro"
				(at 35.56 -17.78 0)
				(effects
					(font
						(size 1.27 1.27)
						(thickness 0.15)
					)
					(justify left bottom)
					(hide yes)
				)
			)
			(property "License" "Apache-2.0"
				(at 35.56 -20.32 0)
				(effects
					(font
						(size 1.27 1.27)
						(thickness 0.15)
					)
					(justify left bottom)
					(hide yes)
				)
			)
			(property "ki_keywords" "HDMI, CONNECTOR, THT"
				(at 0 0 0)
				(effects
					(font
						(size 1.27 1.27)
					)
					(hide yes)
				)
			)
			(symbol "HDMI-A_TE_2007435-1_0_0"
				(polyline
					(pts
						(xy 13.97 0) (xy 13.97 1.524) (xy 13.97 0.762) (xy 15.875 0.762) (xy 15.875 1.524) (xy 15.875 0)
					)
					(stroke
						(width 0.635)
						(type default)
					)
					(fill
						(type none)
					)
				)
				(polyline
					(pts
						(xy 16.637 1.524) (xy 18.288 1.524) (xy 18.542 1.27) (xy 18.542 0.254) (xy 18.288 0) (xy 16.637 0)
						(xy 16.637 0.762)
					)
					(stroke
						(width 0.635)
						(type default)
					)
					(fill
						(type none)
					)
				)
				(polyline
					(pts
						(xy 22.098 0) (xy 22.098 1.524)
					)
					(stroke
						(width 0.635)
						(type default)
					)
					(fill
						(type none)
					)
				)
			)
			(symbol "HDMI-A_TE_2007435-1_0_1"
				(polyline
					(pts
						(xy 10.16 -15.24) (xy 13.97 -15.24) (xy 15.875 -17.145) (xy 15.875 -28.575) (xy 13.97 -30.48)
						(xy 10.16 -30.48) (xy 10.16 -15.24)
					)
					(stroke
						(width 0.635)
						(type default)
					)
					(fill
						(type none)
					)
				)
				(polyline
					(pts
						(xy 12.065 -16.51) (xy 13.335 -16.51) (xy 13.97 -17.145) (xy 13.97 -28.575) (xy 13.335 -29.21)
						(xy 12.065 -29.21) (xy 12.065 -16.51)
					)
					(stroke
						(width 0.254)
						(type default)
					)
					(fill
						(type outline)
					)
				)
				(polyline
					(pts
						(xy 19.304 0) (xy 19.304 1.524) (xy 20.32 1.524) (xy 20.32 0) (xy 20.32 1.524) (xy 21.082 1.524)
						(xy 21.336 1.27) (xy 21.336 0)
					)
					(stroke
						(width 0.635)
						(type default)
					)
					(fill
						(type none)
					)
				)
			)
			(symbol "HDMI-A_TE_2007435-1_1_1"
				(rectangle
					(start 2.54 2.54)
					(end 22.86 -53.34)
					(stroke
						(width 0.254)
						(type default)
					)
					(fill
						(type background)
					)
				)
				(pin bidirectional line
					(at 0 0 0)
					(length 2.54)
					(name "D2+"
						(effects
							(font
								(size 1.27 1.27)
							)
						)
					)
					(number "1"
						(effects
							(font
								(size 1.27 1.27)
							)
						)
					)
				)
				(pin bidirectional line
					(at 0 -2.54 0)
					(length 2.54)
					(name "D2-"
						(effects
							(font
								(size 1.27 1.27)
							)
						)
					)
					(number "3"
						(effects
							(font
								(size 1.27 1.27)
							)
						)
					)
				)
				(pin bidirectional line
					(at 0 -7.62 0)
					(length 2.54)
					(name "D1+"
						(effects
							(font
								(size 1.27 1.27)
							)
						)
					)
					(number "4"
						(effects
							(font
								(size 1.27 1.27)
							)
						)
					)
				)
				(pin bidirectional line
					(at 0 -10.16 0)
					(length 2.54)
					(name "D1-"
						(effects
							(font
								(size 1.27 1.27)
							)
						)
					)
					(number "6"
						(effects
							(font
								(size 1.27 1.27)
							)
						)
					)
				)
				(pin bidirectional line
					(at 0 -15.24 0)
					(length 2.54)
					(name "D0+"
						(effects
							(font
								(size 1.27 1.27)
							)
						)
					)
					(number "7"
						(effects
							(font
								(size 1.27 1.27)
							)
						)
					)
				)
				(pin bidirectional line
					(at 0 -17.78 0)
					(length 2.54)
					(name "D0-"
						(effects
							(font
								(size 1.27 1.27)
							)
						)
					)
					(number "9"
						(effects
							(font
								(size 1.27 1.27)
							)
						)
					)
				)
				(pin bidirectional line
					(at 0 -22.86 0)
					(length 2.54)
					(name "CK+"
						(effects
							(font
								(size 1.27 1.27)
							)
						)
					)
					(number "10"
						(effects
							(font
								(size 1.27 1.27)
							)
						)
					)
				)
				(pin bidirectional line
					(at 0 -25.4 0)
					(length 2.54)
					(name "CK-"
						(effects
							(font
								(size 1.27 1.27)
							)
						)
					)
					(number "12"
						(effects
							(font
								(size 1.27 1.27)
							)
						)
					)
				)
				(pin bidirectional line
					(at 0 -30.48 0)
					(length 2.54)
					(name "SCL"
						(effects
							(font
								(size 1.27 1.27)
							)
						)
					)
					(number "15"
						(effects
							(font
								(size 1.27 1.27)
							)
						)
					)
				)
				(pin bidirectional line
					(at 0 -33.02 0)
					(length 2.54)
					(name "SDA"
						(effects
							(font
								(size 1.27 1.27)
							)
						)
					)
					(number "16"
						(effects
							(font
								(size 1.27 1.27)
							)
						)
					)
				)
				(pin bidirectional line
					(at 0 -38.1 0)
					(length 2.54)
					(name "CEC"
						(effects
							(font
								(size 1.27 1.27)
							)
						)
					)
					(number "13"
						(effects
							(font
								(size 1.27 1.27)
							)
						)
					)
				)
				(pin bidirectional line
					(at 0 -43.18 0)
					(length 2.54)
					(name "HPD/HEAC-"
						(effects
							(font
								(size 1.27 1.27)
							)
						)
					)
					(number "19"
						(effects
							(font
								(size 1.27 1.27)
							)
						)
					)
					(alternate "HEAC-" passive line)
					(alternate "HPD" passive line)
				)
				(pin bidirectional line
					(at 0 -45.72 0)
					(length 2.54)
					(name "UTILITY/HEAC+"
						(effects
							(font
								(size 1.27 1.27)
							)
						)
					)
					(number "14"
						(effects
							(font
								(size 1.27 1.27)
							)
						)
					)
					(alternate "HEAC+" passive line)
					(alternate "UTILITY" passive line)
				)
				(pin power_in line
					(at 0 -50.8 0)
					(length 2.54)
					(name "+5V"
						(effects
							(font
								(size 1.27 1.27)
							)
						)
					)
					(number "18"
						(effects
							(font
								(size 1.27 1.27)
							)
						)
					)
				)
				(pin passive line
					(at 25.4 -38.1 180)
					(length 2.54)
					(name "D2S"
						(effects
							(font
								(size 1.27 1.27)
							)
						)
					)
					(number "2"
						(effects
							(font
								(size 1.27 1.27)
							)
						)
					)
				)
				(pin passive line
					(at 25.4 -40.64 180)
					(length 2.54)
					(name "D1S"
						(effects
							(font
								(size 1.27 1.27)
							)
						)
					)
					(number "5"
						(effects
							(font
								(size 1.27 1.27)
							)
						)
					)
				)
				(pin passive line
					(at 25.4 -43.18 180)
					(length 2.54)
					(name "D0S"
						(effects
							(font
								(size 1.27 1.27)
							)
						)
					)
					(number "8"
						(effects
							(font
								(size 1.27 1.27)
							)
						)
					)
				)
				(pin passive line
					(at 25.4 -45.72 180)
					(length 2.54)
					(name "CKS"
						(effects
							(font
								(size 1.27 1.27)
							)
						)
					)
					(number "11"
						(effects
							(font
								(size 1.27 1.27)
							)
						)
					)
				)
				(pin power_in line
					(at 25.4 -48.26 180)
					(length 2.54)
					(name "GND"
						(effects
							(font
								(size 1.27 1.27)
							)
						)
					)
					(number "17"
						(effects
							(font
								(size 1.27 1.27)
							)
						)
					)
				)
				(pin passive line
					(at 25.4 -50.8 180)
					(length 2.54)
					(name "SH"
						(effects
							(font
								(size 1.27 1.27)
							)
						)
					)
					(number "SH"
						(effects
							(font
								(size 1.27 1.27)
							)
						)
					)
				)
			)
		)
	(symbol "antmicroWire2BoardConnectors:JST_SH_1x4_BM04B-SRSS-TB-LF-SN"
			(pin_names
				(hide yes)
			)
			(exclude_from_sim no)
			(in_bom yes)
			(on_board yes)
			(property "Reference" "J"
				(at 20.32 -5.08 0)
				(effects
					(font
						(size 1.27 1.27)
						(thickness 0.15)
					)
					(justify left bottom)
				)
			)
			(property "Value" "JST_SH_1x4_BM04B-SRSS-TB-LF-SN"
				(at 20.32 -7.62 0)
				(effects
					(font
						(size 1.27 1.27)
						(thickness 0.15)
					)
					(justify left bottom)
					(hide yes)
				)
			)
			(property "Footprint" "antmicro-footprints:Conn_JST_SH_1x4_BM04B-SRSS-TB-LF-SN"
				(at 20.32 -10.16 0)
				(effects
					(font
						(size 1.27 1.27)
						(thickness 0.15)
					)
					(justify left bottom)
					(hide yes)
				)
			)
			(property "Datasheet" "https://www.jst-mfg.com/product/pdf/eng/eSH.pdf"
				(at 20.32 -12.7 0)
				(effects
					(font
						(size 1.27 1.27)
						(thickness 0.15)
					)
					(justify left bottom)
					(hide yes)
				)
			)
			(property "Description" "Pin Header, Top Entry, Wire-to-Board, 1 mm, 1 Rows, 4 Contacts, Surface Mount, SR"
				(at 0 0 0)
				(effects
					(font
						(size 1.27 1.27)
					)
					(hide yes)
				)
			)
			(property "MPN" "BM04B-SRSS-TB(LF)(SN) "
				(at 20.32 -15.24 0)
				(effects
					(font
						(size 1.27 1.27)
						(thickness 0.15)
					)
					(justify left bottom)
				)
			)
			(property "Manufacturer" "JST Automotive Connectors"
				(at 20.32 -17.78 0)
				(effects
					(font
						(size 1.27 1.27)
						(thickness 0.15)
					)
					(justify left bottom)
					(hide yes)
				)
			)
			(property "Author" "Antmicro"
				(at 20.32 -20.32 0)
				(effects
					(font
						(size 1.27 1.27)
						(thickness 0.15)
					)
					(justify left bottom)
					(hide yes)
				)
			)
			(property "License" "Apache-2.0"
				(at 20.32 -22.86 0)
				(effects
					(font
						(size 1.27 1.27)
						(thickness 0.15)
					)
					(justify left bottom)
					(hide yes)
				)
			)
			(property "ki_keywords" "VERTICAL, SMT, WIRE-BOARD, CONNECTOR"
				(at 0 0 0)
				(effects
					(font
						(size 1.27 1.27)
					)
					(hide yes)
				)
			)
			(symbol "JST_SH_1x4_BM04B-SRSS-TB-LF-SN_1_1"
				(rectangle
					(start 2.54 1.27)
					(end 5.08 -11.43)
					(stroke
						(width 0.254)
						(type default)
					)
					(fill
						(type background)
					)
				)
				(rectangle
					(start 2.54 0.127)
					(end 3.81 -0.127)
					(stroke
						(width 0.254)
						(type default)
					)
					(fill
						(type background)
					)
				)
				(rectangle
					(start 2.54 -2.413)
					(end 3.81 -2.667)
					(stroke
						(width 0.254)
						(type default)
					)
					(fill
						(type background)
					)
				)
				(rectangle
					(start 2.54 -4.953)
					(end 3.81 -5.207)
					(stroke
						(width 0.254)
						(type default)
					)
					(fill
						(type background)
					)
				)
				(rectangle
					(start 2.54 -7.493)
					(end 3.81 -7.747)
					(stroke
						(width 0.254)
						(type default)
					)
					(fill
						(type background)
					)
				)
				(rectangle
					(start 2.54 -10.033)
					(end 3.81 -10.287)
					(stroke
						(width 0.254)
						(type default)
					)
					(fill
						(type background)
					)
				)
				(pin passive line
					(at 0 0 0)
					(length 2.54)
					(name "Pin_1"
						(effects
							(font
								(size 1.27 1.27)
							)
						)
					)
					(number "1"
						(effects
							(font
								(size 1.27 1.27)
							)
						)
					)
				)
				(pin passive line
					(at 0 -2.54 0)
					(length 2.54)
					(name "Pin_2"
						(effects
							(font
								(size 1.27 1.27)
							)
						)
					)
					(number "2"
						(effects
							(font
								(size 1.27 1.27)
							)
						)
					)
				)
				(pin passive line
					(at 0 -5.08 0)
					(length 2.54)
					(name "Pin_3"
						(effects
							(font
								(size 1.27 1.27)
							)
						)
					)
					(number "3"
						(effects
							(font
								(size 1.27 1.27)
							)
						)
					)
				)
				(pin passive line
					(at 0 -7.62 0)
					(length 2.54)
					(name "Pin_4"
						(effects
							(font
								(size 1.27 1.27)
							)
						)
					)
					(number "4"
						(effects
							(font
								(size 1.27 1.27)
							)
						)
					)
				)
				(pin passive line
					(at 0 -10.16 0)
					(length 2.54)
					(name "MP"
						(effects
							(font
								(size 1.27 1.27)
							)
						)
					)
					(number "MP"
						(effects
							(font
								(size 1.27 1.27)
							)
						)
					)
				)
			)
		)
	(symbol "antmicropower:+0V675_VREF"
			(power)
			(pin_names
				(offset 0)
			)
			(exclude_from_sim no)
			(in_bom yes)
			(on_board yes)
			(property "Reference" "#PWR"
				(at 0 -3.81 0)
				(effects
					(font
						(size 1.27 1.27)
					)
					(hide yes)
				)
			)
			(property "Value" "+0V675_VREF"
				(at 0 3.556 0)
				(effects
					(font
						(size 1.27 1.27)
					)
				)
			)
			(property "Footprint" ""
				(at 0 0 0)
				(effects
					(font
						(size 1.27 1.27)
					)
					(hide yes)
				)
			)
			(property "Datasheet" ""
				(at 0 0 0)
				(effects
					(font
						(size 1.27 1.27)
					)
					(hide yes)
				)
			)
			(property "Description" ""
				(at 0 0 0)
				(effects
					(font
						(size 1.27 1.27)
					)
					(hide yes)
				)
			)
			(symbol "+0V675_VREF_0_1"
				(polyline
					(pts
						(xy -0.762 1.27) (xy 0 2.54)
					)
					(stroke
						(width 0)
						(type default)
					)
					(fill
						(type none)
					)
				)
				(polyline
					(pts
						(xy 0 2.54) (xy 0.762 1.27)
					)
					(stroke
						(width 0)
						(type default)
					)
					(fill
						(type none)
					)
				)
				(polyline
					(pts
						(xy 0 0) (xy 0 2.54)
					)
					(stroke
						(width 0)
						(type default)
					)
					(fill
						(type none)
					)
				)
			)
			(symbol "+0V675_VREF_1_1"
				(pin power_in line
					(at 0 0 90)
					(length 0)
					(hide yes)
					(name "+0V675_VREF"
						(effects
							(font
								(size 1.27 1.27)
							)
						)
					)
					(number "1"
						(effects
							(font
								(size 1.27 1.27)
							)
						)
					)
				)
			)
		)
	(symbol "antmicropower:+0V675_VTT"
			(power)
			(pin_names
				(offset 0)
			)
			(exclude_from_sim no)
			(in_bom yes)
			(on_board yes)
			(property "Reference" "#PWR"
				(at 0 -3.81 0)
				(effects
					(font
						(size 1.27 1.27)
					)
					(hide yes)
				)
			)
			(property "Value" "+0V675_VTT"
				(at 0 3.556 0)
				(effects
					(font
						(size 1.27 1.27)
					)
				)
			)
			(property "Footprint" ""
				(at 0 0 0)
				(effects
					(font
						(size 1.27 1.27)
					)
					(hide yes)
				)
			)
			(property "Datasheet" ""
				(at 0 0 0)
				(effects
					(font
						(size 1.27 1.27)
					)
					(hide yes)
				)
			)
			(property "Description" ""
				(at 0 0 0)
				(effects
					(font
						(size 1.27 1.27)
					)
					(hide yes)
				)
			)
			(symbol "+0V675_VTT_0_1"
				(polyline
					(pts
						(xy -0.762 1.27) (xy 0 2.54)
					)
					(stroke
						(width 0)
						(type default)
					)
					(fill
						(type none)
					)
				)
				(polyline
					(pts
						(xy 0 2.54) (xy 0.762 1.27)
					)
					(stroke
						(width 0)
						(type default)
					)
					(fill
						(type none)
					)
				)
				(polyline
					(pts
						(xy 0 0) (xy 0 2.54)
					)
					(stroke
						(width 0)
						(type default)
					)
					(fill
						(type none)
					)
				)
			)
			(symbol "+0V675_VTT_1_1"
				(pin power_in line
					(at 0 0 90)
					(length 0)
					(hide yes)
					(name "+0V675_VTT"
						(effects
							(font
								(size 1.27 1.27)
							)
						)
					)
					(number "1"
						(effects
							(font
								(size 1.27 1.27)
							)
						)
					)
				)
			)
		)
	(symbol "antmicropower:+1V0"
			(power)
			(pin_names
				(offset 0)
			)
			(exclude_from_sim no)
			(in_bom yes)
			(on_board yes)
			(property "Reference" "#PWR"
				(at 0 -3.81 0)
				(effects
					(font
						(size 1.27 1.27)
					)
					(hide yes)
				)
			)
			(property "Value" "+1V0"
				(at 0 3.556 0)
				(effects
					(font
						(size 1.27 1.27)
					)
				)
			)
			(property "Footprint" ""
				(at 0 0 0)
				(effects
					(font
						(size 1.27 1.27)
					)
					(hide yes)
				)
			)
			(property "Datasheet" ""
				(at 0 0 0)
				(effects
					(font
						(size 1.27 1.27)
					)
					(hide yes)
				)
			)
			(property "Description" ""
				(at 0 0 0)
				(effects
					(font
						(size 1.27 1.27)
					)
					(hide yes)
				)
			)
			(symbol "+1V0_0_1"
				(polyline
					(pts
						(xy -0.762 1.27) (xy 0 2.54)
					)
					(stroke
						(width 0)
						(type default)
					)
					(fill
						(type none)
					)
				)
				(polyline
					(pts
						(xy 0 2.54) (xy 0.762 1.27)
					)
					(stroke
						(width 0)
						(type default)
					)
					(fill
						(type none)
					)
				)
				(polyline
					(pts
						(xy 0 0) (xy 0 2.54)
					)
					(stroke
						(width 0)
						(type default)
					)
					(fill
						(type none)
					)
				)
			)
			(symbol "+1V0_1_1"
				(pin power_in line
					(at 0 0 90)
					(length 0)
					(hide yes)
					(name "+1V0"
						(effects
							(font
								(size 1.27 1.27)
							)
						)
					)
					(number "1"
						(effects
							(font
								(size 1.27 1.27)
							)
						)
					)
				)
			)
		)
	(symbol "antmicropower:+1V0_MGTAVCC"
			(power)
			(pin_names
				(offset 0)
			)
			(exclude_from_sim no)
			(in_bom yes)
			(on_board yes)
			(property "Reference" "#PWR?"
				(at 0 -3.81 0)
				(effects
					(font
						(size 1.27 1.27)
					)
					(hide yes)
				)
			)
			(property "Value" "+1V0_MGTAVCC"
				(at 0 3.81 0)
				(effects
					(font
						(size 1.27 1.27)
					)
				)
			)
			(property "Footprint" ""
				(at 0 0 0)
				(effects
					(font
						(size 1.27 1.27)
					)
					(hide yes)
				)
			)
			(property "Datasheet" ""
				(at 0 0 0)
				(effects
					(font
						(size 1.27 1.27)
					)
					(hide yes)
				)
			)
			(property "Description" ""
				(at 0 0 0)
				(effects
					(font
						(size 1.27 1.27)
					)
					(hide yes)
				)
			)
			(symbol "+1V0_MGTAVCC_0_1"
				(polyline
					(pts
						(xy -0.762 1.27) (xy 0 2.54)
					)
					(stroke
						(width 0)
						(type default)
					)
					(fill
						(type none)
					)
				)
				(polyline
					(pts
						(xy 0 2.54) (xy 0.762 1.27)
					)
					(stroke
						(width 0)
						(type default)
					)
					(fill
						(type none)
					)
				)
				(polyline
					(pts
						(xy 0 0) (xy 0 2.54)
					)
					(stroke
						(width 0)
						(type default)
					)
					(fill
						(type none)
					)
				)
			)
			(symbol "+1V0_MGTAVCC_1_1"
				(pin power_in line
					(at 0 0 90)
					(length 0)
					(hide yes)
					(name "+1V0_MGTAVCC"
						(effects
							(font
								(size 1.27 1.27)
							)
						)
					)
					(number "1"
						(effects
							(font
								(size 1.27 1.27)
							)
						)
					)
				)
			)
		)
	(symbol "antmicropower:+1V2"
			(power)
			(pin_names
				(offset 0)
			)
			(exclude_from_sim no)
			(in_bom yes)
			(on_board yes)
			(property "Reference" "#PWR"
				(at 0 -3.81 0)
				(effects
					(font
						(size 1.27 1.27)
					)
					(hide yes)
				)
			)
			(property "Value" "+1V2"
				(at 0 3.556 0)
				(effects
					(font
						(size 1.27 1.27)
					)
				)
			)
			(property "Footprint" ""
				(at 0 0 0)
				(effects
					(font
						(size 1.27 1.27)
					)
					(hide yes)
				)
			)
			(property "Datasheet" ""
				(at 0 0 0)
				(effects
					(font
						(size 1.27 1.27)
					)
					(hide yes)
				)
			)
			(property "Description" ""
				(at 0 0 0)
				(effects
					(font
						(size 1.27 1.27)
					)
					(hide yes)
				)
			)
			(symbol "+1V2_0_1"
				(polyline
					(pts
						(xy -0.762 1.27) (xy 0 2.54)
					)
					(stroke
						(width 0)
						(type default)
					)
					(fill
						(type none)
					)
				)
				(polyline
					(pts
						(xy 0 2.54) (xy 0.762 1.27)
					)
					(stroke
						(width 0)
						(type default)
					)
					(fill
						(type none)
					)
				)
				(polyline
					(pts
						(xy 0 0) (xy 0 2.54)
					)
					(stroke
						(width 0)
						(type default)
					)
					(fill
						(type none)
					)
				)
			)
			(symbol "+1V2_1_1"
				(pin power_in line
					(at 0 0 90)
					(length 0)
					(hide yes)
					(name "+1V2"
						(effects
							(font
								(size 1.27 1.27)
							)
						)
					)
					(number "1"
						(effects
							(font
								(size 1.27 1.27)
							)
						)
					)
				)
			)
		)
	(symbol "antmicropower:+1V2_MGTAVTT"
			(power)
			(pin_names
				(offset 0)
			)
			(exclude_from_sim no)
			(in_bom yes)
			(on_board yes)
			(property "Reference" "#PWR?"
				(at 0 -3.81 0)
				(effects
					(font
						(size 1.27 1.27)
					)
					(hide yes)
				)
			)
			(property "Value" "+1V2_MGTAVTT"
				(at 0 3.81 0)
				(effects
					(font
						(size 1.27 1.27)
					)
				)
			)
			(property "Footprint" ""
				(at 0 0 0)
				(effects
					(font
						(size 1.27 1.27)
					)
					(hide yes)
				)
			)
			(property "Datasheet" ""
				(at 0 0 0)
				(effects
					(font
						(size 1.27 1.27)
					)
					(hide yes)
				)
			)
			(property "Description" ""
				(at 0 0 0)
				(effects
					(font
						(size 1.27 1.27)
					)
					(hide yes)
				)
			)
			(symbol "+1V2_MGTAVTT_0_1"
				(polyline
					(pts
						(xy -0.762 1.27) (xy 0 2.54)
					)
					(stroke
						(width 0)
						(type default)
					)
					(fill
						(type none)
					)
				)
				(polyline
					(pts
						(xy 0 2.54) (xy 0.762 1.27)
					)
					(stroke
						(width 0)
						(type default)
					)
					(fill
						(type none)
					)
				)
				(polyline
					(pts
						(xy 0 0) (xy 0 2.54)
					)
					(stroke
						(width 0)
						(type default)
					)
					(fill
						(type none)
					)
				)
			)
			(symbol "+1V2_MGTAVTT_1_1"
				(pin power_in line
					(at 0 0 90)
					(length 0)
					(hide yes)
					(name "+1V2_MGTAVTT"
						(effects
							(font
								(size 1.27 1.27)
							)
						)
					)
					(number "1"
						(effects
							(font
								(size 1.27 1.27)
							)
						)
					)
				)
			)
		)
	(symbol "antmicropower:+1V35"
			(power)
			(pin_names
				(offset 0)
			)
			(exclude_from_sim no)
			(in_bom yes)
			(on_board yes)
			(property "Reference" "#PWR"
				(at 0 -3.81 0)
				(effects
					(font
						(size 1.27 1.27)
					)
					(hide yes)
				)
			)
			(property "Value" "+1V35"
				(at 0 3.556 0)
				(effects
					(font
						(size 1.27 1.27)
					)
				)
			)
			(property "Footprint" ""
				(at 0 0 0)
				(effects
					(font
						(size 1.27 1.27)
					)
					(hide yes)
				)
			)
			(property "Datasheet" ""
				(at 0 0 0)
				(effects
					(font
						(size 1.27 1.27)
					)
					(hide yes)
				)
			)
			(property "Description" ""
				(at 0 0 0)
				(effects
					(font
						(size 1.27 1.27)
					)
					(hide yes)
				)
			)
			(symbol "+1V35_0_1"
				(polyline
					(pts
						(xy -0.762 1.27) (xy 0 2.54)
					)
					(stroke
						(width 0)
						(type default)
					)
					(fill
						(type none)
					)
				)
				(polyline
					(pts
						(xy 0 2.54) (xy 0.762 1.27)
					)
					(stroke
						(width 0)
						(type default)
					)
					(fill
						(type none)
					)
				)
				(polyline
					(pts
						(xy 0 0) (xy 0 2.54)
					)
					(stroke
						(width 0)
						(type default)
					)
					(fill
						(type none)
					)
				)
			)
			(symbol "+1V35_1_1"
				(pin power_in line
					(at 0 0 90)
					(length 0)
					(hide yes)
					(name "+1V35"
						(effects
							(font
								(size 1.27 1.27)
							)
						)
					)
					(number "1"
						(effects
							(font
								(size 1.27 1.27)
							)
						)
					)
				)
			)
		)
	(symbol "antmicropower:+1V8"
			(power)
			(pin_numbers
				(hide yes)
			)
			(pin_names
				(hide yes)
			)
			(exclude_from_sim no)
			(in_bom yes)
			(on_board yes)
			(property "Reference" "#PWR"
				(at 15.24 -2.54 0)
				(effects
					(font
						(size 1.27 1.27)
						(thickness 0.15)
					)
					(justify left bottom)
					(hide yes)
				)
			)
			(property "Value" "+1V8"
				(at -3.175 2.54 0)
				(effects
					(font
						(size 1.27 1.27)
						(thickness 0.15)
					)
					(justify left bottom)
				)
			)
			(property "Footprint" ""
				(at 15.24 -7.62 0)
				(effects
					(font
						(size 1.27 1.27)
						(thickness 0.15)
					)
					(justify left bottom)
					(hide yes)
				)
			)
			(property "Datasheet" ""
				(at 15.24 -10.16 0)
				(effects
					(font
						(size 1.27 1.27)
						(thickness 0.15)
					)
					(justify left bottom)
					(hide yes)
				)
			)
			(property "Description" ""
				(at 0 0 0)
				(effects
					(font
						(size 1.27 1.27)
					)
					(hide yes)
				)
			)
			(property "Author" "Antmicro"
				(at 15.24 -5.08 0)
				(effects
					(font
						(size 1.27 1.27)
						(thickness 0.15)
					)
					(justify left bottom)
					(hide yes)
				)
			)
			(property "License" "Apache-2.0"
				(at 15.24 -7.62 0)
				(effects
					(font
						(size 1.27 1.27)
						(thickness 0.15)
					)
					(justify left bottom)
					(hide yes)
				)
			)
			(symbol "+1V8_1_1"
				(polyline
					(pts
						(xy -0.762 1.27) (xy 0 2.54)
					)
					(stroke
						(width 0)
						(type default)
					)
					(fill
						(type background)
					)
				)
				(polyline
					(pts
						(xy 0 2.54) (xy 0.762 1.27)
					)
					(stroke
						(width 0)
						(type default)
					)
					(fill
						(type background)
					)
				)
				(polyline
					(pts
						(xy 0 0) (xy 0 2.54)
					)
					(stroke
						(width 0)
						(type default)
					)
					(fill
						(type background)
					)
				)
				(pin power_in line
					(at 0 0 90)
					(length 0)
					(hide yes)
					(name "+1V8"
						(effects
							(font
								(size 1.27 1.27)
							)
						)
					)
					(number "1"
						(effects
							(font
								(size 1.27 1.27)
							)
						)
					)
				)
			)
		)
	(symbol "antmicropower:+1V85_ADC"
			(power)
			(pin_names
				(offset 0)
			)
			(exclude_from_sim no)
			(in_bom yes)
			(on_board yes)
			(property "Reference" "#PWR"
				(at 0 -3.81 0)
				(effects
					(font
						(size 1.27 1.27)
					)
					(hide yes)
				)
			)
			(property "Value" "+1V85_ADC"
				(at 0 3.556 0)
				(effects
					(font
						(size 1.27 1.27)
					)
				)
			)
			(property "Footprint" ""
				(at 0 0 0)
				(effects
					(font
						(size 1.27 1.27)
					)
					(hide yes)
				)
			)
			(property "Datasheet" ""
				(at 0 0 0)
				(effects
					(font
						(size 1.27 1.27)
					)
					(hide yes)
				)
			)
			(property "Description" ""
				(at 0 0 0)
				(effects
					(font
						(size 1.27 1.27)
					)
					(hide yes)
				)
			)
			(symbol "+1V85_ADC_0_1"
				(polyline
					(pts
						(xy -0.762 1.27) (xy 0 2.54)
					)
					(stroke
						(width 0)
						(type default)
					)
					(fill
						(type none)
					)
				)
				(polyline
					(pts
						(xy 0 2.54) (xy 0.762 1.27)
					)
					(stroke
						(width 0)
						(type default)
					)
					(fill
						(type none)
					)
				)
				(polyline
					(pts
						(xy 0 0) (xy 0 2.54)
					)
					(stroke
						(width 0)
						(type default)
					)
					(fill
						(type none)
					)
				)
			)
			(symbol "+1V85_ADC_1_1"
				(pin power_in line
					(at 0 0 90)
					(length 0)
					(hide yes)
					(name "+1V85_ADC"
						(effects
							(font
								(size 1.27 1.27)
							)
						)
					)
					(number "1"
						(effects
							(font
								(size 1.27 1.27)
							)
						)
					)
				)
			)
		)
	(symbol "antmicropower:+3.3V"
			(power)
			(pin_names
				(offset 0)
			)
			(exclude_from_sim no)
			(in_bom yes)
			(on_board yes)
			(property "Reference" "#PWR"
				(at 0 -3.81 0)
				(effects
					(font
						(size 1.27 1.27)
					)
					(hide yes)
				)
			)
			(property "Value" "+3.3V"
				(at 0 3.556 0)
				(effects
					(font
						(size 1.27 1.27)
					)
				)
			)
			(property "Footprint" ""
				(at 0 0 0)
				(effects
					(font
						(size 1.27 1.27)
					)
					(hide yes)
				)
			)
			(property "Datasheet" ""
				(at 0 0 0)
				(effects
					(font
						(size 1.27 1.27)
					)
					(hide yes)
				)
			)
			(property "Description" ""
				(at 0 0 0)
				(effects
					(font
						(size 1.27 1.27)
					)
					(hide yes)
				)
			)
			(symbol "+3.3V_0_1"
				(polyline
					(pts
						(xy -0.762 1.27) (xy 0 2.54)
					)
					(stroke
						(width 0)
						(type default)
					)
					(fill
						(type none)
					)
				)
				(polyline
					(pts
						(xy 0 2.54) (xy 0.762 1.27)
					)
					(stroke
						(width 0)
						(type default)
					)
					(fill
						(type none)
					)
				)
				(polyline
					(pts
						(xy 0 0) (xy 0 2.54)
					)
					(stroke
						(width 0)
						(type default)
					)
					(fill
						(type none)
					)
				)
			)
			(symbol "+3.3V_1_1"
				(pin power_in line
					(at 0 0 90)
					(length 0)
					(hide yes)
					(name "+3V3"
						(effects
							(font
								(size 1.27 1.27)
							)
						)
					)
					(number "1"
						(effects
							(font
								(size 1.27 1.27)
							)
						)
					)
				)
			)
		)
	(symbol "antmicropower:+3V3_AON"
			(power)
			(pin_names
				(offset 0)
			)
			(exclude_from_sim no)
			(in_bom yes)
			(on_board yes)
			(property "Reference" "#PWR"
				(at 0 -3.81 0)
				(effects
					(font
						(size 1.27 1.27)
					)
					(hide yes)
				)
			)
			(property "Value" "+3V3_AON"
				(at 0 3.556 0)
				(effects
					(font
						(size 1.27 1.27)
					)
				)
			)
			(property "Footprint" ""
				(at 0 0 0)
				(effects
					(font
						(size 1.27 1.27)
					)
					(hide yes)
				)
			)
			(property "Datasheet" ""
				(at 0 0 0)
				(effects
					(font
						(size 1.27 1.27)
					)
					(hide yes)
				)
			)
			(property "Description" ""
				(at 0 0 0)
				(effects
					(font
						(size 1.27 1.27)
					)
					(hide yes)
				)
			)
			(symbol "+3V3_AON_0_1"
				(polyline
					(pts
						(xy -0.762 1.27) (xy 0 2.54)
					)
					(stroke
						(width 0)
						(type default)
					)
					(fill
						(type none)
					)
				)
				(polyline
					(pts
						(xy 0 2.54) (xy 0.762 1.27)
					)
					(stroke
						(width 0)
						(type default)
					)
					(fill
						(type none)
					)
				)
				(polyline
					(pts
						(xy 0 0) (xy 0 2.54)
					)
					(stroke
						(width 0)
						(type default)
					)
					(fill
						(type none)
					)
				)
			)
			(symbol "+3V3_AON_1_1"
				(pin power_in line
					(at 0 0 90)
					(length 0)
					(hide yes)
					(name "+3V3_AON"
						(effects
							(font
								(size 1.27 1.27)
							)
						)
					)
					(number "1"
						(effects
							(font
								(size 1.27 1.27)
							)
						)
					)
				)
			)
		)
	(symbol "antmicropower:+5V"
			(power)
			(pin_numbers
				(hide yes)
			)
			(pin_names
				(hide yes)
			)
			(exclude_from_sim no)
			(in_bom yes)
			(on_board yes)
			(property "Reference" "#PWR"
				(at 15.24 -2.54 0)
				(effects
					(font
						(size 1.27 1.27)
						(thickness 0.15)
					)
					(justify left bottom)
					(hide yes)
				)
			)
			(property "Value" "+5V"
				(at 15.24 -5.08 0)
				(effects
					(font
						(size 1.27 1.27)
						(thickness 0.15)
					)
					(justify left bottom)
				)
			)
			(property "Footprint" ""
				(at 15.24 -7.62 0)
				(effects
					(font
						(size 1.27 1.27)
						(thickness 0.15)
					)
					(justify left bottom)
					(hide yes)
				)
			)
			(property "Datasheet" ""
				(at 15.24 -10.16 0)
				(effects
					(font
						(size 1.27 1.27)
						(thickness 0.15)
					)
					(justify left bottom)
					(hide yes)
				)
			)
			(property "Description" ""
				(at 0 0 0)
				(effects
					(font
						(size 1.27 1.27)
					)
					(hide yes)
				)
			)
			(property "Author" "Antmicro"
				(at 15.24 -7.62 0)
				(effects
					(font
						(size 1.27 1.27)
						(thickness 0.15)
					)
					(justify left bottom)
					(hide yes)
				)
			)
			(property "License" "Apache-2.0"
				(at 15.24 -10.16 0)
				(effects
					(font
						(size 1.27 1.27)
						(thickness 0.15)
					)
					(justify left bottom)
					(hide yes)
				)
			)
			(symbol "+5V_1_1"
				(polyline
					(pts
						(xy -0.762 1.27) (xy 0 2.54)
					)
					(stroke
						(width 0)
						(type default)
					)
					(fill
						(type background)
					)
				)
				(polyline
					(pts
						(xy 0 2.54) (xy 0.762 1.27)
					)
					(stroke
						(width 0)
						(type default)
					)
					(fill
						(type background)
					)
				)
				(polyline
					(pts
						(xy 0 0) (xy 0 2.54)
					)
					(stroke
						(width 0)
						(type default)
					)
					(fill
						(type background)
					)
				)
				(pin power_in line
					(at 0 0 90)
					(length 0)
					(name "+5V"
						(effects
							(font
								(size 1.27 1.27)
							)
						)
					)
					(number "1"
						(effects
							(font
								(size 1.27 1.27)
							)
						)
					)
				)
			)
		)
	(symbol "antmicropower:GND"
			(power)
			(pin_numbers
				(hide yes)
			)
			(pin_names
				(hide yes)
			)
			(exclude_from_sim no)
			(in_bom yes)
			(on_board yes)
			(property "Reference" "#PWR"
				(at 8.89 -2.54 0)
				(effects
					(font
						(size 1.27 1.27)
						(thickness 0.15)
					)
					(justify left bottom)
					(hide yes)
				)
			)
			(property "Value" "GND"
				(at 8.89 -5.08 0)
				(effects
					(font
						(size 1.27 1.27)
						(thickness 0.15)
					)
					(justify left bottom)
				)
			)
			(property "Footprint" ""
				(at 8.89 -7.62 0)
				(effects
					(font
						(size 1.27 1.27)
						(thickness 0.15)
					)
					(justify left bottom)
					(hide yes)
				)
			)
			(property "Datasheet" ""
				(at 8.89 -12.7 0)
				(effects
					(font
						(size 1.27 1.27)
						(thickness 0.15)
					)
					(justify left bottom)
					(hide yes)
				)
			)
			(property "Description" ""
				(at 0 0 0)
				(effects
					(font
						(size 1.27 1.27)
					)
					(hide yes)
				)
			)
			(property "Author" "Antmicro"
				(at 8.89 -7.62 0)
				(effects
					(font
						(size 1.27 1.27)
						(thickness 0.15)
					)
					(justify left bottom)
					(hide yes)
				)
			)
			(property "License" "Apache-2.0"
				(at 8.89 -10.16 0)
				(effects
					(font
						(size 1.27 1.27)
						(thickness 0.15)
					)
					(justify left bottom)
					(hide yes)
				)
			)
			(symbol "GND_1_1"
				(polyline
					(pts
						(xy 0 0) (xy 0 -1.27) (xy 1.27 -1.27) (xy 0 -2.54) (xy -1.27 -1.27) (xy 0 -1.27)
					)
					(stroke
						(width 0)
						(type default)
					)
					(fill
						(type none)
					)
				)
				(pin power_in line
					(at 0 0 270)
					(length 0)
					(name "GND"
						(effects
							(font
								(size 1.27 1.27)
							)
						)
					)
					(number "1"
						(effects
							(font
								(size 1.27 1.27)
							)
						)
					)
				)
			)
		)
	(symbol "antmicropower:GNDD"
			(power)
			(pin_numbers
				(hide yes)
			)
			(pin_names
				(hide yes)
			)
			(exclude_from_sim no)
			(in_bom yes)
			(on_board yes)
			(property "Reference" "#PWR"
				(at 15.24 -2.54 0)
				(effects
					(font
						(size 1.27 1.27)
						(thickness 0.15)
					)
					(justify left bottom)
					(hide yes)
				)
			)
			(property "Value" "GNDD"
				(at 15.24 -5.08 0)
				(effects
					(font
						(size 1.27 1.27)
						(thickness 0.15)
					)
					(justify left bottom)
				)
			)
			(property "Footprint" ""
				(at 15.24 -10.16 0)
				(effects
					(font
						(size 1.27 1.27)
						(thickness 0.15)
					)
					(justify left bottom)
					(hide yes)
				)
			)
			(property "Datasheet" ""
				(at 15.24 -12.7 0)
				(effects
					(font
						(size 1.27 1.27)
						(thickness 0.15)
					)
					(justify left bottom)
					(hide yes)
				)
			)
			(property "Description" ""
				(at 0 0 0)
				(effects
					(font
						(size 1.27 1.27)
					)
					(hide yes)
				)
			)
			(property "Author" "Antmicro"
				(at 15.24 -7.62 0)
				(effects
					(font
						(size 1.27 1.27)
						(thickness 0.15)
					)
					(justify left bottom)
					(hide yes)
				)
			)
			(property "License" "Apache-2.0"
				(at 15.24 -10.16 0)
				(effects
					(font
						(size 1.27 1.27)
						(thickness 0.15)
					)
					(justify left bottom)
					(hide yes)
				)
			)
			(symbol "GNDD_1_1"
				(rectangle
					(start -1.27 -1.524)
					(end 1.27 -2.032)
					(stroke
						(width 0)
						(type default)
					)
					(fill
						(type outline)
					)
				)
				(polyline
					(pts
						(xy 0 0) (xy 0 -1.524)
					)
					(stroke
						(width 0)
						(type default)
					)
					(fill
						(type background)
					)
				)
				(pin power_in line
					(at 0 0 270)
					(length 0)
					(name "GNDD"
						(effects
							(font
								(size 1.27 1.27)
							)
						)
					)
					(number "1"
						(effects
							(font
								(size 1.27 1.27)
							)
						)
					)
				)
			)
		)
	(symbol "antmicropower:PWR_FLAG"
			(power)
			(pin_numbers
				(hide yes)
			)
			(pin_names
				(offset 0)
				(hide yes)
			)
			(exclude_from_sim no)
			(in_bom yes)
			(on_board yes)
			(property "Reference" "#FLG"
				(at 0 1.905 0)
				(effects
					(font
						(size 1.27 1.27)
					)
					(hide yes)
				)
			)
			(property "Value" "PWR_FLAG"
				(at 0 3.81 0)
				(effects
					(font
						(size 1.27 1.27)
					)
				)
			)
			(property "Footprint" ""
				(at 0 0 0)
				(effects
					(font
						(size 1.27 1.27)
					)
					(hide yes)
				)
			)
			(property "Datasheet" ""
				(at 0 0 0)
				(effects
					(font
						(size 1.27 1.27)
					)
					(hide yes)
				)
			)
			(property "Description" ""
				(at 0 0 0)
				(effects
					(font
						(size 1.27 1.27)
					)
					(hide yes)
				)
			)
			(symbol "PWR_FLAG_0_0"
				(pin power_out line
					(at 0 0 90)
					(length 0)
					(name "pwr"
						(effects
							(font
								(size 1.27 1.27)
							)
						)
					)
					(number "1"
						(effects
							(font
								(size 1.27 1.27)
							)
						)
					)
				)
			)
			(symbol "PWR_FLAG_0_1"
				(polyline
					(pts
						(xy 0 0) (xy 0 1.27) (xy -1.016 1.905) (xy 0 2.54) (xy 1.016 1.905) (xy 0 1.27)
					)
					(stroke
						(width 0)
						(type default)
					)
					(fill
						(type none)
					)
				)
			)
		)
	(symbol "antmicropower:VCC_USR_A"
			(power)
			(pin_names
				(offset 0)
			)
			(exclude_from_sim no)
			(in_bom yes)
			(on_board yes)
			(property "Reference" "#PWR?"
				(at 0 -3.81 0)
				(effects
					(font
						(size 1.27 1.27)
					)
					(hide yes)
				)
			)
			(property "Value" "VCC_USR_A"
				(at 0 3.81 0)
				(effects
					(font
						(size 1.27 1.27)
					)
				)
			)
			(property "Footprint" ""
				(at 0 0 0)
				(effects
					(font
						(size 1.27 1.27)
					)
					(hide yes)
				)
			)
			(property "Datasheet" ""
				(at 0 0 0)
				(effects
					(font
						(size 1.27 1.27)
					)
					(hide yes)
				)
			)
			(property "Description" ""
				(at 0 0 0)
				(effects
					(font
						(size 1.27 1.27)
					)
					(hide yes)
				)
			)
			(symbol "VCC_USR_A_0_1"
				(polyline
					(pts
						(xy -0.762 1.27) (xy 0 2.54)
					)
					(stroke
						(width 0)
						(type default)
					)
					(fill
						(type none)
					)
				)
				(polyline
					(pts
						(xy 0 2.54) (xy 0.762 1.27)
					)
					(stroke
						(width 0)
						(type default)
					)
					(fill
						(type none)
					)
				)
				(polyline
					(pts
						(xy 0 0) (xy 0 2.54)
					)
					(stroke
						(width 0)
						(type default)
					)
					(fill
						(type none)
					)
				)
			)
			(symbol "VCC_USR_A_1_1"
				(pin power_in line
					(at 0 0 90)
					(length 0)
					(hide yes)
					(name "VCC_USR_A"
						(effects
							(font
								(size 1.27 1.27)
							)
						)
					)
					(number "1"
						(effects
							(font
								(size 1.27 1.27)
							)
						)
					)
				)
			)
		)
	(symbol "antmicropower:VCC_USR_B"
			(power)
			(pin_names
				(offset 0)
			)
			(exclude_from_sim no)
			(in_bom yes)
			(on_board yes)
			(property "Reference" "#PWR?"
				(at 0 -3.81 0)
				(effects
					(font
						(size 1.27 1.27)
					)
					(hide yes)
				)
			)
			(property "Value" "VCC_USR_B"
				(at 0 3.81 0)
				(effects
					(font
						(size 1.27 1.27)
					)
				)
			)
			(property "Footprint" ""
				(at 0 0 0)
				(effects
					(font
						(size 1.27 1.27)
					)
					(hide yes)
				)
			)
			(property "Datasheet" ""
				(at 0 0 0)
				(effects
					(font
						(size 1.27 1.27)
					)
					(hide yes)
				)
			)
			(property "Description" ""
				(at 0 0 0)
				(effects
					(font
						(size 1.27 1.27)
					)
					(hide yes)
				)
			)
			(symbol "VCC_USR_B_0_1"
				(polyline
					(pts
						(xy -0.762 1.27) (xy 0 2.54)
					)
					(stroke
						(width 0)
						(type default)
					)
					(fill
						(type none)
					)
				)
				(polyline
					(pts
						(xy 0 2.54) (xy 0.762 1.27)
					)
					(stroke
						(width 0)
						(type default)
					)
					(fill
						(type none)
					)
				)
				(polyline
					(pts
						(xy 0 0) (xy 0 2.54)
					)
					(stroke
						(width 0)
						(type default)
					)
					(fill
						(type none)
					)
				)
			)
			(symbol "VCC_USR_B_1_1"
				(pin power_in line
					(at 0 0 90)
					(length 0)
					(hide yes)
					(name "VCC_USR_B"
						(effects
							(font
								(size 1.27 1.27)
							)
						)
					)
					(number "1"
						(effects
							(font
								(size 1.27 1.27)
							)
						)
					)
				)
			)
		)
	(symbol "antmicropower:VDC"
			(power)
			(pin_names
				(offset 0)
			)
			(exclude_from_sim no)
			(in_bom yes)
			(on_board yes)
			(property "Reference" "#PWR"
				(at 0 -2.54 0)
				(effects
					(font
						(size 1.27 1.27)
					)
					(hide yes)
				)
			)
			(property "Value" "VDC"
				(at 0 6.35 0)
				(effects
					(font
						(size 1.27 1.27)
					)
				)
			)
			(property "Footprint" ""
				(at 0 0 0)
				(effects
					(font
						(size 1.27 1.27)
					)
					(hide yes)
				)
			)
			(property "Datasheet" ""
				(at 0 0 0)
				(effects
					(font
						(size 1.27 1.27)
					)
					(hide yes)
				)
			)
			(property "Description" ""
				(at 0 0 0)
				(effects
					(font
						(size 1.27 1.27)
					)
					(hide yes)
				)
			)
			(symbol "VDC_0_1"
				(polyline
					(pts
						(xy -0.762 1.27) (xy 0 2.54)
					)
					(stroke
						(width 0)
						(type default)
					)
					(fill
						(type none)
					)
				)
				(polyline
					(pts
						(xy 0 2.54) (xy 0.762 1.27)
					)
					(stroke
						(width 0)
						(type default)
					)
					(fill
						(type none)
					)
				)
				(polyline
					(pts
						(xy 0 0) (xy 0 2.54)
					)
					(stroke
						(width 0)
						(type default)
					)
					(fill
						(type none)
					)
				)
			)
			(symbol "VDC_1_1"
				(pin power_in line
					(at 0 0 90)
					(length 0)
					(hide yes)
					(name "VDC"
						(effects
							(font
								(size 1.27 1.27)
							)
						)
					)
					(number "1"
						(effects
							(font
								(size 1.27 1.27)
							)
						)
					)
				)
			)
		)
	(symbol "k410t-devboard:Net-Tie_2"
			(pin_numbers
				(hide yes)
			)
			(pin_names
				(hide yes)
			)
			(exclude_from_sim no)
			(in_bom yes)
			(on_board yes)
			(property "Reference" "TP"
				(at 21.59 0 0)
				(effects
					(font
						(size 1.27 1.27)
						(thickness 0.15)
					)
					(justify left bottom)
				)
			)
			(property "Value" "Net-Tie_2"
				(at 21.59 -2.54 0)
				(effects
					(font
						(size 1.27 1.27)
						(thickness 0.15)
					)
					(justify left bottom)
				)
			)
			(property "Footprint" "k410t-devboard-footprints:NetTie-2_SMD_Pad0.127mm"
				(at 21.59 -5.08 0)
				(effects
					(font
						(size 1.27 1.27)
						(thickness 0.15)
					)
					(justify left bottom)
					(hide yes)
				)
			)
			(property "Datasheet" ""
				(at 21.59 -7.62 0)
				(effects
					(font
						(size 1.27 1.27)
						(thickness 0.15)
					)
					(justify left bottom)
					(hide yes)
				)
			)
			(property "Description" "Net tie, 2 pins"
				(at 0 0 0)
				(effects
					(font
						(size 1.27 1.27)
					)
					(hide yes)
				)
			)
			(property "MPN" ""
				(at 21.59 -8.89 0)
				(effects
					(font
						(size 1.27 1.27)
					)
					(justify left)
					(hide yes)
				)
			)
			(property "Manufacturer" ""
				(at 21.59 -11.43 0)
				(effects
					(font
						(size 1.27 1.27)
					)
					(justify left)
					(hide yes)
				)
			)
			(property "Author" "Antmicro"
				(at 21.59 -15.24 0)
				(effects
					(font
						(size 1.27 1.27)
						(thickness 0.15)
					)
					(justify left bottom)
					(hide yes)
				)
			)
			(property "License" "Apache-2.0"
				(at 21.59 -17.78 0)
				(effects
					(font
						(size 1.27 1.27)
						(thickness 0.15)
					)
					(justify left bottom)
					(hide yes)
				)
			)
			(property "ki_keywords" "net tie short"
				(at 0 0 0)
				(effects
					(font
						(size 1.27 1.27)
					)
					(hide yes)
				)
			)
			(property "ki_fp_filters" "Net*Tie*"
				(at 0 0 0)
				(effects
					(font
						(size 1.27 1.27)
					)
					(hide yes)
				)
			)
			(symbol "Net-Tie_2_1_1"
				(polyline
					(pts
						(xy 1.27 0) (xy 2.54 0)
					)
					(stroke
						(width 0.254)
						(type default)
					)
					(fill
						(type background)
					)
				)
				(pin passive line
					(at 0 0 0)
					(length 1.27)
					(name "1"
						(effects
							(font
								(size 1.27 1.27)
							)
						)
					)
					(number "1"
						(effects
							(font
								(size 1.27 1.27)
							)
						)
					)
				)
				(pin passive line
					(at 3.81 0 180)
					(length 1.27)
					(name "2"
						(effects
							(font
								(size 1.27 1.27)
							)
						)
					)
					(number "2"
						(effects
							(font
								(size 1.27 1.27)
							)
						)
					)
				)
			)
		)
)
